-- pcdb file, Rev:1.0 written by Allegro Design Entry HDL 17.2-2016 S081 (4005846) 1/11/2022 on Thu Mar 30 10:12:15 2023
#ISCELL
  pure_quanta quanta_title_block_c *
  *
#ISCELL
  pure_quanta quanta_title_block_c *
  *
#ISCELL
  pure_quanta quanta_title_block_c *
  *
#ISCELL
  pure_quanta quanta_title_block_c *
  *
#ISCELL
  pure_quanta quanta_title_block_c *
  *
#ISCELL
  pure_quanta quanta_title_block_c *
  *
#ISCELL
  pure_quanta quanta_title_block_c *
  *
#ISCELL
  pure_quanta quanta_title_block_c *
  *
#ISCELL
  pure_quanta quanta_title_block_c *
  *
#ISCELL
  pure_quanta quanta_title_block_c *
  *
#ISCELL
  pure_quanta quanta_title_block_c *
  *
#ISCELL
  pure_quanta quanta_title_block_c *
  *
#ISCELL
  pure_quanta quanta_title_block_c *
  *
#ISCELL
  standard offpage *
  page13_i10
#ISCELL
  standard offpage *
  page13_i11
#ISCELL
  standard offpage *
  page13_i12
#ISCELL
  standard offpage *
  page13_i13
#ISCELL
  standard offpage *
  page13_i14
#ISCELL
  standard offpage *
  page13_i15
#CELL
  pure_quanta q_res *
  page13_i16
#ISCELL
  standard offpage *
  page13_i17
#CELL
  pure_quanta q_res *
  page13_i18
#ISCELL
  standard offpage *
  page13_i19
#ISCELL
  standard offpage *
  page13_i2
#CELL
  pure_quanta q_res *
  page13_i21
#ISCELL
  standard offpage *
  page13_i22
#ISCELL
  standard offpage *
  page13_i23
#CELL
  pure_quanta q_res *
  page13_i24
#CELL
  pure_quanta q_res *
  page13_i25
#ISCELL
  standard offpage *
  page13_i26
#ISCELL
  standard offpage *
  page13_i28
#CELL
  pure_quanta q_res *
  page13_i29
#ISCELL
  standard offpage *
  page13_i3
#ISCELL
  standard offpage *
  page13_i30
#ISCELL
  standard offpage *
  page13_i31
#ISCELL
  standard offpage *
  page13_i32
#ISCELL
  standard offpage *
  page13_i33
#ISCELL
  standard offpage *
  page13_i34
#ISCELL
  standard offpage *
  page13_i35
#ISCELL
  standard offpage *
  page13_i36
#ISCELL
  standard offpage *
  page13_i37
#ISCELL
  standard offpage *
  page13_i38
#ISCELL
  standard offpage *
  page13_i39
#ISCELL
  standard offpage *
  page13_i4
#ISCELL
  standard offpage *
  page13_i40
#ISCELL
  standard offpage *
  page13_i41
#ISCELL
  standard offpage *
  page13_i42
#ISCELL
  standard offpage *
  page13_i43
#ISCELL
  standard offpage *
  page13_i44
#ISCELL
  standard offpage *
  page13_i45
#ISCELL
  standard offpage *
  page13_i5
#ISCELL
  standard offpage *
  page13_i51
#ISCELL
  standard offpage *
  page13_i53
#ISCELL
  standard offpage *
  page13_i54
#ISCELL
  standard offpage *
  page13_i55
#ISCELL
  standard offpage *
  page13_i56
#CELL
  pure_quanta socket4677_azif0045p001c01cs *
  page13_i57
#ISCELL
  standard offpage *
  page13_i58
#ISCELL
  standard offpage *
  page13_i59
#ISCELL
  standard offpage *
  page13_i6
#ISCELL
  standard offpage *
  page13_i60
#ISCELL
  standard offpage *
  page13_i7
#ISCELL
  standard offpage *
  page13_i8
#ISCELL
  standard offpage *
  page13_i9
#ISCELL
  logical_power cad_note *
  *
#ISCELL
  pure_quanta quanta_title_block_c *
  *
#CELL
  pure_quanta socket4677_azif0045p001c01cs *
  page14_i1
#CELL
  pure_quanta q_res *
  page14_i100
#ISCELL
  standard offpage *
  page14_i106
#ISCELL
  standard offpage *
  page14_i108
#CELL
  pure_quanta q_res *
  page14_i109
#ISCELL
  standard offpage *
  page14_i11
#CELL
  pure_quanta q_res *
  page14_i110
#ISCELL
  standard offpage *
  page14_i111
#ISCELL
  standard offpage *
  page14_i112
#ISCELL
  standard offpage *
  page14_i114
#CELL
  pure_quanta q_res *
  page14_i115
#ISCELL
  standard offpage *
  page14_i116
#CELL
  pure_quanta q_res *
  page14_i117
#ISCELL
  standard offpage *
  page14_i118
#ISCELL
  standard offpage *
  page14_i12
#CELL
  pure_quanta q_res *
  page14_i122
#ISCELL
  standard offpage *
  page14_i123
#ISCELL
  standard offpage *
  page14_i124
#ISCELL
  standard offpage *
  page14_i125
#ISCELL
  standard offpage *
  page14_i126
#ISCELL
  standard offpage *
  page14_i127
#CELL
  pure_quanta q_res *
  page14_i128
#ISCELL
  standard offpage *
  page14_i129
#ISCELL
  standard offpage *
  page14_i13
#ISCELL
  standard offpage *
  page14_i14
#ISCELL
  standard offpage *
  page14_i15
#ISCELL
  standard offpage *
  page14_i16
#ISCELL
  standard offpage *
  page14_i17
#ISCELL
  standard offpage *
  page14_i18
#ISCELL
  standard offpage *
  page14_i19
#ISCELL
  standard offpage *
  page14_i20
#ISCELL
  standard offpage *
  page14_i21
#ISCELL
  standard offpage *
  page14_i22
#ISCELL
  standard offpage *
  page14_i23
#ISCELL
  standard offpage *
  page14_i24
#ISCELL
  standard offpage *
  page14_i25
#ISCELL
  standard offpage *
  page14_i26
#ISCELL
  standard offpage *
  page14_i27
#ISCELL
  standard offpage *
  page14_i28
#ISCELL
  standard offpage *
  page14_i32
#ISCELL
  standard offpage *
  page14_i33
#ISCELL
  standard offpage *
  page14_i34
#ISCELL
  standard offpage *
  page14_i39
#ISCELL
  standard offpage *
  page14_i40
#ISCELL
  standard offpage *
  page14_i41
#ISCELL
  standard offpage *
  page14_i42
#ISCELL
  standard offpage *
  page14_i43
#ISCELL
  standard offpage *
  page14_i44
#ISCELL
  standard offpage *
  page14_i46
#ISCELL
  standard offpage *
  page14_i5
#ISCELL
  standard offpage *
  page14_i51
#ISCELL
  standard offpage *
  page14_i52
#ISCELL
  standard offpage *
  page14_i53
#ISCELL
  standard offpage *
  page14_i54
#ISCELL
  standard offpage *
  page14_i55
#CELL
  pure_quanta q_res *
  page14_i59
#ISCELL
  standard offpage *
  page14_i6
#CELL
  pure_quanta q_res *
  page14_i60
#CELL
  pure_quanta q_res *
  page14_i61
#CELL
  pure_quanta q_res *
  page14_i62
#CELL
  pure_quanta q_res *
  page14_i63
#CELL
  pure_quanta q_res *
  page14_i64
#ISCELL
  standard offpage *
  page14_i65
#CELL
  pure_quanta q_res *
  page14_i66
#ISCELL
  standard offpage *
  page14_i67
#ISCELL
  standard offpage *
  page14_i7
#ISCELL
  standard offpage *
  page14_i76
#CELL
  pure_quanta q_res *
  page14_i78
#CELL
  pure_quanta q_res *
  page14_i79
#ISCELL
  standard offpage *
  page14_i8
#ISCELL
  standard offpage *
  page14_i80
#ISCELL
  standard offpage *
  page14_i9
#CELL
  pure_quanta q_res *
  page14_i90
#ISCELL
  standard offpage *
  page14_i91
#ISCELL
  standard offpage *
  page14_i92
#CELL
  pure_quanta q_res *
  page14_i93
#CELL
  pure_quanta q_res *
  page14_i94
#ISCELL
  logical_power universal_power *
  page14_i95
#ISCELL
  standard offpage *
  page14_i96
#ISCELL
  standard offpage *
  page14_i97
#CELL
  pure_quanta q_res *
  page14_i98
#ISCELL
  standard offpage *
  page14_i99
#ISCELL
  pure_quanta quanta_title_block_c *
  *
#CELL
  pure_quanta socket4677_azif0045p001c01cs *
  page15_i1
#ISCELL
  standard offpage *
  page15_i10
#ISCELL
  standard offpage *
  page15_i11
#ISCELL
  standard offpage *
  page15_i13
#ISCELL
  standard offpage *
  page15_i14
#ISCELL
  standard offpage *
  page15_i15
#ISCELL
  standard offpage *
  page15_i25
#ISCELL
  standard offpage *
  page15_i3
#ISCELL
  standard offpage *
  page15_i31
#ISCELL
  standard offpage *
  page15_i4
#ISCELL
  standard offpage *
  page15_i5
#ISCELL
  standard offpage *
  page15_i6
#ISCELL
  standard offpage *
  page15_i7
#ISCELL
  standard offpage *
  page15_i8
#ISCELL
  standard offpage *
  page15_i9
#ISCELL
  pure_quanta quanta_title_block_c *
  *
#CELL
  pure_quanta socket4677_azif0045p001c01cs *
  page16_i1
#ISCELL
  standard offpage *
  page16_i10
#ISCELL
  standard offpage *
  page16_i11
#ISCELL
  standard offpage *
  page16_i12
#ISCELL
  standard offpage *
  page16_i16
#ISCELL
  standard offpage *
  page16_i18
#CELL
  pure_quanta q_res *
  page16_i19
#ISCELL
  standard offpage *
  page16_i2
#CELL
  pure_quanta q_res *
  page16_i20
#ISCELL
  standard offpage *
  page16_i21
#ISCELL
  standard offpage *
  page16_i23
#ISCELL
  standard offpage *
  page16_i24
#CELL
  pure_quanta q_res *
  page16_i25
#CELL
  pure_quanta q_res *
  page16_i26
#ISCELL
  logical_power universal_power *
  page16_i28
#ISCELL
  standard offpage *
  page16_i29
#ISCELL
  standard offpage *
  page16_i3
#ISCELL
  standard offpage *
  page16_i30
#CELL
  pure_quanta q_res *
  page16_i31
#CELL
  pure_quanta q_res *
  page16_i32
#ISCELL
  standard offpage *
  page16_i33
#ISCELL
  standard offpage *
  page16_i34
#CELL
  pure_quanta q_res *
  page16_i35
#CELL
  pure_quanta q_res *
  page16_i36
#ISCELL
  standard offpage *
  page16_i4
#ISCELL
  standard offpage *
  page16_i5
#ISCELL
  standard offpage *
  page16_i6
#ISCELL
  standard offpage *
  page16_i7
#ISCELL
  standard offpage *
  page16_i8
#ISCELL
  standard offpage *
  page16_i9
#ISCELL
  pure_quanta quanta_title_block_c *
  *
#CELL
  pure_quanta socket4677_azif0045p001c01cs *
  page17_i1
#ISCELL
  pure_quanta quanta_title_block_c *
  *
#CELL
  pure_quanta socket4677_azif0045p001c01cs *
  page18_i1
#ISCELL
  pure_quanta quanta_title_block_c *
  *
#CELL
  pure_quanta socket4677_azif0045p001c01cs *
  page19_i1
#ISCELL
  standard offpage *
  page19_i2
#ISCELL
  standard offpage *
  page19_i3
#ISCELL
  standard offpage *
  page19_i4
#ISCELL
  standard offpage *
  page19_i5
#ISCELL
  pure_quanta quanta_title_block_c *
  *
#CELL
  pure_quanta socket4677_azif0045p001c01cs *
  page20_i1
#ISCELL
  standard tap *
  page20_i10
#ISCELL
  standard tap *
  page20_i100
#ISCELL
  standard tap *
  page20_i101
#ISCELL
  standard tap *
  page20_i102
#ISCELL
  standard tap *
  page20_i103
#ISCELL
  standard tap *
  page20_i104
#ISCELL
  standard offpage *
  page20_i105
#ISCELL
  standard tap *
  page20_i106
#ISCELL
  standard tap *
  page20_i107
#ISCELL
  standard tap *
  page20_i108
#ISCELL
  standard offpage *
  page20_i109
#ISCELL
  standard tap *
  page20_i11
#ISCELL
  standard tap *
  page20_i110
#ISCELL
  standard tap *
  page20_i111
#ISCELL
  standard tap *
  page20_i112
#ISCELL
  standard tap *
  page20_i113
#ISCELL
  standard tap *
  page20_i114
#ISCELL
  standard tap *
  page20_i115
#ISCELL
  standard tap *
  page20_i116
#ISCELL
  standard tap *
  page20_i117
#ISCELL
  standard tap *
  page20_i118
#ISCELL
  standard tap *
  page20_i119
#ISCELL
  standard tap *
  page20_i12
#ISCELL
  standard tap *
  page20_i120
#ISCELL
  standard tap *
  page20_i121
#ISCELL
  standard tap *
  page20_i122
#ISCELL
  standard tap *
  page20_i123
#ISCELL
  standard tap *
  page20_i124
#ISCELL
  standard tap *
  page20_i125
#ISCELL
  standard tap *
  page20_i126
#ISCELL
  standard tap *
  page20_i127
#ISCELL
  standard tap *
  page20_i128
#ISCELL
  standard tap *
  page20_i129
#ISCELL
  standard tap *
  page20_i13
#ISCELL
  standard tap *
  page20_i130
#ISCELL
  standard tap *
  page20_i131
#ISCELL
  standard tap *
  page20_i132
#ISCELL
  standard tap *
  page20_i133
#ISCELL
  standard offpage *
  page20_i134
#ISCELL
  standard offpage *
  page20_i135
#ISCELL
  standard offpage *
  page20_i136
#ISCELL
  standard offpage *
  page20_i137
#ISCELL
  standard tap *
  page20_i138
#ISCELL
  standard tap *
  page20_i139
#ISCELL
  standard tap *
  page20_i14
#ISCELL
  standard tap *
  page20_i140
#ISCELL
  standard tap *
  page20_i141
#ISCELL
  standard tap *
  page20_i142
#ISCELL
  standard tap *
  page20_i143
#ISCELL
  standard tap *
  page20_i144
#ISCELL
  standard tap *
  page20_i147
#ISCELL
  standard tap *
  page20_i148
#ISCELL
  standard tap *
  page20_i149
#ISCELL
  standard tap *
  page20_i15
#ISCELL
  standard tap *
  page20_i150
#ISCELL
  standard offpage *
  page20_i151
#ISCELL
  standard offpage *
  page20_i152
#ISCELL
  standard tap *
  page20_i153
#ISCELL
  standard tap *
  page20_i154
#ISCELL
  standard tap *
  page20_i155
#ISCELL
  standard tap *
  page20_i156
#ISCELL
  standard offpage *
  page20_i157
#ISCELL
  standard offpage *
  page20_i158
#ISCELL
  standard offpage *
  page20_i159
#ISCELL
  standard tap *
  page20_i16
#ISCELL
  standard offpage *
  page20_i160
#ISCELL
  standard offpage *
  page20_i161
#ISCELL
  standard tap *
  page20_i162
#ISCELL
  standard tap *
  page20_i163
#ISCELL
  standard tap *
  page20_i164
#ISCELL
  standard tap *
  page20_i165
#ISCELL
  standard tap *
  page20_i166
#ISCELL
  standard tap *
  page20_i167
#ISCELL
  standard tap *
  page20_i168
#ISCELL
  standard tap *
  page20_i169
#ISCELL
  standard tap *
  page20_i17
#ISCELL
  standard offpage *
  page20_i170
#ISCELL
  standard tap *
  page20_i171
#ISCELL
  standard tap *
  page20_i172
#ISCELL
  standard tap *
  page20_i175
#ISCELL
  standard tap *
  page20_i176
#ISCELL
  standard offpage *
  page20_i177
#ISCELL
  standard offpage *
  page20_i178
#ISCELL
  standard tap *
  page20_i18
#ISCELL
  standard tap *
  page20_i19
#ISCELL
  standard offpage *
  page20_i2
#ISCELL
  standard tap *
  page20_i20
#ISCELL
  standard tap *
  page20_i21
#ISCELL
  standard tap *
  page20_i22
#ISCELL
  standard tap *
  page20_i23
#ISCELL
  standard tap *
  page20_i24
#ISCELL
  standard tap *
  page20_i25
#ISCELL
  standard tap *
  page20_i26
#ISCELL
  standard tap *
  page20_i27
#ISCELL
  standard tap *
  page20_i28
#ISCELL
  standard tap *
  page20_i29
#ISCELL
  standard tap *
  page20_i3
#ISCELL
  standard tap *
  page20_i30
#ISCELL
  standard tap *
  page20_i31
#ISCELL
  standard tap *
  page20_i32
#ISCELL
  standard tap *
  page20_i33
#ISCELL
  standard tap *
  page20_i34
#ISCELL
  standard tap *
  page20_i35
#ISCELL
  standard tap *
  page20_i36
#ISCELL
  standard tap *
  page20_i37
#ISCELL
  standard offpage *
  page20_i38
#ISCELL
  standard tap *
  page20_i39
#ISCELL
  standard tap *
  page20_i4
#ISCELL
  standard tap *
  page20_i40
#ISCELL
  standard tap *
  page20_i41
#ISCELL
  standard tap *
  page20_i42
#ISCELL
  standard tap *
  page20_i43
#ISCELL
  standard tap *
  page20_i44
#ISCELL
  standard tap *
  page20_i45
#ISCELL
  standard tap *
  page20_i46
#ISCELL
  standard tap *
  page20_i47
#ISCELL
  standard tap *
  page20_i48
#ISCELL
  standard tap *
  page20_i49
#ISCELL
  standard tap *
  page20_i5
#ISCELL
  standard tap *
  page20_i50
#ISCELL
  standard tap *
  page20_i51
#ISCELL
  standard tap *
  page20_i52
#ISCELL
  standard tap *
  page20_i53
#ISCELL
  standard tap *
  page20_i54
#ISCELL
  standard tap *
  page20_i55
#ISCELL
  standard tap *
  page20_i56
#ISCELL
  standard tap *
  page20_i57
#ISCELL
  standard tap *
  page20_i58
#ISCELL
  standard tap *
  page20_i59
#ISCELL
  standard tap *
  page20_i6
#ISCELL
  standard tap *
  page20_i60
#ISCELL
  standard tap *
  page20_i61
#ISCELL
  standard tap *
  page20_i62
#ISCELL
  standard tap *
  page20_i63
#ISCELL
  standard tap *
  page20_i64
#ISCELL
  standard tap *
  page20_i65
#ISCELL
  standard tap *
  page20_i66
#ISCELL
  standard tap *
  page20_i67
#ISCELL
  standard tap *
  page20_i68
#ISCELL
  standard tap *
  page20_i69
#ISCELL
  standard tap *
  page20_i7
#ISCELL
  standard tap *
  page20_i70
#ISCELL
  standard tap *
  page20_i71
#ISCELL
  standard tap *
  page20_i72
#ISCELL
  standard tap *
  page20_i73
#ISCELL
  standard offpage *
  page20_i74
#ISCELL
  standard tap *
  page20_i75
#ISCELL
  standard tap *
  page20_i76
#ISCELL
  standard tap *
  page20_i8
#ISCELL
  standard tap *
  page20_i82
#ISCELL
  standard tap *
  page20_i84
#ISCELL
  standard tap *
  page20_i85
#ISCELL
  standard tap *
  page20_i86
#ISCELL
  standard tap *
  page20_i87
#ISCELL
  standard tap *
  page20_i88
#ISCELL
  standard tap *
  page20_i89
#ISCELL
  standard tap *
  page20_i9
#ISCELL
  standard tap *
  page20_i90
#ISCELL
  standard tap *
  page20_i91
#ISCELL
  standard tap *
  page20_i92
#ISCELL
  standard offpage *
  page20_i93
#ISCELL
  standard tap *
  page20_i94
#ISCELL
  standard offpage *
  page20_i95
#ISCELL
  standard tap *
  page20_i96
#ISCELL
  standard tap *
  page20_i97
#ISCELL
  standard tap *
  page20_i98
#ISCELL
  standard tap *
  page20_i99
#ISCELL
  pure_quanta quanta_title_block_c *
  *
#ISCELL
  standard tap *
  page21_i10
#ISCELL
  standard tap *
  page21_i100
#ISCELL
  standard tap *
  page21_i101
#ISCELL
  standard tap *
  page21_i102
#ISCELL
  standard tap *
  page21_i103
#ISCELL
  standard tap *
  page21_i104
#ISCELL
  standard tap *
  page21_i105
#ISCELL
  standard tap *
  page21_i106
#ISCELL
  standard tap *
  page21_i107
#ISCELL
  standard tap *
  page21_i108
#ISCELL
  standard tap *
  page21_i109
#ISCELL
  standard tap *
  page21_i11
#ISCELL
  standard tap *
  page21_i110
#ISCELL
  standard tap *
  page21_i111
#ISCELL
  standard tap *
  page21_i112
#ISCELL
  standard tap *
  page21_i113
#ISCELL
  standard tap *
  page21_i114
#ISCELL
  standard offpage *
  page21_i115
#ISCELL
  standard offpage *
  page21_i116
#ISCELL
  standard offpage *
  page21_i117
#ISCELL
  standard offpage *
  page21_i118
#ISCELL
  standard offpage *
  page21_i119
#ISCELL
  standard tap *
  page21_i12
#ISCELL
  standard offpage *
  page21_i120
#ISCELL
  standard offpage *
  page21_i121
#ISCELL
  standard offpage *
  page21_i122
#ISCELL
  standard offpage *
  page21_i123
#ISCELL
  standard offpage *
  page21_i124
#ISCELL
  standard tap *
  page21_i125
#ISCELL
  standard tap *
  page21_i126
#ISCELL
  standard tap *
  page21_i127
#ISCELL
  standard tap *
  page21_i128
#ISCELL
  standard tap *
  page21_i129
#ISCELL
  standard tap *
  page21_i13
#ISCELL
  standard tap *
  page21_i130
#ISCELL
  standard tap *
  page21_i131
#ISCELL
  standard tap *
  page21_i132
#ISCELL
  standard tap *
  page21_i133
#ISCELL
  standard tap *
  page21_i134
#ISCELL
  standard tap *
  page21_i135
#ISCELL
  standard tap *
  page21_i136
#ISCELL
  standard tap *
  page21_i137
#ISCELL
  standard tap *
  page21_i138
#ISCELL
  standard tap *
  page21_i139
#ISCELL
  standard tap *
  page21_i14
#ISCELL
  standard tap *
  page21_i140
#ISCELL
  standard tap *
  page21_i141
#ISCELL
  standard tap *
  page21_i142
#ISCELL
  standard tap *
  page21_i143
#ISCELL
  standard tap *
  page21_i144
#ISCELL
  standard tap *
  page21_i145
#ISCELL
  standard tap *
  page21_i146
#ISCELL
  standard tap *
  page21_i147
#ISCELL
  standard tap *
  page21_i148
#ISCELL
  standard tap *
  page21_i149
#ISCELL
  standard tap *
  page21_i15
#ISCELL
  standard tap *
  page21_i150
#ISCELL
  standard tap *
  page21_i151
#ISCELL
  standard tap *
  page21_i152
#ISCELL
  standard tap *
  page21_i153
#ISCELL
  standard tap *
  page21_i154
#ISCELL
  standard tap *
  page21_i155
#ISCELL
  standard tap *
  page21_i156
#ISCELL
  standard tap *
  page21_i157
#ISCELL
  standard tap *
  page21_i158
#ISCELL
  standard tap *
  page21_i159
#ISCELL
  standard tap *
  page21_i16
#ISCELL
  standard tap *
  page21_i160
#ISCELL
  standard tap *
  page21_i161
#ISCELL
  standard offpage *
  page21_i162
#ISCELL
  standard offpage *
  page21_i163
#ISCELL
  standard offpage *
  page21_i164
#ISCELL
  standard tap *
  page21_i165
#ISCELL
  standard tap *
  page21_i166
#ISCELL
  standard tap *
  page21_i167
#ISCELL
  standard offpage *
  page21_i168
#CELL
  pure_quanta socket4677_azif0045p001c01cs *
  page21_i169
#ISCELL
  standard tap *
  page21_i17
#ISCELL
  standard tap *
  page21_i18
#ISCELL
  standard tap *
  page21_i19
#ISCELL
  standard tap *
  page21_i2
#ISCELL
  standard tap *
  page21_i20
#ISCELL
  standard tap *
  page21_i21
#ISCELL
  standard tap *
  page21_i22
#ISCELL
  standard tap *
  page21_i23
#ISCELL
  standard tap *
  page21_i24
#ISCELL
  standard tap *
  page21_i25
#ISCELL
  standard tap *
  page21_i26
#ISCELL
  standard tap *
  page21_i27
#ISCELL
  standard tap *
  page21_i28
#ISCELL
  standard tap *
  page21_i29
#ISCELL
  standard offpage *
  page21_i3
#ISCELL
  standard tap *
  page21_i30
#ISCELL
  standard tap *
  page21_i31
#ISCELL
  standard tap *
  page21_i32
#ISCELL
  standard tap *
  page21_i33
#ISCELL
  standard tap *
  page21_i34
#ISCELL
  standard tap *
  page21_i35
#ISCELL
  standard tap *
  page21_i36
#ISCELL
  standard tap *
  page21_i37
#ISCELL
  standard tap *
  page21_i38
#ISCELL
  standard tap *
  page21_i39
#ISCELL
  standard offpage *
  page21_i4
#ISCELL
  standard tap *
  page21_i40
#ISCELL
  standard tap *
  page21_i41
#ISCELL
  standard tap *
  page21_i42
#ISCELL
  standard tap *
  page21_i43
#ISCELL
  standard tap *
  page21_i44
#ISCELL
  standard offpage *
  page21_i45
#ISCELL
  standard offpage *
  page21_i46
#ISCELL
  standard tap *
  page21_i47
#ISCELL
  standard tap *
  page21_i48
#ISCELL
  standard tap *
  page21_i49
#ISCELL
  standard offpage *
  page21_i5
#ISCELL
  standard tap *
  page21_i50
#ISCELL
  standard tap *
  page21_i51
#ISCELL
  standard tap *
  page21_i52
#ISCELL
  standard tap *
  page21_i53
#ISCELL
  standard tap *
  page21_i54
#ISCELL
  standard tap *
  page21_i55
#ISCELL
  standard tap *
  page21_i56
#ISCELL
  standard tap *
  page21_i57
#ISCELL
  standard tap *
  page21_i58
#ISCELL
  standard tap *
  page21_i59
#ISCELL
  standard tap *
  page21_i6
#ISCELL
  standard tap *
  page21_i60
#ISCELL
  standard tap *
  page21_i61
#ISCELL
  standard tap *
  page21_i62
#ISCELL
  standard tap *
  page21_i63
#ISCELL
  standard tap *
  page21_i64
#ISCELL
  standard tap *
  page21_i65
#ISCELL
  standard tap *
  page21_i66
#ISCELL
  standard tap *
  page21_i67
#ISCELL
  standard tap *
  page21_i68
#ISCELL
  standard tap *
  page21_i69
#ISCELL
  standard tap *
  page21_i7
#ISCELL
  standard tap *
  page21_i70
#ISCELL
  standard tap *
  page21_i71
#ISCELL
  standard tap *
  page21_i72
#ISCELL
  standard tap *
  page21_i73
#ISCELL
  standard tap *
  page21_i74
#ISCELL
  standard tap *
  page21_i75
#ISCELL
  standard tap *
  page21_i76
#ISCELL
  standard tap *
  page21_i77
#ISCELL
  standard tap *
  page21_i78
#ISCELL
  standard tap *
  page21_i79
#ISCELL
  standard tap *
  page21_i8
#ISCELL
  standard tap *
  page21_i80
#ISCELL
  standard tap *
  page21_i81
#ISCELL
  standard tap *
  page21_i82
#ISCELL
  standard tap *
  page21_i83
#ISCELL
  standard tap *
  page21_i84
#ISCELL
  standard tap *
  page21_i85
#ISCELL
  standard tap *
  page21_i86
#ISCELL
  standard tap *
  page21_i87
#ISCELL
  standard offpage *
  page21_i88
#ISCELL
  standard tap *
  page21_i89
#ISCELL
  standard tap *
  page21_i9
#ISCELL
  standard tap *
  page21_i90
#ISCELL
  standard tap *
  page21_i91
#ISCELL
  standard offpage *
  page21_i92
#ISCELL
  standard tap *
  page21_i93
#ISCELL
  standard tap *
  page21_i94
#ISCELL
  standard tap *
  page21_i95
#ISCELL
  standard tap *
  page21_i96
#ISCELL
  standard tap *
  page21_i97
#ISCELL
  standard tap *
  page21_i98
#ISCELL
  standard tap *
  page21_i99
#ISCELL
  pure_quanta quanta_title_block_c *
  *
#ISCELL
  standard offpage *
  page22_i1
#ISCELL
  standard tap *
  page22_i10
#ISCELL
  standard tap *
  page22_i100
#ISCELL
  standard tap *
  page22_i101
#ISCELL
  standard tap *
  page22_i102
#ISCELL
  standard tap *
  page22_i103
#ISCELL
  standard tap *
  page22_i104
#ISCELL
  standard tap *
  page22_i105
#ISCELL
  standard tap *
  page22_i106
#ISCELL
  standard tap *
  page22_i107
#ISCELL
  standard tap *
  page22_i108
#ISCELL
  standard tap *
  page22_i109
#ISCELL
  standard tap *
  page22_i11
#ISCELL
  standard tap *
  page22_i110
#ISCELL
  standard tap *
  page22_i111
#ISCELL
  standard tap *
  page22_i112
#ISCELL
  standard tap *
  page22_i113
#ISCELL
  standard tap *
  page22_i114
#ISCELL
  standard tap *
  page22_i115
#ISCELL
  standard tap *
  page22_i116
#ISCELL
  standard tap *
  page22_i117
#ISCELL
  standard tap *
  page22_i118
#ISCELL
  standard tap *
  page22_i119
#ISCELL
  standard tap *
  page22_i12
#ISCELL
  standard tap *
  page22_i120
#ISCELL
  standard tap *
  page22_i121
#ISCELL
  standard tap *
  page22_i122
#ISCELL
  standard tap *
  page22_i123
#ISCELL
  standard tap *
  page22_i124
#ISCELL
  standard tap *
  page22_i125
#ISCELL
  standard tap *
  page22_i126
#ISCELL
  standard tap *
  page22_i127
#ISCELL
  standard tap *
  page22_i128
#ISCELL
  standard tap *
  page22_i129
#ISCELL
  standard tap *
  page22_i13
#ISCELL
  standard tap *
  page22_i130
#ISCELL
  standard tap *
  page22_i131
#ISCELL
  standard tap *
  page22_i132
#ISCELL
  standard tap *
  page22_i133
#ISCELL
  standard tap *
  page22_i134
#ISCELL
  standard tap *
  page22_i135
#ISCELL
  standard tap *
  page22_i136
#ISCELL
  standard tap *
  page22_i137
#ISCELL
  standard tap *
  page22_i138
#ISCELL
  standard tap *
  page22_i139
#ISCELL
  standard tap *
  page22_i14
#ISCELL
  standard tap *
  page22_i140
#ISCELL
  standard tap *
  page22_i141
#ISCELL
  standard tap *
  page22_i142
#ISCELL
  standard tap *
  page22_i143
#ISCELL
  standard tap *
  page22_i144
#ISCELL
  standard tap *
  page22_i145
#ISCELL
  standard tap *
  page22_i146
#ISCELL
  standard tap *
  page22_i147
#ISCELL
  standard tap *
  page22_i148
#ISCELL
  standard tap *
  page22_i149
#ISCELL
  standard tap *
  page22_i15
#ISCELL
  standard tap *
  page22_i150
#ISCELL
  standard tap *
  page22_i151
#ISCELL
  standard tap *
  page22_i152
#ISCELL
  standard tap *
  page22_i153
#ISCELL
  standard tap *
  page22_i154
#ISCELL
  standard tap *
  page22_i155
#ISCELL
  standard tap *
  page22_i156
#ISCELL
  standard tap *
  page22_i157
#ISCELL
  standard offpage *
  page22_i158
#ISCELL
  standard offpage *
  page22_i159
#ISCELL
  standard tap *
  page22_i16
#ISCELL
  standard offpage *
  page22_i160
#ISCELL
  standard offpage *
  page22_i161
#ISCELL
  standard offpage *
  page22_i162
#ISCELL
  standard offpage *
  page22_i163
#ISCELL
  standard offpage *
  page22_i164
#ISCELL
  standard offpage *
  page22_i165
#ISCELL
  standard offpage *
  page22_i166
#ISCELL
  standard offpage *
  page22_i167
#ISCELL
  standard offpage *
  page22_i168
#CELL
  pure_quanta socket4677_azif0045p001c01cs *
  page22_i169
#ISCELL
  standard tap *
  page22_i17
#ISCELL
  standard tap *
  page22_i18
#ISCELL
  standard tap *
  page22_i19
#ISCELL
  standard offpage *
  page22_i2
#ISCELL
  standard tap *
  page22_i20
#ISCELL
  standard tap *
  page22_i21
#ISCELL
  standard tap *
  page22_i22
#ISCELL
  standard tap *
  page22_i23
#ISCELL
  standard tap *
  page22_i24
#ISCELL
  standard tap *
  page22_i25
#ISCELL
  standard tap *
  page22_i26
#ISCELL
  standard tap *
  page22_i27
#ISCELL
  standard tap *
  page22_i28
#ISCELL
  standard tap *
  page22_i29
#ISCELL
  standard tap *
  page22_i3
#ISCELL
  standard tap *
  page22_i30
#ISCELL
  standard tap *
  page22_i31
#ISCELL
  standard tap *
  page22_i32
#ISCELL
  standard tap *
  page22_i33
#ISCELL
  standard tap *
  page22_i34
#ISCELL
  standard tap *
  page22_i35
#ISCELL
  standard tap *
  page22_i36
#ISCELL
  standard tap *
  page22_i37
#ISCELL
  standard tap *
  page22_i38
#ISCELL
  standard tap *
  page22_i39
#ISCELL
  standard tap *
  page22_i4
#ISCELL
  standard tap *
  page22_i40
#ISCELL
  standard tap *
  page22_i41
#ISCELL
  standard tap *
  page22_i42
#ISCELL
  standard tap *
  page22_i43
#ISCELL
  standard tap *
  page22_i44
#ISCELL
  standard tap *
  page22_i45
#ISCELL
  standard tap *
  page22_i46
#ISCELL
  standard tap *
  page22_i47
#ISCELL
  standard tap *
  page22_i48
#ISCELL
  standard tap *
  page22_i49
#ISCELL
  standard tap *
  page22_i5
#ISCELL
  standard offpage *
  page22_i50
#ISCELL
  standard offpage *
  page22_i51
#ISCELL
  standard tap *
  page22_i52
#ISCELL
  standard tap *
  page22_i53
#ISCELL
  standard tap *
  page22_i54
#ISCELL
  standard tap *
  page22_i55
#ISCELL
  standard tap *
  page22_i56
#ISCELL
  standard tap *
  page22_i57
#ISCELL
  standard tap *
  page22_i58
#ISCELL
  standard tap *
  page22_i59
#ISCELL
  standard tap *
  page22_i6
#ISCELL
  standard tap *
  page22_i60
#ISCELL
  standard tap *
  page22_i61
#ISCELL
  standard tap *
  page22_i62
#ISCELL
  standard tap *
  page22_i63
#ISCELL
  standard tap *
  page22_i64
#ISCELL
  standard tap *
  page22_i65
#ISCELL
  standard tap *
  page22_i66
#ISCELL
  standard tap *
  page22_i67
#ISCELL
  standard tap *
  page22_i68
#ISCELL
  standard tap *
  page22_i69
#ISCELL
  standard offpage *
  page22_i7
#ISCELL
  standard tap *
  page22_i70
#ISCELL
  standard tap *
  page22_i71
#ISCELL
  standard tap *
  page22_i72
#ISCELL
  standard tap *
  page22_i73
#ISCELL
  standard tap *
  page22_i74
#ISCELL
  standard tap *
  page22_i75
#ISCELL
  standard tap *
  page22_i76
#ISCELL
  standard tap *
  page22_i77
#ISCELL
  standard tap *
  page22_i78
#ISCELL
  standard tap *
  page22_i79
#ISCELL
  standard offpage *
  page22_i8
#ISCELL
  standard tap *
  page22_i80
#ISCELL
  standard tap *
  page22_i81
#ISCELL
  standard tap *
  page22_i82
#ISCELL
  standard tap *
  page22_i83
#ISCELL
  standard tap *
  page22_i84
#ISCELL
  standard tap *
  page22_i85
#ISCELL
  standard tap *
  page22_i86
#ISCELL
  standard tap *
  page22_i87
#ISCELL
  standard tap *
  page22_i88
#ISCELL
  standard tap *
  page22_i89
#ISCELL
  standard tap *
  page22_i9
#ISCELL
  standard tap *
  page22_i90
#ISCELL
  standard offpage *
  page22_i92
#ISCELL
  standard offpage *
  page22_i93
#ISCELL
  standard offpage *
  page22_i94
#ISCELL
  standard offpage *
  page22_i95
#ISCELL
  standard tap *
  page22_i96
#ISCELL
  standard tap *
  page22_i97
#ISCELL
  standard tap *
  page22_i98
#ISCELL
  standard tap *
  page22_i99
#ISCELL
  pure_quanta quanta_title_block_c *
  *
#ISCELL
  standard offpage *
  page23_i1
#ISCELL
  standard tap *
  page23_i10
#ISCELL
  standard tap *
  page23_i100
#ISCELL
  standard tap *
  page23_i101
#ISCELL
  standard tap *
  page23_i102
#ISCELL
  standard tap *
  page23_i103
#ISCELL
  standard tap *
  page23_i104
#ISCELL
  standard tap *
  page23_i105
#ISCELL
  standard tap *
  page23_i106
#ISCELL
  standard tap *
  page23_i107
#ISCELL
  standard tap *
  page23_i108
#ISCELL
  standard tap *
  page23_i109
#ISCELL
  standard tap *
  page23_i11
#ISCELL
  standard tap *
  page23_i110
#ISCELL
  standard tap *
  page23_i111
#ISCELL
  standard tap *
  page23_i112
#ISCELL
  standard tap *
  page23_i113
#ISCELL
  standard tap *
  page23_i114
#ISCELL
  standard tap *
  page23_i115
#ISCELL
  standard tap *
  page23_i116
#ISCELL
  standard tap *
  page23_i117
#ISCELL
  standard tap *
  page23_i118
#ISCELL
  standard tap *
  page23_i119
#ISCELL
  standard tap *
  page23_i12
#ISCELL
  standard tap *
  page23_i120
#ISCELL
  standard tap *
  page23_i121
#ISCELL
  standard tap *
  page23_i122
#ISCELL
  standard tap *
  page23_i123
#ISCELL
  standard tap *
  page23_i124
#ISCELL
  standard tap *
  page23_i125
#ISCELL
  standard tap *
  page23_i126
#ISCELL
  standard tap *
  page23_i127
#ISCELL
  standard tap *
  page23_i128
#ISCELL
  standard tap *
  page23_i129
#ISCELL
  standard tap *
  page23_i13
#ISCELL
  standard tap *
  page23_i130
#ISCELL
  standard tap *
  page23_i131
#ISCELL
  standard tap *
  page23_i132
#ISCELL
  standard tap *
  page23_i133
#ISCELL
  standard tap *
  page23_i134
#ISCELL
  standard tap *
  page23_i135
#ISCELL
  standard tap *
  page23_i136
#ISCELL
  standard tap *
  page23_i137
#ISCELL
  standard tap *
  page23_i138
#ISCELL
  standard tap *
  page23_i139
#ISCELL
  standard offpage *
  page23_i14
#ISCELL
  standard tap *
  page23_i140
#ISCELL
  standard tap *
  page23_i141
#ISCELL
  standard tap *
  page23_i142
#ISCELL
  standard tap *
  page23_i143
#ISCELL
  standard tap *
  page23_i144
#ISCELL
  standard tap *
  page23_i145
#ISCELL
  standard tap *
  page23_i146
#ISCELL
  standard tap *
  page23_i147
#ISCELL
  standard tap *
  page23_i148
#ISCELL
  standard tap *
  page23_i149
#ISCELL
  standard offpage *
  page23_i15
#ISCELL
  standard tap *
  page23_i150
#ISCELL
  standard tap *
  page23_i151
#ISCELL
  standard tap *
  page23_i152
#ISCELL
  standard tap *
  page23_i153
#ISCELL
  standard tap *
  page23_i154
#ISCELL
  standard tap *
  page23_i155
#ISCELL
  standard tap *
  page23_i156
#ISCELL
  standard tap *
  page23_i157
#ISCELL
  standard tap *
  page23_i158
#ISCELL
  standard offpage *
  page23_i159
#ISCELL
  standard offpage *
  page23_i16
#ISCELL
  standard offpage *
  page23_i160
#ISCELL
  standard offpage *
  page23_i161
#ISCELL
  standard offpage *
  page23_i162
#ISCELL
  standard offpage *
  page23_i163
#ISCELL
  standard offpage *
  page23_i164
#ISCELL
  standard offpage *
  page23_i165
#ISCELL
  standard offpage *
  page23_i166
#ISCELL
  standard offpage *
  page23_i167
#ISCELL
  standard offpage *
  page23_i168
#CELL
  pure_quanta socket4677_azif0045p001c01cs *
  page23_i169
#ISCELL
  standard tap *
  page23_i17
#ISCELL
  standard tap *
  page23_i18
#ISCELL
  standard tap *
  page23_i19
#ISCELL
  standard offpage *
  page23_i2
#ISCELL
  standard tap *
  page23_i20
#ISCELL
  standard tap *
  page23_i21
#ISCELL
  standard tap *
  page23_i22
#ISCELL
  standard tap *
  page23_i23
#ISCELL
  standard tap *
  page23_i24
#ISCELL
  standard tap *
  page23_i25
#ISCELL
  standard tap *
  page23_i26
#ISCELL
  standard tap *
  page23_i27
#ISCELL
  standard tap *
  page23_i28
#ISCELL
  standard tap *
  page23_i29
#ISCELL
  standard tap *
  page23_i3
#ISCELL
  standard tap *
  page23_i30
#ISCELL
  standard tap *
  page23_i31
#ISCELL
  standard tap *
  page23_i32
#ISCELL
  standard tap *
  page23_i33
#ISCELL
  standard tap *
  page23_i34
#ISCELL
  standard tap *
  page23_i35
#ISCELL
  standard tap *
  page23_i36
#ISCELL
  standard tap *
  page23_i37
#ISCELL
  standard tap *
  page23_i38
#ISCELL
  standard tap *
  page23_i39
#ISCELL
  standard tap *
  page23_i4
#ISCELL
  standard tap *
  page23_i40
#ISCELL
  standard tap *
  page23_i41
#ISCELL
  standard tap *
  page23_i42
#ISCELL
  standard tap *
  page23_i43
#ISCELL
  standard tap *
  page23_i44
#ISCELL
  standard tap *
  page23_i45
#ISCELL
  standard tap *
  page23_i46
#ISCELL
  standard tap *
  page23_i47
#ISCELL
  standard tap *
  page23_i48
#ISCELL
  standard tap *
  page23_i49
#ISCELL
  standard tap *
  page23_i5
#ISCELL
  standard tap *
  page23_i50
#ISCELL
  standard tap *
  page23_i51
#ISCELL
  standard tap *
  page23_i52
#ISCELL
  standard tap *
  page23_i53
#ISCELL
  standard tap *
  page23_i54
#ISCELL
  standard tap *
  page23_i55
#ISCELL
  standard tap *
  page23_i56
#ISCELL
  standard offpage *
  page23_i57
#ISCELL
  standard tap *
  page23_i58
#ISCELL
  standard tap *
  page23_i59
#ISCELL
  standard tap *
  page23_i6
#ISCELL
  standard tap *
  page23_i60
#ISCELL
  standard tap *
  page23_i61
#ISCELL
  standard tap *
  page23_i62
#ISCELL
  standard tap *
  page23_i63
#ISCELL
  standard tap *
  page23_i64
#ISCELL
  standard tap *
  page23_i65
#ISCELL
  standard tap *
  page23_i66
#ISCELL
  standard tap *
  page23_i67
#ISCELL
  standard tap *
  page23_i68
#ISCELL
  standard tap *
  page23_i69
#ISCELL
  standard tap *
  page23_i7
#ISCELL
  standard tap *
  page23_i70
#ISCELL
  standard tap *
  page23_i71
#ISCELL
  standard tap *
  page23_i72
#ISCELL
  standard tap *
  page23_i73
#ISCELL
  standard tap *
  page23_i74
#ISCELL
  standard tap *
  page23_i75
#ISCELL
  standard tap *
  page23_i76
#ISCELL
  standard tap *
  page23_i77
#ISCELL
  standard tap *
  page23_i78
#ISCELL
  standard tap *
  page23_i79
#ISCELL
  standard tap *
  page23_i8
#ISCELL
  standard tap *
  page23_i80
#ISCELL
  standard tap *
  page23_i81
#ISCELL
  standard tap *
  page23_i82
#ISCELL
  standard tap *
  page23_i83
#ISCELL
  standard tap *
  page23_i84
#ISCELL
  standard tap *
  page23_i85
#ISCELL
  standard tap *
  page23_i86
#ISCELL
  standard tap *
  page23_i87
#ISCELL
  standard tap *
  page23_i88
#ISCELL
  standard tap *
  page23_i89
#ISCELL
  standard tap *
  page23_i9
#ISCELL
  standard tap *
  page23_i90
#ISCELL
  standard tap *
  page23_i92
#ISCELL
  standard tap *
  page23_i93
#ISCELL
  standard tap *
  page23_i94
#ISCELL
  standard offpage *
  page23_i95
#ISCELL
  standard offpage *
  page23_i96
#ISCELL
  standard offpage *
  page23_i97
#ISCELL
  standard offpage *
  page23_i98
#ISCELL
  standard offpage *
  page23_i99
#ISCELL
  pure_quanta quanta_title_block_c *
  *
#ISCELL
  standard offpage *
  page24_i1
#ISCELL
  standard offpage *
  page24_i10
#ISCELL
  standard tap *
  page24_i100
#ISCELL
  standard tap *
  page24_i101
#ISCELL
  standard tap *
  page24_i102
#ISCELL
  standard tap *
  page24_i103
#ISCELL
  standard tap *
  page24_i104
#ISCELL
  standard tap *
  page24_i105
#ISCELL
  standard tap *
  page24_i106
#ISCELL
  standard tap *
  page24_i107
#ISCELL
  standard tap *
  page24_i108
#ISCELL
  standard tap *
  page24_i109
#ISCELL
  standard tap *
  page24_i11
#ISCELL
  standard tap *
  page24_i110
#ISCELL
  standard tap *
  page24_i111
#ISCELL
  standard tap *
  page24_i112
#ISCELL
  standard tap *
  page24_i113
#ISCELL
  standard tap *
  page24_i114
#ISCELL
  standard tap *
  page24_i115
#ISCELL
  standard tap *
  page24_i116
#ISCELL
  standard tap *
  page24_i117
#ISCELL
  standard tap *
  page24_i118
#ISCELL
  standard tap *
  page24_i119
#ISCELL
  standard tap *
  page24_i12
#ISCELL
  standard tap *
  page24_i120
#ISCELL
  standard tap *
  page24_i121
#ISCELL
  standard tap *
  page24_i122
#ISCELL
  standard tap *
  page24_i123
#ISCELL
  standard tap *
  page24_i124
#ISCELL
  standard tap *
  page24_i125
#ISCELL
  standard tap *
  page24_i126
#ISCELL
  standard tap *
  page24_i127
#ISCELL
  standard tap *
  page24_i128
#ISCELL
  standard tap *
  page24_i129
#ISCELL
  standard tap *
  page24_i13
#ISCELL
  standard tap *
  page24_i130
#ISCELL
  standard tap *
  page24_i131
#ISCELL
  standard tap *
  page24_i132
#ISCELL
  standard tap *
  page24_i133
#ISCELL
  standard tap *
  page24_i134
#ISCELL
  standard tap *
  page24_i135
#ISCELL
  standard tap *
  page24_i136
#ISCELL
  standard tap *
  page24_i137
#ISCELL
  standard tap *
  page24_i138
#ISCELL
  standard tap *
  page24_i139
#ISCELL
  standard tap *
  page24_i14
#ISCELL
  standard tap *
  page24_i140
#ISCELL
  standard tap *
  page24_i141
#ISCELL
  standard tap *
  page24_i142
#ISCELL
  standard tap *
  page24_i143
#ISCELL
  standard tap *
  page24_i144
#ISCELL
  standard tap *
  page24_i145
#ISCELL
  standard tap *
  page24_i146
#ISCELL
  standard tap *
  page24_i147
#ISCELL
  standard tap *
  page24_i148
#ISCELL
  standard tap *
  page24_i149
#ISCELL
  standard tap *
  page24_i15
#ISCELL
  standard tap *
  page24_i150
#ISCELL
  standard tap *
  page24_i151
#ISCELL
  standard tap *
  page24_i152
#ISCELL
  standard tap *
  page24_i153
#ISCELL
  standard tap *
  page24_i154
#ISCELL
  standard tap *
  page24_i155
#ISCELL
  standard tap *
  page24_i156
#ISCELL
  standard tap *
  page24_i157
#ISCELL
  standard tap *
  page24_i158
#ISCELL
  standard offpage *
  page24_i159
#ISCELL
  standard tap *
  page24_i16
#ISCELL
  standard offpage *
  page24_i160
#ISCELL
  standard offpage *
  page24_i161
#ISCELL
  standard offpage *
  page24_i162
#ISCELL
  standard offpage *
  page24_i163
#ISCELL
  standard offpage *
  page24_i164
#ISCELL
  standard offpage *
  page24_i165
#ISCELL
  standard offpage *
  page24_i166
#ISCELL
  standard offpage *
  page24_i167
#ISCELL
  standard offpage *
  page24_i168
#CELL
  pure_quanta socket4677_azif0045p001c01cs *
  page24_i169
#ISCELL
  standard tap *
  page24_i17
#ISCELL
  standard tap *
  page24_i18
#ISCELL
  standard tap *
  page24_i19
#ISCELL
  standard offpage *
  page24_i2
#ISCELL
  standard tap *
  page24_i20
#ISCELL
  standard tap *
  page24_i21
#ISCELL
  standard tap *
  page24_i22
#ISCELL
  standard tap *
  page24_i23
#ISCELL
  standard tap *
  page24_i24
#ISCELL
  standard tap *
  page24_i25
#ISCELL
  standard tap *
  page24_i26
#ISCELL
  standard tap *
  page24_i27
#ISCELL
  standard tap *
  page24_i28
#ISCELL
  standard tap *
  page24_i29
#ISCELL
  standard tap *
  page24_i3
#ISCELL
  standard tap *
  page24_i30
#ISCELL
  standard tap *
  page24_i31
#ISCELL
  standard tap *
  page24_i32
#ISCELL
  standard tap *
  page24_i33
#ISCELL
  standard tap *
  page24_i34
#ISCELL
  standard tap *
  page24_i35
#ISCELL
  standard tap *
  page24_i36
#ISCELL
  standard tap *
  page24_i37
#ISCELL
  standard tap *
  page24_i38
#ISCELL
  standard tap *
  page24_i39
#ISCELL
  standard tap *
  page24_i4
#ISCELL
  standard tap *
  page24_i40
#ISCELL
  standard tap *
  page24_i41
#ISCELL
  standard tap *
  page24_i42
#ISCELL
  standard tap *
  page24_i43
#ISCELL
  standard tap *
  page24_i44
#ISCELL
  standard tap *
  page24_i45
#ISCELL
  standard tap *
  page24_i46
#ISCELL
  standard tap *
  page24_i47
#ISCELL
  standard tap *
  page24_i48
#ISCELL
  standard tap *
  page24_i49
#ISCELL
  standard tap *
  page24_i5
#ISCELL
  standard tap *
  page24_i50
#ISCELL
  standard offpage *
  page24_i51
#ISCELL
  standard offpage *
  page24_i52
#ISCELL
  standard tap *
  page24_i53
#ISCELL
  standard tap *
  page24_i54
#ISCELL
  standard tap *
  page24_i55
#ISCELL
  standard tap *
  page24_i56
#ISCELL
  standard tap *
  page24_i57
#ISCELL
  standard tap *
  page24_i58
#ISCELL
  standard tap *
  page24_i59
#ISCELL
  standard tap *
  page24_i6
#ISCELL
  standard tap *
  page24_i60
#ISCELL
  standard tap *
  page24_i61
#ISCELL
  standard tap *
  page24_i62
#ISCELL
  standard tap *
  page24_i63
#ISCELL
  standard tap *
  page24_i64
#ISCELL
  standard tap *
  page24_i65
#ISCELL
  standard tap *
  page24_i66
#ISCELL
  standard tap *
  page24_i67
#ISCELL
  standard tap *
  page24_i68
#ISCELL
  standard tap *
  page24_i69
#ISCELL
  standard tap *
  page24_i7
#ISCELL
  standard tap *
  page24_i70
#ISCELL
  standard tap *
  page24_i71
#ISCELL
  standard tap *
  page24_i72
#ISCELL
  standard tap *
  page24_i73
#ISCELL
  standard tap *
  page24_i74
#ISCELL
  standard tap *
  page24_i75
#ISCELL
  standard tap *
  page24_i76
#ISCELL
  standard tap *
  page24_i77
#ISCELL
  standard tap *
  page24_i78
#ISCELL
  standard tap *
  page24_i79
#ISCELL
  standard tap *
  page24_i8
#ISCELL
  standard tap *
  page24_i80
#ISCELL
  standard tap *
  page24_i81
#ISCELL
  standard tap *
  page24_i82
#ISCELL
  standard tap *
  page24_i83
#ISCELL
  standard tap *
  page24_i84
#ISCELL
  standard tap *
  page24_i85
#ISCELL
  standard tap *
  page24_i86
#ISCELL
  standard tap *
  page24_i87
#ISCELL
  standard tap *
  page24_i88
#ISCELL
  standard tap *
  page24_i89
#ISCELL
  standard offpage *
  page24_i9
#ISCELL
  standard tap *
  page24_i90
#ISCELL
  standard offpage *
  page24_i92
#ISCELL
  standard offpage *
  page24_i93
#ISCELL
  standard offpage *
  page24_i94
#ISCELL
  standard offpage *
  page24_i95
#ISCELL
  standard offpage *
  page24_i96
#ISCELL
  standard tap *
  page24_i97
#ISCELL
  standard tap *
  page24_i98
#ISCELL
  standard tap *
  page24_i99
#ISCELL
  pure_quanta quanta_title_block_c *
  *
#ISCELL
  standard offpage *
  page25_i1
#ISCELL
  standard tap *
  page25_i10
#ISCELL
  standard tap *
  page25_i100
#ISCELL
  standard tap *
  page25_i101
#ISCELL
  standard tap *
  page25_i102
#ISCELL
  standard tap *
  page25_i103
#ISCELL
  standard tap *
  page25_i104
#ISCELL
  standard tap *
  page25_i105
#ISCELL
  standard tap *
  page25_i106
#ISCELL
  standard tap *
  page25_i107
#ISCELL
  standard tap *
  page25_i108
#ISCELL
  standard tap *
  page25_i109
#ISCELL
  standard tap *
  page25_i11
#ISCELL
  standard tap *
  page25_i110
#ISCELL
  standard tap *
  page25_i111
#ISCELL
  standard tap *
  page25_i112
#ISCELL
  standard tap *
  page25_i113
#ISCELL
  standard tap *
  page25_i114
#ISCELL
  standard tap *
  page25_i115
#ISCELL
  standard tap *
  page25_i116
#ISCELL
  standard tap *
  page25_i117
#ISCELL
  standard tap *
  page25_i118
#ISCELL
  standard tap *
  page25_i119
#ISCELL
  standard tap *
  page25_i12
#ISCELL
  standard tap *
  page25_i120
#ISCELL
  standard offpage *
  page25_i121
#ISCELL
  standard offpage *
  page25_i122
#ISCELL
  standard offpage *
  page25_i123
#ISCELL
  standard offpage *
  page25_i124
#ISCELL
  standard offpage *
  page25_i125
#ISCELL
  standard offpage *
  page25_i126
#ISCELL
  standard offpage *
  page25_i127
#ISCELL
  standard offpage *
  page25_i128
#ISCELL
  standard tap *
  page25_i129
#ISCELL
  standard tap *
  page25_i13
#ISCELL
  standard tap *
  page25_i130
#ISCELL
  standard tap *
  page25_i131
#ISCELL
  standard tap *
  page25_i132
#ISCELL
  standard tap *
  page25_i133
#ISCELL
  standard tap *
  page25_i134
#ISCELL
  standard tap *
  page25_i135
#ISCELL
  standard tap *
  page25_i136
#ISCELL
  standard tap *
  page25_i137
#ISCELL
  standard tap *
  page25_i138
#ISCELL
  standard tap *
  page25_i139
#ISCELL
  standard tap *
  page25_i14
#ISCELL
  standard tap *
  page25_i140
#ISCELL
  standard tap *
  page25_i141
#ISCELL
  standard tap *
  page25_i142
#ISCELL
  standard tap *
  page25_i143
#ISCELL
  standard tap *
  page25_i144
#ISCELL
  standard tap *
  page25_i145
#ISCELL
  standard tap *
  page25_i146
#ISCELL
  standard tap *
  page25_i147
#ISCELL
  standard tap *
  page25_i148
#ISCELL
  standard tap *
  page25_i149
#ISCELL
  standard tap *
  page25_i15
#ISCELL
  standard tap *
  page25_i150
#ISCELL
  standard tap *
  page25_i151
#ISCELL
  standard tap *
  page25_i152
#ISCELL
  standard tap *
  page25_i153
#ISCELL
  standard tap *
  page25_i154
#ISCELL
  standard tap *
  page25_i155
#ISCELL
  standard tap *
  page25_i156
#ISCELL
  standard tap *
  page25_i157
#ISCELL
  standard tap *
  page25_i158
#ISCELL
  standard tap *
  page25_i159
#ISCELL
  standard tap *
  page25_i16
#ISCELL
  standard tap *
  page25_i160
#ISCELL
  standard tap *
  page25_i161
#ISCELL
  standard tap *
  page25_i162
#ISCELL
  standard tap *
  page25_i163
#ISCELL
  standard tap *
  page25_i164
#ISCELL
  standard offpage *
  page25_i165
#ISCELL
  standard offpage *
  page25_i166
#ISCELL
  standard offpage *
  page25_i167
#ISCELL
  standard offpage *
  page25_i168
#CELL
  pure_quanta socket4677_azif0045p001c01cs *
  page25_i169
#ISCELL
  standard tap *
  page25_i17
#ISCELL
  standard tap *
  page25_i18
#ISCELL
  standard tap *
  page25_i19
#ISCELL
  standard offpage *
  page25_i2
#ISCELL
  standard tap *
  page25_i20
#ISCELL
  standard tap *
  page25_i21
#ISCELL
  standard tap *
  page25_i22
#ISCELL
  standard tap *
  page25_i23
#ISCELL
  standard tap *
  page25_i24
#ISCELL
  standard tap *
  page25_i25
#ISCELL
  standard tap *
  page25_i26
#ISCELL
  standard tap *
  page25_i27
#ISCELL
  standard tap *
  page25_i28
#ISCELL
  standard tap *
  page25_i29
#ISCELL
  standard tap *
  page25_i3
#ISCELL
  standard tap *
  page25_i30
#ISCELL
  standard tap *
  page25_i31
#ISCELL
  standard tap *
  page25_i32
#ISCELL
  standard tap *
  page25_i33
#ISCELL
  standard tap *
  page25_i34
#ISCELL
  standard tap *
  page25_i35
#ISCELL
  standard tap *
  page25_i36
#ISCELL
  standard tap *
  page25_i37
#ISCELL
  standard tap *
  page25_i38
#ISCELL
  standard tap *
  page25_i39
#ISCELL
  standard tap *
  page25_i4
#ISCELL
  standard tap *
  page25_i40
#ISCELL
  standard tap *
  page25_i41
#ISCELL
  standard tap *
  page25_i42
#ISCELL
  standard tap *
  page25_i43
#ISCELL
  standard tap *
  page25_i44
#ISCELL
  standard tap *
  page25_i45
#ISCELL
  standard tap *
  page25_i46
#ISCELL
  standard tap *
  page25_i47
#ISCELL
  standard tap *
  page25_i48
#ISCELL
  standard tap *
  page25_i49
#ISCELL
  standard tap *
  page25_i5
#ISCELL
  standard offpage *
  page25_i50
#ISCELL
  standard offpage *
  page25_i51
#ISCELL
  standard tap *
  page25_i52
#ISCELL
  standard tap *
  page25_i53
#ISCELL
  standard tap *
  page25_i54
#ISCELL
  standard tap *
  page25_i55
#ISCELL
  standard tap *
  page25_i56
#ISCELL
  standard tap *
  page25_i57
#ISCELL
  standard tap *
  page25_i58
#ISCELL
  standard tap *
  page25_i59
#ISCELL
  standard tap *
  page25_i6
#ISCELL
  standard tap *
  page25_i60
#ISCELL
  standard tap *
  page25_i61
#ISCELL
  standard tap *
  page25_i62
#ISCELL
  standard tap *
  page25_i63
#ISCELL
  standard tap *
  page25_i64
#ISCELL
  standard tap *
  page25_i65
#ISCELL
  standard tap *
  page25_i66
#ISCELL
  standard tap *
  page25_i67
#ISCELL
  standard tap *
  page25_i68
#ISCELL
  standard tap *
  page25_i69
#ISCELL
  standard tap *
  page25_i70
#ISCELL
  standard tap *
  page25_i71
#ISCELL
  standard tap *
  page25_i72
#ISCELL
  standard tap *
  page25_i73
#ISCELL
  standard tap *
  page25_i74
#ISCELL
  standard tap *
  page25_i75
#ISCELL
  standard tap *
  page25_i76
#ISCELL
  standard tap *
  page25_i77
#ISCELL
  standard tap *
  page25_i78
#ISCELL
  standard tap *
  page25_i79
#ISCELL
  standard offpage *
  page25_i8
#ISCELL
  standard tap *
  page25_i80
#ISCELL
  standard tap *
  page25_i81
#ISCELL
  standard tap *
  page25_i82
#ISCELL
  standard tap *
  page25_i83
#ISCELL
  standard tap *
  page25_i84
#ISCELL
  standard tap *
  page25_i85
#ISCELL
  standard tap *
  page25_i86
#ISCELL
  standard tap *
  page25_i87
#ISCELL
  standard tap *
  page25_i88
#ISCELL
  standard tap *
  page25_i89
#ISCELL
  standard offpage *
  page25_i9
#ISCELL
  standard tap *
  page25_i90
#ISCELL
  standard tap *
  page25_i91
#ISCELL
  standard offpage *
  page25_i92
#ISCELL
  standard offpage *
  page25_i93
#ISCELL
  standard offpage *
  page25_i94
#ISCELL
  standard tap *
  page25_i95
#ISCELL
  standard tap *
  page25_i96
#ISCELL
  standard tap *
  page25_i97
#ISCELL
  standard tap *
  page25_i98
#ISCELL
  standard tap *
  page25_i99
#ISCELL
  pure_quanta quanta_title_block_c *
  *
#ISCELL
  standard offpage *
  page26_i1
#ISCELL
  standard offpage *
  page26_i10
#ISCELL
  standard tap *
  page26_i100
#ISCELL
  standard tap *
  page26_i101
#ISCELL
  standard tap *
  page26_i102
#ISCELL
  standard tap *
  page26_i103
#ISCELL
  standard tap *
  page26_i104
#ISCELL
  standard tap *
  page26_i105
#ISCELL
  standard tap *
  page26_i106
#ISCELL
  standard tap *
  page26_i107
#ISCELL
  standard tap *
  page26_i108
#ISCELL
  standard tap *
  page26_i109
#ISCELL
  standard offpage *
  page26_i11
#ISCELL
  standard tap *
  page26_i110
#ISCELL
  standard tap *
  page26_i111
#ISCELL
  standard tap *
  page26_i112
#ISCELL
  standard tap *
  page26_i113
#ISCELL
  standard tap *
  page26_i114
#ISCELL
  standard tap *
  page26_i115
#ISCELL
  standard tap *
  page26_i116
#ISCELL
  standard tap *
  page26_i117
#ISCELL
  standard tap *
  page26_i118
#ISCELL
  standard tap *
  page26_i119
#ISCELL
  standard tap *
  page26_i12
#ISCELL
  standard tap *
  page26_i120
#ISCELL
  standard tap *
  page26_i121
#ISCELL
  standard tap *
  page26_i122
#ISCELL
  standard tap *
  page26_i123
#ISCELL
  standard tap *
  page26_i124
#ISCELL
  standard tap *
  page26_i125
#ISCELL
  standard tap *
  page26_i126
#ISCELL
  standard tap *
  page26_i127
#ISCELL
  standard tap *
  page26_i128
#ISCELL
  standard tap *
  page26_i129
#ISCELL
  standard tap *
  page26_i13
#ISCELL
  standard tap *
  page26_i130
#ISCELL
  standard tap *
  page26_i131
#ISCELL
  standard tap *
  page26_i132
#ISCELL
  standard tap *
  page26_i133
#ISCELL
  standard tap *
  page26_i134
#ISCELL
  standard tap *
  page26_i135
#ISCELL
  standard tap *
  page26_i136
#ISCELL
  standard tap *
  page26_i137
#ISCELL
  standard tap *
  page26_i138
#ISCELL
  standard tap *
  page26_i139
#ISCELL
  standard tap *
  page26_i14
#ISCELL
  standard tap *
  page26_i140
#ISCELL
  standard tap *
  page26_i141
#ISCELL
  standard tap *
  page26_i142
#ISCELL
  standard tap *
  page26_i143
#ISCELL
  standard tap *
  page26_i144
#ISCELL
  standard tap *
  page26_i145
#ISCELL
  standard tap *
  page26_i146
#ISCELL
  standard tap *
  page26_i147
#ISCELL
  standard tap *
  page26_i148
#ISCELL
  standard tap *
  page26_i149
#ISCELL
  standard tap *
  page26_i15
#ISCELL
  standard tap *
  page26_i150
#ISCELL
  standard tap *
  page26_i151
#ISCELL
  standard tap *
  page26_i152
#ISCELL
  standard tap *
  page26_i153
#ISCELL
  standard tap *
  page26_i154
#ISCELL
  standard tap *
  page26_i155
#ISCELL
  standard tap *
  page26_i156
#ISCELL
  standard tap *
  page26_i157
#ISCELL
  standard tap *
  page26_i158
#ISCELL
  standard offpage *
  page26_i159
#ISCELL
  standard tap *
  page26_i16
#ISCELL
  standard offpage *
  page26_i160
#ISCELL
  standard offpage *
  page26_i161
#ISCELL
  standard offpage *
  page26_i162
#ISCELL
  standard offpage *
  page26_i163
#ISCELL
  standard offpage *
  page26_i164
#ISCELL
  standard offpage *
  page26_i165
#ISCELL
  standard offpage *
  page26_i166
#ISCELL
  standard offpage *
  page26_i167
#ISCELL
  standard offpage *
  page26_i168
#CELL
  pure_quanta socket4677_azif0045p001c01cs *
  page26_i169
#ISCELL
  standard tap *
  page26_i17
#ISCELL
  standard tap *
  page26_i18
#ISCELL
  standard tap *
  page26_i19
#ISCELL
  standard offpage *
  page26_i2
#ISCELL
  standard tap *
  page26_i20
#ISCELL
  standard tap *
  page26_i21
#ISCELL
  standard tap *
  page26_i22
#ISCELL
  standard tap *
  page26_i23
#ISCELL
  standard tap *
  page26_i24
#ISCELL
  standard tap *
  page26_i25
#ISCELL
  standard tap *
  page26_i26
#ISCELL
  standard tap *
  page26_i27
#ISCELL
  standard tap *
  page26_i28
#ISCELL
  standard tap *
  page26_i29
#ISCELL
  standard tap *
  page26_i3
#ISCELL
  standard tap *
  page26_i30
#ISCELL
  standard tap *
  page26_i31
#ISCELL
  standard tap *
  page26_i32
#ISCELL
  standard tap *
  page26_i33
#ISCELL
  standard tap *
  page26_i34
#ISCELL
  standard tap *
  page26_i35
#ISCELL
  standard tap *
  page26_i36
#ISCELL
  standard tap *
  page26_i37
#ISCELL
  standard tap *
  page26_i38
#ISCELL
  standard tap *
  page26_i39
#ISCELL
  standard tap *
  page26_i4
#ISCELL
  standard tap *
  page26_i40
#ISCELL
  standard tap *
  page26_i41
#ISCELL
  standard tap *
  page26_i42
#ISCELL
  standard tap *
  page26_i43
#ISCELL
  standard tap *
  page26_i44
#ISCELL
  standard tap *
  page26_i45
#ISCELL
  standard tap *
  page26_i46
#ISCELL
  standard tap *
  page26_i47
#ISCELL
  standard tap *
  page26_i48
#ISCELL
  standard tap *
  page26_i49
#ISCELL
  standard tap *
  page26_i5
#ISCELL
  standard tap *
  page26_i50
#ISCELL
  standard tap *
  page26_i51
#ISCELL
  standard offpage *
  page26_i52
#ISCELL
  standard offpage *
  page26_i53
#ISCELL
  standard tap *
  page26_i54
#ISCELL
  standard tap *
  page26_i55
#ISCELL
  standard tap *
  page26_i56
#ISCELL
  standard tap *
  page26_i57
#ISCELL
  standard tap *
  page26_i58
#ISCELL
  standard tap *
  page26_i59
#ISCELL
  standard tap *
  page26_i6
#ISCELL
  standard tap *
  page26_i60
#ISCELL
  standard tap *
  page26_i61
#ISCELL
  standard tap *
  page26_i62
#ISCELL
  standard tap *
  page26_i63
#ISCELL
  standard tap *
  page26_i64
#ISCELL
  standard tap *
  page26_i65
#ISCELL
  standard tap *
  page26_i66
#ISCELL
  standard tap *
  page26_i67
#ISCELL
  standard tap *
  page26_i68
#ISCELL
  standard tap *
  page26_i69
#ISCELL
  standard tap *
  page26_i7
#ISCELL
  standard tap *
  page26_i70
#ISCELL
  standard tap *
  page26_i71
#ISCELL
  standard tap *
  page26_i72
#ISCELL
  standard tap *
  page26_i73
#ISCELL
  standard tap *
  page26_i74
#ISCELL
  standard tap *
  page26_i75
#ISCELL
  standard tap *
  page26_i76
#ISCELL
  standard tap *
  page26_i77
#ISCELL
  standard tap *
  page26_i78
#ISCELL
  standard tap *
  page26_i79
#ISCELL
  standard tap *
  page26_i8
#ISCELL
  standard tap *
  page26_i80
#ISCELL
  standard tap *
  page26_i81
#ISCELL
  standard tap *
  page26_i82
#ISCELL
  standard tap *
  page26_i83
#ISCELL
  standard tap *
  page26_i84
#ISCELL
  standard tap *
  page26_i85
#ISCELL
  standard tap *
  page26_i86
#ISCELL
  standard tap *
  page26_i87
#ISCELL
  standard tap *
  page26_i88
#ISCELL
  standard tap *
  page26_i89
#ISCELL
  standard tap *
  page26_i9
#ISCELL
  standard tap *
  page26_i90
#ISCELL
  standard offpage *
  page26_i92
#ISCELL
  standard offpage *
  page26_i93
#ISCELL
  standard offpage *
  page26_i94
#ISCELL
  standard offpage *
  page26_i95
#ISCELL
  standard offpage *
  page26_i96
#ISCELL
  standard tap *
  page26_i97
#ISCELL
  standard tap *
  page26_i98
#ISCELL
  standard tap *
  page26_i99
#ISCELL
  pure_quanta quanta_title_block_c *
  *
#ISCELL
  standard offpage *
  page27_i1
#ISCELL
  standard offpage *
  page27_i10
#ISCELL
  standard tap *
  page27_i100
#ISCELL
  standard tap *
  page27_i101
#ISCELL
  standard tap *
  page27_i102
#ISCELL
  standard tap *
  page27_i103
#ISCELL
  standard tap *
  page27_i104
#ISCELL
  standard tap *
  page27_i105
#ISCELL
  standard tap *
  page27_i106
#ISCELL
  standard tap *
  page27_i107
#ISCELL
  standard tap *
  page27_i108
#ISCELL
  standard tap *
  page27_i109
#ISCELL
  standard offpage *
  page27_i11
#ISCELL
  standard tap *
  page27_i110
#ISCELL
  standard tap *
  page27_i111
#ISCELL
  standard tap *
  page27_i112
#ISCELL
  standard tap *
  page27_i113
#ISCELL
  standard tap *
  page27_i114
#ISCELL
  standard tap *
  page27_i115
#ISCELL
  standard tap *
  page27_i116
#ISCELL
  standard tap *
  page27_i117
#ISCELL
  standard tap *
  page27_i118
#ISCELL
  standard tap *
  page27_i119
#ISCELL
  standard tap *
  page27_i12
#ISCELL
  standard tap *
  page27_i120
#ISCELL
  standard tap *
  page27_i121
#ISCELL
  standard tap *
  page27_i122
#ISCELL
  standard tap *
  page27_i123
#ISCELL
  standard tap *
  page27_i124
#ISCELL
  standard tap *
  page27_i125
#ISCELL
  standard tap *
  page27_i126
#ISCELL
  standard tap *
  page27_i127
#ISCELL
  standard tap *
  page27_i128
#ISCELL
  standard tap *
  page27_i129
#ISCELL
  standard tap *
  page27_i13
#ISCELL
  standard tap *
  page27_i130
#ISCELL
  standard tap *
  page27_i131
#ISCELL
  standard tap *
  page27_i132
#ISCELL
  standard tap *
  page27_i133
#ISCELL
  standard tap *
  page27_i134
#ISCELL
  standard tap *
  page27_i135
#ISCELL
  standard tap *
  page27_i136
#ISCELL
  standard tap *
  page27_i137
#ISCELL
  standard tap *
  page27_i138
#ISCELL
  standard tap *
  page27_i139
#ISCELL
  standard tap *
  page27_i14
#ISCELL
  standard tap *
  page27_i140
#ISCELL
  standard tap *
  page27_i141
#ISCELL
  standard tap *
  page27_i142
#ISCELL
  standard tap *
  page27_i143
#ISCELL
  standard tap *
  page27_i144
#ISCELL
  standard tap *
  page27_i145
#ISCELL
  standard tap *
  page27_i146
#ISCELL
  standard tap *
  page27_i147
#ISCELL
  standard tap *
  page27_i148
#ISCELL
  standard tap *
  page27_i149
#ISCELL
  standard tap *
  page27_i15
#ISCELL
  standard tap *
  page27_i150
#ISCELL
  standard tap *
  page27_i151
#ISCELL
  standard tap *
  page27_i152
#ISCELL
  standard tap *
  page27_i153
#ISCELL
  standard tap *
  page27_i154
#ISCELL
  standard tap *
  page27_i155
#ISCELL
  standard tap *
  page27_i156
#ISCELL
  standard tap *
  page27_i157
#ISCELL
  standard tap *
  page27_i158
#ISCELL
  standard offpage *
  page27_i159
#ISCELL
  standard tap *
  page27_i16
#ISCELL
  standard offpage *
  page27_i160
#ISCELL
  standard offpage *
  page27_i161
#ISCELL
  standard offpage *
  page27_i162
#ISCELL
  standard offpage *
  page27_i163
#ISCELL
  standard offpage *
  page27_i164
#ISCELL
  standard offpage *
  page27_i165
#ISCELL
  standard offpage *
  page27_i166
#ISCELL
  standard offpage *
  page27_i167
#ISCELL
  standard offpage *
  page27_i168
#CELL
  pure_quanta socket4677_azif0045p001c01cs *
  page27_i169
#ISCELL
  standard tap *
  page27_i17
#ISCELL
  standard tap *
  page27_i18
#ISCELL
  standard tap *
  page27_i19
#ISCELL
  standard offpage *
  page27_i2
#ISCELL
  standard tap *
  page27_i20
#ISCELL
  standard tap *
  page27_i21
#ISCELL
  standard tap *
  page27_i22
#ISCELL
  standard tap *
  page27_i23
#ISCELL
  standard tap *
  page27_i24
#ISCELL
  standard tap *
  page27_i25
#ISCELL
  standard tap *
  page27_i26
#ISCELL
  standard tap *
  page27_i27
#ISCELL
  standard tap *
  page27_i28
#ISCELL
  standard tap *
  page27_i29
#ISCELL
  standard tap *
  page27_i3
#ISCELL
  standard tap *
  page27_i30
#ISCELL
  standard tap *
  page27_i31
#ISCELL
  standard tap *
  page27_i32
#ISCELL
  standard tap *
  page27_i33
#ISCELL
  standard tap *
  page27_i34
#ISCELL
  standard tap *
  page27_i35
#ISCELL
  standard tap *
  page27_i36
#ISCELL
  standard tap *
  page27_i37
#ISCELL
  standard tap *
  page27_i38
#ISCELL
  standard tap *
  page27_i39
#ISCELL
  standard tap *
  page27_i4
#ISCELL
  standard tap *
  page27_i40
#ISCELL
  standard tap *
  page27_i41
#ISCELL
  standard tap *
  page27_i42
#ISCELL
  standard tap *
  page27_i43
#ISCELL
  standard tap *
  page27_i44
#ISCELL
  standard tap *
  page27_i45
#ISCELL
  standard tap *
  page27_i46
#ISCELL
  standard tap *
  page27_i47
#ISCELL
  standard tap *
  page27_i48
#ISCELL
  standard tap *
  page27_i49
#ISCELL
  standard tap *
  page27_i5
#ISCELL
  standard tap *
  page27_i50
#ISCELL
  standard tap *
  page27_i51
#ISCELL
  standard offpage *
  page27_i52
#ISCELL
  standard offpage *
  page27_i53
#ISCELL
  standard tap *
  page27_i54
#ISCELL
  standard tap *
  page27_i55
#ISCELL
  standard tap *
  page27_i56
#ISCELL
  standard tap *
  page27_i57
#ISCELL
  standard tap *
  page27_i58
#ISCELL
  standard tap *
  page27_i59
#ISCELL
  standard tap *
  page27_i6
#ISCELL
  standard tap *
  page27_i60
#ISCELL
  standard tap *
  page27_i61
#ISCELL
  standard tap *
  page27_i62
#ISCELL
  standard tap *
  page27_i63
#ISCELL
  standard tap *
  page27_i64
#ISCELL
  standard tap *
  page27_i65
#ISCELL
  standard tap *
  page27_i66
#ISCELL
  standard tap *
  page27_i67
#ISCELL
  standard tap *
  page27_i68
#ISCELL
  standard tap *
  page27_i69
#ISCELL
  standard tap *
  page27_i7
#ISCELL
  standard tap *
  page27_i70
#ISCELL
  standard tap *
  page27_i71
#ISCELL
  standard tap *
  page27_i72
#ISCELL
  standard tap *
  page27_i73
#ISCELL
  standard tap *
  page27_i74
#ISCELL
  standard tap *
  page27_i75
#ISCELL
  standard tap *
  page27_i76
#ISCELL
  standard tap *
  page27_i77
#ISCELL
  standard tap *
  page27_i78
#ISCELL
  standard tap *
  page27_i79
#ISCELL
  standard tap *
  page27_i8
#ISCELL
  standard tap *
  page27_i80
#ISCELL
  standard tap *
  page27_i81
#ISCELL
  standard tap *
  page27_i82
#ISCELL
  standard tap *
  page27_i83
#ISCELL
  standard tap *
  page27_i84
#ISCELL
  standard tap *
  page27_i85
#ISCELL
  standard tap *
  page27_i86
#ISCELL
  standard tap *
  page27_i87
#ISCELL
  standard tap *
  page27_i88
#ISCELL
  standard tap *
  page27_i89
#ISCELL
  standard tap *
  page27_i9
#ISCELL
  standard tap *
  page27_i90
#ISCELL
  standard offpage *
  page27_i92
#ISCELL
  standard offpage *
  page27_i93
#ISCELL
  standard offpage *
  page27_i94
#ISCELL
  standard offpage *
  page27_i95
#ISCELL
  standard offpage *
  page27_i96
#ISCELL
  standard tap *
  page27_i97
#ISCELL
  standard tap *
  page27_i98
#ISCELL
  standard tap *
  page27_i99
#ISCELL
  pure_quanta quanta_title_block_c *
  *
#ISCELL
  standard tap *
  page28_i151
#ISCELL
  standard tap *
  page28_i152
#ISCELL
  standard tap *
  page28_i161
#ISCELL
  standard tap *
  page28_i165
#CELL
  pure_quanta socket4677_azif0045p001c01cs *
  page28_i169
#ISCELL
  standard tap *
  page28_i171
#ISCELL
  standard tap *
  page28_i173
#ISCELL
  standard tap *
  page28_i179
#ISCELL
  standard tap *
  page28_i184
#ISCELL
  standard tap *
  page28_i186
#ISCELL
  standard tap *
  page28_i188
#ISCELL
  standard offpage *
  page28_i281
#ISCELL
  standard offpage *
  page28_i282
#ISCELL
  standard offpage *
  page28_i286
#ISCELL
  standard offpage *
  page28_i287
#ISCELL
  standard tap *
  page28_i288
#ISCELL
  standard tap *
  page28_i289
#ISCELL
  standard tap *
  page28_i290
#ISCELL
  standard tap *
  page28_i292
#ISCELL
  standard tap *
  page28_i293
#ISCELL
  standard tap *
  page28_i294
#ISCELL
  standard tap *
  page28_i296
#ISCELL
  standard tap *
  page28_i297
#ISCELL
  standard tap *
  page28_i298
#ISCELL
  standard tap *
  page28_i299
#ISCELL
  standard tap *
  page28_i300
#ISCELL
  standard tap *
  page28_i301
#ISCELL
  standard tap *
  page28_i302
#ISCELL
  standard tap *
  page28_i303
#ISCELL
  standard tap *
  page28_i304
#ISCELL
  standard tap *
  page28_i305
#ISCELL
  standard tap *
  page28_i306
#ISCELL
  standard tap *
  page28_i307
#ISCELL
  standard tap *
  page28_i308
#ISCELL
  standard tap *
  page28_i309
#ISCELL
  standard tap *
  page28_i310
#ISCELL
  standard tap *
  page28_i311
#ISCELL
  pure_quanta quanta_title_block_c *
  *
#CELL
  pure_quanta socket4677_azif0045p001c01cs *
  page29_i176
#CELL
  pure_quanta socket4677_azif0045p001c01cs *
  page29_i37
#ISCELL
  standard offpage *
  page29_i402
#ISCELL
  standard offpage *
  page29_i403
#ISCELL
  standard tap *
  page29_i404
#ISCELL
  standard tap *
  page29_i405
#ISCELL
  standard tap *
  page29_i406
#ISCELL
  standard tap *
  page29_i407
#ISCELL
  standard tap *
  page29_i408
#ISCELL
  standard tap *
  page29_i409
#ISCELL
  standard tap *
  page29_i410
#ISCELL
  standard tap *
  page29_i411
#ISCELL
  standard tap *
  page29_i412
#ISCELL
  standard tap *
  page29_i413
#ISCELL
  standard tap *
  page29_i414
#ISCELL
  standard tap *
  page29_i415
#ISCELL
  standard tap *
  page29_i416
#ISCELL
  standard tap *
  page29_i417
#ISCELL
  standard tap *
  page29_i418
#ISCELL
  standard tap *
  page29_i419
#ISCELL
  standard tap *
  page29_i420
#ISCELL
  standard tap *
  page29_i421
#ISCELL
  standard tap *
  page29_i422
#ISCELL
  standard tap *
  page29_i423
#ISCELL
  standard tap *
  page29_i424
#ISCELL
  standard tap *
  page29_i425
#ISCELL
  standard tap *
  page29_i426
#ISCELL
  standard tap *
  page29_i427
#ISCELL
  standard tap *
  page29_i428
#ISCELL
  standard tap *
  page29_i429
#ISCELL
  standard tap *
  page29_i430
#ISCELL
  standard tap *
  page29_i431
#ISCELL
  standard tap *
  page29_i432
#ISCELL
  standard tap *
  page29_i433
#ISCELL
  standard tap *
  page29_i434
#ISCELL
  standard tap *
  page29_i435
#ISCELL
  standard tap *
  page29_i436
#ISCELL
  standard tap *
  page29_i437
#ISCELL
  standard tap *
  page29_i438
#ISCELL
  standard tap *
  page29_i439
#ISCELL
  standard tap *
  page29_i440
#ISCELL
  standard tap *
  page29_i441
#ISCELL
  standard tap *
  page29_i442
#ISCELL
  standard tap *
  page29_i443
#ISCELL
  standard tap *
  page29_i444
#ISCELL
  standard tap *
  page29_i445
#ISCELL
  standard tap *
  page29_i446
#ISCELL
  standard tap *
  page29_i447
#ISCELL
  standard tap *
  page29_i448
#ISCELL
  standard tap *
  page29_i449
#ISCELL
  standard tap *
  page29_i450
#ISCELL
  standard tap *
  page29_i451
#ISCELL
  standard tap *
  page29_i452
#ISCELL
  standard tap *
  page29_i453
#ISCELL
  standard tap *
  page29_i454
#ISCELL
  standard tap *
  page29_i455
#ISCELL
  standard tap *
  page29_i456
#ISCELL
  standard tap *
  page29_i457
#ISCELL
  standard tap *
  page29_i458
#ISCELL
  standard tap *
  page29_i459
#ISCELL
  standard tap *
  page29_i460
#ISCELL
  standard tap *
  page29_i461
#ISCELL
  standard tap *
  page29_i462
#ISCELL
  standard tap *
  page29_i463
#ISCELL
  standard tap *
  page29_i464
#ISCELL
  standard tap *
  page29_i465
#ISCELL
  standard tap *
  page29_i466
#ISCELL
  standard tap *
  page29_i467
#ISCELL
  standard offpage *
  page29_i468
#ISCELL
  standard offpage *
  page29_i469
#ISCELL
  standard tap *
  page29_i470
#ISCELL
  standard tap *
  page29_i471
#ISCELL
  standard tap *
  page29_i472
#ISCELL
  standard tap *
  page29_i473
#ISCELL
  standard tap *
  page29_i474
#ISCELL
  standard tap *
  page29_i475
#ISCELL
  standard tap *
  page29_i476
#ISCELL
  standard tap *
  page29_i477
#ISCELL
  standard tap *
  page29_i478
#ISCELL
  standard tap *
  page29_i479
#ISCELL
  standard tap *
  page29_i480
#ISCELL
  standard tap *
  page29_i481
#ISCELL
  standard tap *
  page29_i482
#ISCELL
  standard tap *
  page29_i483
#ISCELL
  standard tap *
  page29_i484
#ISCELL
  standard tap *
  page29_i485
#ISCELL
  standard tap *
  page29_i486
#ISCELL
  standard tap *
  page29_i487
#ISCELL
  standard tap *
  page29_i488
#ISCELL
  standard tap *
  page29_i489
#ISCELL
  standard tap *
  page29_i490
#ISCELL
  standard tap *
  page29_i491
#ISCELL
  standard tap *
  page29_i492
#ISCELL
  standard tap *
  page29_i493
#ISCELL
  standard tap *
  page29_i494
#ISCELL
  standard tap *
  page29_i495
#ISCELL
  standard tap *
  page29_i496
#ISCELL
  standard tap *
  page29_i497
#ISCELL
  standard tap *
  page29_i498
#ISCELL
  standard tap *
  page29_i499
#ISCELL
  standard tap *
  page29_i500
#ISCELL
  standard tap *
  page29_i501
#ISCELL
  standard offpage *
  page29_i502
#ISCELL
  standard offpage *
  page29_i503
#ISCELL
  standard tap *
  page29_i504
#ISCELL
  standard tap *
  page29_i505
#ISCELL
  standard tap *
  page29_i506
#ISCELL
  standard tap *
  page29_i507
#ISCELL
  standard tap *
  page29_i508
#ISCELL
  standard tap *
  page29_i509
#ISCELL
  standard tap *
  page29_i510
#ISCELL
  standard tap *
  page29_i511
#ISCELL
  standard tap *
  page29_i512
#ISCELL
  standard tap *
  page29_i513
#ISCELL
  standard tap *
  page29_i514
#ISCELL
  standard tap *
  page29_i515
#ISCELL
  standard tap *
  page29_i516
#ISCELL
  standard tap *
  page29_i517
#ISCELL
  standard tap *
  page29_i518
#ISCELL
  standard tap *
  page29_i519
#ISCELL
  standard tap *
  page29_i520
#ISCELL
  standard tap *
  page29_i521
#ISCELL
  standard tap *
  page29_i522
#ISCELL
  standard tap *
  page29_i523
#ISCELL
  standard tap *
  page29_i524
#ISCELL
  standard tap *
  page29_i525
#ISCELL
  standard tap *
  page29_i526
#ISCELL
  standard tap *
  page29_i527
#ISCELL
  standard tap *
  page29_i528
#ISCELL
  standard tap *
  page29_i529
#ISCELL
  standard tap *
  page29_i530
#ISCELL
  standard tap *
  page29_i531
#ISCELL
  standard tap *
  page29_i532
#ISCELL
  standard tap *
  page29_i533
#ISCELL
  standard tap *
  page29_i534
#ISCELL
  standard tap *
  page29_i535
#ISCELL
  standard offpage *
  page29_i536
#ISCELL
  standard offpage *
  page29_i537
#ISCELL
  pure_quanta quanta_title_block_c *
  *
#CELL
  pure_quanta socket4677_azif0045p001c01cs *
  page30_i139
#CELL
  pure_quanta socket4677_azif0045p001c01cs *
  page30_i140
#ISCELL
  standard offpage *
  page30_i181
#ISCELL
  standard offpage *
  page30_i182
#ISCELL
  standard offpage *
  page30_i251
#ISCELL
  standard offpage *
  page30_i252
#ISCELL
  standard tap *
  page30_i253
#ISCELL
  standard tap *
  page30_i254
#ISCELL
  standard tap *
  page30_i255
#ISCELL
  standard tap *
  page30_i256
#ISCELL
  standard tap *
  page30_i257
#ISCELL
  standard tap *
  page30_i258
#ISCELL
  standard tap *
  page30_i259
#ISCELL
  standard tap *
  page30_i260
#ISCELL
  standard tap *
  page30_i261
#ISCELL
  standard tap *
  page30_i262
#ISCELL
  standard tap *
  page30_i263
#ISCELL
  standard tap *
  page30_i264
#ISCELL
  standard tap *
  page30_i265
#ISCELL
  standard tap *
  page30_i266
#ISCELL
  standard tap *
  page30_i267
#ISCELL
  standard tap *
  page30_i268
#ISCELL
  standard tap *
  page30_i269
#ISCELL
  standard tap *
  page30_i270
#ISCELL
  standard tap *
  page30_i271
#ISCELL
  standard tap *
  page30_i272
#ISCELL
  standard tap *
  page30_i273
#ISCELL
  standard tap *
  page30_i274
#ISCELL
  standard tap *
  page30_i275
#ISCELL
  standard tap *
  page30_i276
#ISCELL
  standard tap *
  page30_i277
#ISCELL
  standard tap *
  page30_i278
#ISCELL
  standard tap *
  page30_i279
#ISCELL
  standard tap *
  page30_i280
#ISCELL
  standard tap *
  page30_i281
#ISCELL
  standard tap *
  page30_i282
#ISCELL
  standard tap *
  page30_i283
#ISCELL
  standard tap *
  page30_i284
#ISCELL
  standard tap *
  page30_i285
#ISCELL
  standard tap *
  page30_i286
#ISCELL
  standard tap *
  page30_i287
#ISCELL
  standard tap *
  page30_i288
#ISCELL
  standard tap *
  page30_i289
#ISCELL
  standard tap *
  page30_i290
#ISCELL
  standard tap *
  page30_i291
#ISCELL
  standard tap *
  page30_i292
#ISCELL
  standard tap *
  page30_i293
#ISCELL
  standard tap *
  page30_i294
#ISCELL
  standard tap *
  page30_i295
#ISCELL
  standard tap *
  page30_i296
#ISCELL
  standard tap *
  page30_i297
#ISCELL
  standard tap *
  page30_i298
#ISCELL
  standard tap *
  page30_i299
#ISCELL
  standard tap *
  page30_i300
#ISCELL
  standard tap *
  page30_i301
#ISCELL
  standard tap *
  page30_i302
#ISCELL
  standard tap *
  page30_i303
#ISCELL
  standard tap *
  page30_i304
#ISCELL
  standard tap *
  page30_i305
#ISCELL
  standard tap *
  page30_i306
#ISCELL
  standard tap *
  page30_i307
#ISCELL
  standard tap *
  page30_i308
#ISCELL
  standard tap *
  page30_i309
#ISCELL
  standard tap *
  page30_i310
#ISCELL
  standard tap *
  page30_i311
#ISCELL
  standard tap *
  page30_i312
#ISCELL
  standard tap *
  page30_i313
#ISCELL
  standard tap *
  page30_i314
#ISCELL
  standard tap *
  page30_i315
#ISCELL
  standard tap *
  page30_i316
#ISCELL
  standard offpage *
  page30_i317
#ISCELL
  standard offpage *
  page30_i318
#ISCELL
  standard tap *
  page30_i319
#ISCELL
  standard tap *
  page30_i320
#ISCELL
  standard tap *
  page30_i321
#ISCELL
  standard tap *
  page30_i322
#ISCELL
  standard tap *
  page30_i323
#ISCELL
  standard tap *
  page30_i324
#ISCELL
  standard tap *
  page30_i325
#ISCELL
  standard tap *
  page30_i326
#ISCELL
  standard tap *
  page30_i327
#ISCELL
  standard tap *
  page30_i328
#ISCELL
  standard tap *
  page30_i329
#ISCELL
  standard tap *
  page30_i330
#ISCELL
  standard tap *
  page30_i331
#ISCELL
  standard tap *
  page30_i332
#ISCELL
  standard tap *
  page30_i333
#ISCELL
  standard tap *
  page30_i334
#ISCELL
  standard tap *
  page30_i335
#ISCELL
  standard tap *
  page30_i336
#ISCELL
  standard tap *
  page30_i337
#ISCELL
  standard tap *
  page30_i338
#ISCELL
  standard tap *
  page30_i339
#ISCELL
  standard tap *
  page30_i340
#ISCELL
  standard tap *
  page30_i341
#ISCELL
  standard tap *
  page30_i342
#ISCELL
  standard tap *
  page30_i343
#ISCELL
  standard tap *
  page30_i344
#ISCELL
  standard tap *
  page30_i345
#ISCELL
  standard tap *
  page30_i346
#ISCELL
  standard tap *
  page30_i347
#ISCELL
  standard tap *
  page30_i348
#ISCELL
  standard tap *
  page30_i349
#ISCELL
  standard tap *
  page30_i350
#ISCELL
  standard offpage *
  page30_i351
#ISCELL
  standard offpage *
  page30_i352
#ISCELL
  standard tap *
  page30_i37
#ISCELL
  standard tap *
  page30_i38
#ISCELL
  standard tap *
  page30_i39
#ISCELL
  standard tap *
  page30_i40
#ISCELL
  standard tap *
  page30_i41
#ISCELL
  standard tap *
  page30_i42
#ISCELL
  standard tap *
  page30_i43
#ISCELL
  standard tap *
  page30_i44
#ISCELL
  standard tap *
  page30_i45
#ISCELL
  standard tap *
  page30_i46
#ISCELL
  standard tap *
  page30_i47
#ISCELL
  standard tap *
  page30_i48
#ISCELL
  standard tap *
  page30_i49
#ISCELL
  standard tap *
  page30_i50
#ISCELL
  standard tap *
  page30_i51
#ISCELL
  standard tap *
  page30_i52
#ISCELL
  standard tap *
  page30_i53
#ISCELL
  standard tap *
  page30_i54
#ISCELL
  standard tap *
  page30_i55
#ISCELL
  standard tap *
  page30_i56
#ISCELL
  standard tap *
  page30_i57
#ISCELL
  standard tap *
  page30_i58
#ISCELL
  standard tap *
  page30_i59
#ISCELL
  standard tap *
  page30_i60
#ISCELL
  standard tap *
  page30_i61
#ISCELL
  standard tap *
  page30_i62
#ISCELL
  standard tap *
  page30_i63
#ISCELL
  standard tap *
  page30_i64
#ISCELL
  standard tap *
  page30_i65
#ISCELL
  standard tap *
  page30_i66
#ISCELL
  standard tap *
  page30_i67
#ISCELL
  standard tap *
  page30_i68
#ISCELL
  pure_quanta quanta_title_block_c *
  *
#CELL
  pure_quanta socket4677_azif0045p001c01cs *
  page31_i139
#ISCELL
  standard tap *
  page31_i207
#ISCELL
  standard tap *
  page31_i208
#ISCELL
  standard tap *
  page31_i209
#ISCELL
  standard tap *
  page31_i210
#ISCELL
  standard tap *
  page31_i211
#ISCELL
  standard tap *
  page31_i212
#ISCELL
  standard tap *
  page31_i213
#ISCELL
  standard tap *
  page31_i214
#ISCELL
  standard tap *
  page31_i215
#ISCELL
  standard tap *
  page31_i216
#ISCELL
  standard tap *
  page31_i217
#ISCELL
  standard tap *
  page31_i218
#ISCELL
  standard tap *
  page31_i219
#ISCELL
  standard tap *
  page31_i220
#ISCELL
  standard tap *
  page31_i221
#ISCELL
  standard tap *
  page31_i222
#ISCELL
  standard tap *
  page31_i223
#ISCELL
  standard tap *
  page31_i224
#ISCELL
  standard tap *
  page31_i225
#ISCELL
  standard tap *
  page31_i226
#ISCELL
  standard tap *
  page31_i227
#ISCELL
  standard tap *
  page31_i228
#ISCELL
  standard tap *
  page31_i229
#ISCELL
  standard tap *
  page31_i230
#ISCELL
  standard tap *
  page31_i231
#ISCELL
  standard tap *
  page31_i232
#ISCELL
  standard tap *
  page31_i233
#ISCELL
  standard tap *
  page31_i234
#ISCELL
  standard tap *
  page31_i235
#ISCELL
  standard tap *
  page31_i236
#ISCELL
  standard tap *
  page31_i237
#ISCELL
  standard tap *
  page31_i238
#ISCELL
  standard offpage *
  page31_i239
#ISCELL
  standard offpage *
  page31_i240
#ISCELL
  standard offpage *
  page31_i241
#ISCELL
  standard offpage *
  page31_i242
#ISCELL
  standard tap *
  page31_i243
#ISCELL
  standard tap *
  page31_i244
#ISCELL
  standard tap *
  page31_i245
#ISCELL
  standard tap *
  page31_i246
#ISCELL
  standard tap *
  page31_i247
#ISCELL
  standard tap *
  page31_i248
#ISCELL
  standard tap *
  page31_i249
#ISCELL
  standard tap *
  page31_i250
#ISCELL
  standard tap *
  page31_i251
#ISCELL
  standard tap *
  page31_i252
#ISCELL
  standard tap *
  page31_i253
#ISCELL
  standard tap *
  page31_i254
#ISCELL
  standard tap *
  page31_i255
#ISCELL
  standard tap *
  page31_i256
#ISCELL
  standard tap *
  page31_i257
#ISCELL
  standard tap *
  page31_i258
#ISCELL
  standard tap *
  page31_i259
#ISCELL
  standard tap *
  page31_i260
#ISCELL
  standard tap *
  page31_i261
#ISCELL
  standard tap *
  page31_i262
#ISCELL
  standard tap *
  page31_i263
#ISCELL
  standard tap *
  page31_i264
#ISCELL
  standard tap *
  page31_i265
#ISCELL
  standard tap *
  page31_i266
#ISCELL
  standard tap *
  page31_i267
#ISCELL
  standard tap *
  page31_i268
#ISCELL
  standard tap *
  page31_i269
#ISCELL
  standard tap *
  page31_i270
#ISCELL
  standard tap *
  page31_i271
#ISCELL
  standard tap *
  page31_i272
#ISCELL
  standard tap *
  page31_i273
#ISCELL
  standard tap *
  page31_i274
#ISCELL
  logical_power design_note *
  *
#ISCELL
  pure_quanta quanta_title_block_c *
  *
#ISCELL
  standard tap *
  page32_i101
#ISCELL
  standard tap *
  page32_i102
#ISCELL
  standard tap *
  page32_i103
#ISCELL
  standard tap *
  page32_i104
#ISCELL
  standard tap *
  page32_i106
#ISCELL
  standard tap *
  page32_i107
#ISCELL
  standard tap *
  page32_i108
#ISCELL
  standard tap *
  page32_i109
#ISCELL
  standard tap *
  page32_i110
#ISCELL
  standard tap *
  page32_i111
#ISCELL
  standard tap *
  page32_i112
#ISCELL
  standard tap *
  page32_i113
#ISCELL
  standard tap *
  page32_i114
#ISCELL
  standard tap *
  page32_i115
#ISCELL
  standard tap *
  page32_i116
#ISCELL
  standard tap *
  page32_i117
#ISCELL
  standard tap *
  page32_i118
#ISCELL
  standard tap *
  page32_i119
#ISCELL
  standard tap *
  page32_i120
#ISCELL
  standard tap *
  page32_i121
#ISCELL
  standard tap *
  page32_i122
#ISCELL
  standard tap *
  page32_i123
#ISCELL
  standard tap *
  page32_i124
#ISCELL
  standard tap *
  page32_i125
#ISCELL
  standard tap *
  page32_i126
#ISCELL
  standard tap *
  page32_i127
#ISCELL
  standard tap *
  page32_i128
#ISCELL
  standard tap *
  page32_i129
#ISCELL
  standard tap *
  page32_i130
#ISCELL
  standard tap *
  page32_i131
#ISCELL
  standard tap *
  page32_i132
#ISCELL
  standard tap *
  page32_i133
#ISCELL
  standard tap *
  page32_i134
#ISCELL
  standard tap *
  page32_i135
#ISCELL
  standard tap *
  page32_i136
#ISCELL
  standard tap *
  page32_i137
#ISCELL
  standard tap *
  page32_i139
#ISCELL
  standard tap *
  page32_i140
#ISCELL
  standard tap *
  page32_i141
#ISCELL
  standard tap *
  page32_i142
#ISCELL
  standard tap *
  page32_i143
#ISCELL
  standard tap *
  page32_i144
#ISCELL
  standard offpage *
  page32_i145
#ISCELL
  standard tap *
  page32_i146
#ISCELL
  standard tap *
  page32_i147
#ISCELL
  standard tap *
  page32_i148
#ISCELL
  standard tap *
  page32_i149
#ISCELL
  standard tap *
  page32_i150
#ISCELL
  standard tap *
  page32_i151
#ISCELL
  standard tap *
  page32_i152
#ISCELL
  standard tap *
  page32_i153
#ISCELL
  standard tap *
  page32_i154
#ISCELL
  standard tap *
  page32_i155
#ISCELL
  standard tap *
  page32_i156
#ISCELL
  standard tap *
  page32_i157
#ISCELL
  standard tap *
  page32_i158
#ISCELL
  standard tap *
  page32_i159
#ISCELL
  standard tap *
  page32_i160
#ISCELL
  standard tap *
  page32_i161
#ISCELL
  standard tap *
  page32_i162
#ISCELL
  standard tap *
  page32_i163
#ISCELL
  standard offpage *
  page32_i164
#ISCELL
  standard tap *
  page32_i165
#ISCELL
  standard tap *
  page32_i166
#ISCELL
  standard tap *
  page32_i167
#ISCELL
  standard tap *
  page32_i168
#ISCELL
  standard tap *
  page32_i169
#ISCELL
  standard tap *
  page32_i170
#ISCELL
  standard tap *
  page32_i171
#ISCELL
  standard tap *
  page32_i172
#ISCELL
  standard tap *
  page32_i173
#ISCELL
  standard tap *
  page32_i174
#ISCELL
  standard tap *
  page32_i175
#ISCELL
  standard tap *
  page32_i176
#ISCELL
  standard tap *
  page32_i19
#ISCELL
  standard offpage *
  page32_i2
#ISCELL
  standard tap *
  page32_i21
#ISCELL
  standard tap *
  page32_i34
#ISCELL
  standard tap *
  page32_i52
#ISCELL
  standard tap *
  page32_i53
#ISCELL
  standard tap *
  page32_i54
#ISCELL
  standard tap *
  page32_i55
#ISCELL
  standard tap *
  page32_i58
#ISCELL
  standard tap *
  page32_i59
#ISCELL
  standard tap *
  page32_i61
#ISCELL
  standard tap *
  page32_i62
#ISCELL
  standard tap *
  page32_i64
#ISCELL
  standard tap *
  page32_i66
#ISCELL
  standard offpage *
  page32_i69
#CELL
  pure_quanta socket4677_azif0045p001c01cs *
  page32_i70
#ISCELL
  standard tap *
  page32_i77
#ISCELL
  standard tap *
  page32_i78
#ISCELL
  standard tap *
  page32_i79
#ISCELL
  standard tap *
  page32_i80
#ISCELL
  standard tap *
  page32_i82
#ISCELL
  standard tap *
  page32_i84
#ISCELL
  standard tap *
  page32_i85
#ISCELL
  standard tap *
  page32_i86
#ISCELL
  standard tap *
  page32_i95
#ISCELL
  standard tap *
  page32_i97
#ISCELL
  standard tap *
  page32_i98
#ISCELL
  logical_power design_note *
  *
#ISCELL
  pure_quanta quanta_title_block_c *
  *
#ISCELL
  standard tap *
  page33_i1
#ISCELL
  standard tap *
  page33_i10
#ISCELL
  standard offpage *
  page33_i101
#CELL
  pure_quanta socket4677_azif0045p001c01cs *
  page33_i102
#ISCELL
  standard tap *
  page33_i103
#ISCELL
  standard tap *
  page33_i104
#ISCELL
  standard tap *
  page33_i105
#ISCELL
  standard tap *
  page33_i106
#ISCELL
  standard tap *
  page33_i107
#ISCELL
  standard tap *
  page33_i108
#ISCELL
  standard tap *
  page33_i109
#ISCELL
  standard tap *
  page33_i11
#ISCELL
  standard tap *
  page33_i111
#ISCELL
  standard tap *
  page33_i112
#ISCELL
  standard tap *
  page33_i113
#ISCELL
  standard tap *
  page33_i114
#ISCELL
  standard tap *
  page33_i115
#ISCELL
  standard tap *
  page33_i116
#ISCELL
  standard tap *
  page33_i117
#ISCELL
  standard tap *
  page33_i118
#ISCELL
  standard tap *
  page33_i119
#ISCELL
  standard tap *
  page33_i12
#ISCELL
  standard tap *
  page33_i120
#ISCELL
  standard tap *
  page33_i121
#ISCELL
  standard tap *
  page33_i122
#ISCELL
  standard tap *
  page33_i123
#ISCELL
  standard tap *
  page33_i124
#ISCELL
  standard tap *
  page33_i125
#ISCELL
  standard tap *
  page33_i126
#ISCELL
  standard tap *
  page33_i127
#ISCELL
  standard tap *
  page33_i128
#ISCELL
  standard tap *
  page33_i129
#ISCELL
  standard tap *
  page33_i13
#ISCELL
  standard tap *
  page33_i130
#ISCELL
  standard tap *
  page33_i131
#ISCELL
  standard tap *
  page33_i132
#ISCELL
  standard tap *
  page33_i133
#ISCELL
  standard tap *
  page33_i134
#ISCELL
  standard tap *
  page33_i135
#ISCELL
  standard offpage *
  page33_i136
#ISCELL
  standard tap *
  page33_i137
#ISCELL
  standard tap *
  page33_i138
#ISCELL
  standard tap *
  page33_i139
#ISCELL
  standard tap *
  page33_i14
#ISCELL
  standard tap *
  page33_i140
#ISCELL
  standard tap *
  page33_i141
#ISCELL
  standard tap *
  page33_i142
#ISCELL
  standard tap *
  page33_i143
#ISCELL
  standard tap *
  page33_i144
#ISCELL
  standard tap *
  page33_i145
#ISCELL
  standard tap *
  page33_i15
#ISCELL
  standard tap *
  page33_i16
#ISCELL
  standard offpage *
  page33_i17
#ISCELL
  standard offpage *
  page33_i18
#ISCELL
  standard tap *
  page33_i19
#ISCELL
  standard tap *
  page33_i2
#ISCELL
  standard tap *
  page33_i20
#ISCELL
  standard tap *
  page33_i22
#ISCELL
  standard tap *
  page33_i24
#ISCELL
  standard tap *
  page33_i25
#ISCELL
  standard tap *
  page33_i27
#ISCELL
  standard tap *
  page33_i29
#ISCELL
  standard tap *
  page33_i30
#ISCELL
  standard tap *
  page33_i31
#ISCELL
  standard tap *
  page33_i32
#ISCELL
  standard tap *
  page33_i33
#ISCELL
  standard tap *
  page33_i34
#ISCELL
  standard tap *
  page33_i35
#ISCELL
  standard tap *
  page33_i36
#ISCELL
  standard tap *
  page33_i37
#ISCELL
  standard tap *
  page33_i38
#ISCELL
  standard tap *
  page33_i4
#ISCELL
  standard tap *
  page33_i40
#ISCELL
  standard tap *
  page33_i41
#ISCELL
  standard tap *
  page33_i42
#ISCELL
  standard tap *
  page33_i43
#ISCELL
  standard tap *
  page33_i44
#ISCELL
  standard tap *
  page33_i48
#ISCELL
  standard tap *
  page33_i5
#ISCELL
  standard tap *
  page33_i52
#ISCELL
  standard tap *
  page33_i53
#ISCELL
  standard tap *
  page33_i54
#ISCELL
  standard tap *
  page33_i56
#ISCELL
  standard tap *
  page33_i58
#ISCELL
  standard tap *
  page33_i59
#ISCELL
  standard tap *
  page33_i6
#ISCELL
  standard tap *
  page33_i61
#ISCELL
  standard tap *
  page33_i62
#ISCELL
  standard tap *
  page33_i7
#ISCELL
  standard tap *
  page33_i75
#ISCELL
  standard tap *
  page33_i76
#ISCELL
  standard tap *
  page33_i77
#ISCELL
  standard tap *
  page33_i78
#ISCELL
  standard tap *
  page33_i8
#ISCELL
  standard tap *
  page33_i81
#ISCELL
  standard tap *
  page33_i82
#ISCELL
  standard tap *
  page33_i84
#ISCELL
  standard tap *
  page33_i85
#ISCELL
  standard tap *
  page33_i86
#ISCELL
  standard tap *
  page33_i9
#ISCELL
  standard tap *
  page33_i99
#ISCELL
  logical_power design_note *
  *
#ISCELL
  pure_quanta quanta_title_block_c *
  *
#ISCELL
  standard offpage *
  page34_i100
#ISCELL
  standard offpage *
  page34_i101
#CELL
  pure_quanta socket4677_azif0045p001c01cs *
  page34_i102
#ISCELL
  standard tap *
  page34_i103
#ISCELL
  standard tap *
  page34_i105
#ISCELL
  standard tap *
  page34_i106
#ISCELL
  standard tap *
  page34_i107
#ISCELL
  standard tap *
  page34_i108
#ISCELL
  standard tap *
  page34_i109
#ISCELL
  standard tap *
  page34_i110
#ISCELL
  standard tap *
  page34_i111
#ISCELL
  standard tap *
  page34_i112
#ISCELL
  standard tap *
  page34_i113
#ISCELL
  standard tap *
  page34_i114
#ISCELL
  standard tap *
  page34_i115
#ISCELL
  standard tap *
  page34_i116
#ISCELL
  standard tap *
  page34_i118
#ISCELL
  standard tap *
  page34_i119
#ISCELL
  standard tap *
  page34_i120
#ISCELL
  standard tap *
  page34_i121
#ISCELL
  standard tap *
  page34_i122
#ISCELL
  standard tap *
  page34_i123
#ISCELL
  standard tap *
  page34_i124
#ISCELL
  standard tap *
  page34_i125
#ISCELL
  standard tap *
  page34_i126
#ISCELL
  standard tap *
  page34_i127
#ISCELL
  standard tap *
  page34_i128
#ISCELL
  standard offpage *
  page34_i129
#ISCELL
  standard tap *
  page34_i130
#ISCELL
  standard tap *
  page34_i131
#ISCELL
  standard tap *
  page34_i14
#ISCELL
  standard tap *
  page34_i16
#ISCELL
  standard tap *
  page34_i17
#ISCELL
  standard offpage *
  page34_i2
#ISCELL
  standard tap *
  page34_i20
#ISCELL
  standard tap *
  page34_i22
#ISCELL
  standard tap *
  page34_i26
#ISCELL
  standard tap *
  page34_i28
#ISCELL
  standard tap *
  page34_i31
#ISCELL
  standard tap *
  page34_i32
#ISCELL
  standard tap *
  page34_i33
#ISCELL
  standard tap *
  page34_i34
#ISCELL
  standard tap *
  page34_i38
#ISCELL
  standard tap *
  page34_i41
#ISCELL
  standard tap *
  page34_i42
#ISCELL
  standard tap *
  page34_i45
#ISCELL
  standard tap *
  page34_i46
#ISCELL
  standard tap *
  page34_i5
#ISCELL
  standard tap *
  page34_i50
#ISCELL
  standard tap *
  page34_i52
#ISCELL
  standard tap *
  page34_i53
#ISCELL
  standard tap *
  page34_i54
#ISCELL
  standard tap *
  page34_i55
#ISCELL
  standard tap *
  page34_i56
#ISCELL
  standard tap *
  page34_i57
#ISCELL
  standard tap *
  page34_i58
#ISCELL
  standard tap *
  page34_i59
#ISCELL
  standard tap *
  page34_i6
#ISCELL
  standard tap *
  page34_i60
#ISCELL
  standard tap *
  page34_i61
#ISCELL
  standard tap *
  page34_i62
#ISCELL
  standard tap *
  page34_i63
#ISCELL
  standard tap *
  page34_i64
#ISCELL
  standard tap *
  page34_i65
#ISCELL
  standard tap *
  page34_i66
#ISCELL
  standard tap *
  page34_i67
#ISCELL
  standard tap *
  page34_i68
#ISCELL
  standard tap *
  page34_i69
#ISCELL
  standard tap *
  page34_i7
#ISCELL
  standard tap *
  page34_i70
#ISCELL
  standard tap *
  page34_i71
#ISCELL
  standard tap *
  page34_i72
#ISCELL
  standard tap *
  page34_i73
#ISCELL
  standard tap *
  page34_i74
#ISCELL
  standard tap *
  page34_i75
#ISCELL
  standard tap *
  page34_i76
#ISCELL
  standard tap *
  page34_i77
#ISCELL
  standard tap *
  page34_i78
#ISCELL
  standard tap *
  page34_i79
#ISCELL
  standard tap *
  page34_i8
#ISCELL
  standard tap *
  page34_i80
#ISCELL
  standard tap *
  page34_i81
#ISCELL
  standard tap *
  page34_i82
#ISCELL
  standard tap *
  page34_i83
#ISCELL
  standard tap *
  page34_i84
#ISCELL
  standard tap *
  page34_i85
#ISCELL
  standard tap *
  page34_i86
#ISCELL
  standard tap *
  page34_i87
#ISCELL
  standard tap *
  page34_i88
#ISCELL
  standard tap *
  page34_i89
#ISCELL
  standard tap *
  page34_i9
#ISCELL
  standard tap *
  page34_i90
#ISCELL
  standard tap *
  page34_i91
#ISCELL
  standard tap *
  page34_i92
#ISCELL
  standard tap *
  page34_i93
#ISCELL
  standard tap *
  page34_i94
#ISCELL
  standard tap *
  page34_i95
#ISCELL
  standard tap *
  page34_i96
#ISCELL
  standard tap *
  page34_i97
#ISCELL
  standard tap *
  page34_i98
#ISCELL
  standard tap *
  page34_i99
#ISCELL
  pure_quanta quanta_title_block_c *
  *
#CELL
  pure_quanta socket4677_azif0045p001c01cs *
  page35_i102
#ISCELL
  logical_power universal_gnd *
  page35_i104
#ISCELL
  pure_quanta quanta_title_block_c *
  *
#CELL
  pure_quanta socket4677_azif0045p001c01cs *
  page36_i1
#ISCELL
  logical_power vcc_core *
  page36_i2
#ISCELL
  logical_power vcc_core *
  page36_i3
#ISCELL
  logical_power vcc_core *
  page36_i5
#ISCELL
  logical_power vcc_core *
  page36_i6
#CELL
  pure_quanta socket4677_azif0045p001c01cs *
  page36_i7
#ISCELL
  pure_quanta quanta_title_block_c *
  *
#ISCELL
  logical_power vcc_core *
  page37_i10
#ISCELL
  logical_power vcc_core *
  page37_i11
#ISCELL
  logical_power vcc_core *
  page37_i12
#ISCELL
  logical_power vcc_core *
  page37_i13
#ISCELL
  logical_power universal_gnd *
  page37_i14
#CELL
  pure_quanta q_cap *
  page37_i15
#ISCELL
  logical_power vcc_core *
  page37_i2
#ISCELL
  logical_power vcc_core *
  page37_i4
#ISCELL
  logical_power vcc_core *
  page37_i5
#ISCELL
  logical_power vcc_core *
  page37_i6
#CELL
  pure_quanta socket4677_azif0045p001c01cs *
  page37_i7
#CELL
  pure_quanta socket4677_azif0045p001c01cs *
  page37_i8
#ISCELL
  logical_power vcc_core *
  page37_i9
#ISCELL
  pure_quanta quanta_title_block_c *
  *
#ISCELL
  logical_power vcc_core *
  page38_i2
#CELL
  pure_quanta socket4677_azif0045p001c01cs *
  page38_i4
#ISCELL
  logical_power vcc_core *
  page38_i5
#ISCELL
  pure_quanta quanta_title_block_c *
  *
#CELL
  pure_quanta socket4677_azif0045p001c01cs *
  page39_i1
#CELL
  pure_quanta socket4677_azif0045p001c01cs *
  page39_i10
#ISCELL
  logical_power universal_gnd *
  page39_i2
#ISCELL
  logical_power universal_gnd *
  page39_i3
#ISCELL
  logical_power universal_gnd *
  page39_i5
#ISCELL
  logical_power universal_gnd *
  page39_i6
#ISCELL
  logical_power universal_gnd *
  page39_i7
#ISCELL
  logical_power universal_gnd *
  page39_i8
#CELL
  pure_quanta socket4677_azif0045p001c01cs *
  page39_i9
#ISCELL
  pure_quanta quanta_title_block_c *
  *
#ISCELL
  logical_power universal_gnd *
  page40_i1
#CELL
  pure_quanta socket4677_azif0045p001c01cs *
  page40_i10
#CELL
  pure_quanta socket4677_azif0045p001c01cs *
  page40_i11
#CELL
  pure_quanta socket4677_azif0045p001c01cs *
  page40_i12
#ISCELL
  logical_power universal_gnd *
  page40_i3
#ISCELL
  logical_power universal_gnd *
  page40_i4
#ISCELL
  logical_power universal_gnd *
  page40_i6
#ISCELL
  logical_power universal_gnd *
  page40_i7
#ISCELL
  logical_power universal_gnd *
  page40_i9
#ISCELL
  pure_quanta quanta_title_block_c *
  *
#ISCELL
  logical_power universal_gnd *
  page41_i1
#CELL
  pure_quanta socket4677_azif0045p001c01cs *
  page41_i10
#CELL
  pure_quanta socket4677_azif0045p001c01cs *
  page41_i11
#ISCELL
  logical_power universal_gnd *
  page41_i3
#ISCELL
  logical_power universal_gnd *
  page41_i4
#ISCELL
  logical_power universal_gnd *
  page41_i5
#ISCELL
  logical_power universal_gnd *
  page41_i6
#ISCELL
  logical_power universal_gnd *
  page41_i8
#CELL
  pure_quanta socket4677_azif0045p001c01cs *
  page41_i9
#ISCELL
  pure_quanta quanta_title_block_c *
  *
#ISCELL
  logical_power universal_gnd *
  page42_i1
#CELL
  pure_quanta socket4677_azif0045p001c01cs *
  page42_i10
#CELL
  pure_quanta socket4677_azif0045p001c01cs *
  page42_i11
#CELL
  pure_quanta socket4677_azif0045p001c01cs *
  page42_i12
#ISCELL
  logical_power universal_gnd *
  page42_i3
#ISCELL
  logical_power universal_gnd *
  page42_i4
#ISCELL
  logical_power universal_gnd *
  page42_i6
#ISCELL
  logical_power universal_gnd *
  page42_i7
#ISCELL
  pure_quanta quanta_title_block_c *
  *
#ISCELL
  standard offpage *
  page43_i1
#ISCELL
  standard offpage *
  page43_i10
#ISCELL
  standard offpage *
  page43_i11
#CELL
  pure_quanta q_res *
  page43_i12
#CELL
  pure_quanta q_res *
  page43_i13
#ISCELL
  standard offpage *
  page43_i14
#ISCELL
  standard offpage *
  page43_i15
#CELL
  pure_quanta q_res *
  page43_i16
#CELL
  pure_quanta q_res *
  page43_i17
#ISCELL
  standard offpage *
  page43_i2
#ISCELL
  logical_power universal_gnd *
  page43_i20
#ISCELL
  standard offpage *
  page43_i47
#CELL
  pure_quanta q_res *
  page43_i52
#ISCELL
  logical_power universal_gnd *
  page43_i54
#ISCELL
  standard offpage *
  page43_i55
#CELL
  pure_quanta q_res *
  page43_i56
#ISCELL
  mstr_misc dns *
  *
#ISCELL
  pure_quanta quanta_title_block_c *
  *
#ISCELL
  standard offpage *
  page44_i1
#CELL
  pure_quanta q_res *
  page44_i10
#CELL
  pure_quanta q_res *
  page44_i11
#ISCELL
  standard offpage *
  page44_i12
#ISCELL
  standard offpage *
  page44_i13
#ISCELL
  standard offpage *
  page44_i14
#ISCELL
  standard offpage *
  page44_i15
#CELL
  pure_quanta q_res *
  page44_i16
#ISCELL
  standard offpage *
  page44_i17
#ISCELL
  standard offpage *
  page44_i18
#ISCELL
  standard offpage *
  page44_i19
#ISCELL
  standard offpage *
  page44_i2
#ISCELL
  standard offpage *
  page44_i20
#ISCELL
  standard offpage *
  page44_i21
#ISCELL
  standard offpage *
  page44_i22
#ISCELL
  standard offpage *
  page44_i23
#ISCELL
  standard offpage *
  page44_i24
#ISCELL
  standard offpage *
  page44_i25
#ISCELL
  standard offpage *
  page44_i26
#ISCELL
  standard offpage *
  page44_i28
#ISCELL
  standard offpage *
  page44_i3
#ISCELL
  standard offpage *
  page44_i30
#ISCELL
  standard offpage *
  page44_i31
#ISCELL
  standard offpage *
  page44_i32
#ISCELL
  standard offpage *
  page44_i33
#ISCELL
  standard offpage *
  page44_i34
#ISCELL
  standard offpage *
  page44_i35
#ISCELL
  standard offpage *
  page44_i36
#ISCELL
  standard offpage *
  page44_i38
#ISCELL
  standard offpage *
  page44_i39
#ISCELL
  standard offpage *
  page44_i4
#ISCELL
  standard offpage *
  page44_i40
#ISCELL
  standard offpage *
  page44_i41
#ISCELL
  standard offpage *
  page44_i42
#ISCELL
  standard offpage *
  page44_i43
#ISCELL
  standard offpage *
  page44_i44
#ISCELL
  standard offpage *
  page44_i45
#ISCELL
  standard offpage *
  page44_i46
#ISCELL
  standard offpage *
  page44_i47
#ISCELL
  standard offpage *
  page44_i48
#ISCELL
  standard offpage *
  page44_i49
#ISCELL
  standard offpage *
  page44_i5
#ISCELL
  standard offpage *
  page44_i50
#CELL
  pure_quanta socket4677_azif0045p001c01cs *
  page44_i51
#ISCELL
  standard offpage *
  page44_i52
#ISCELL
  standard offpage *
  page44_i53
#ISCELL
  standard offpage *
  page44_i54
#CELL
  pure_quanta q_res *
  page44_i55
#ISCELL
  logical_power universal_gnd *
  page44_i56
#ISCELL
  standard offpage *
  page44_i57
#ISCELL
  standard offpage *
  page44_i58
#ISCELL
  standard offpage *
  page44_i6
#CELL
  pure_quanta q_res *
  page44_i7
#CELL
  pure_quanta q_res *
  page44_i8
#CELL
  pure_quanta q_res *
  page44_i9
#ISCELL
  pure_quanta quanta_title_block_c *
  *
#ISCELL
  standard offpage *
  page45_i1
#ISCELL
  standard offpage *
  page45_i10
#ISCELL
  standard offpage *
  page45_i11
#ISCELL
  standard offpage *
  page45_i13
#ISCELL
  standard offpage *
  page45_i14
#ISCELL
  standard offpage *
  page45_i16
#ISCELL
  standard offpage *
  page45_i17
#ISCELL
  standard offpage *
  page45_i18
#ISCELL
  standard offpage *
  page45_i19
#ISCELL
  standard offpage *
  page45_i20
#ISCELL
  standard offpage *
  page45_i21
#ISCELL
  standard offpage *
  page45_i22
#ISCELL
  standard offpage *
  page45_i23
#CELL
  pure_quanta socket4677_azif0045p001c01cs *
  page45_i29
#ISCELL
  standard offpage *
  page45_i32
#ISCELL
  standard offpage *
  page45_i33
#ISCELL
  standard offpage *
  page45_i38
#ISCELL
  standard offpage *
  page45_i39
#ISCELL
  standard offpage *
  page45_i41
#ISCELL
  standard offpage *
  page45_i42
#ISCELL
  standard offpage *
  page45_i43
#ISCELL
  standard offpage *
  page45_i44
#ISCELL
  standard offpage *
  page45_i45
#ISCELL
  standard offpage *
  page45_i46
#ISCELL
  standard offpage *
  page45_i47
#ISCELL
  standard offpage *
  page45_i48
#ISCELL
  standard offpage *
  page45_i49
#ISCELL
  standard offpage *
  page45_i50
#CELL
  pure_quanta q_res *
  page45_i51
#CELL
  pure_quanta q_res *
  page45_i52
#CELL
  pure_quanta q_res *
  page45_i53
#CELL
  pure_quanta q_res *
  page45_i54
#CELL
  pure_quanta q_res *
  page45_i55
#CELL
  pure_quanta q_res *
  page45_i56
#ISCELL
  standard offpage *
  page45_i57
#ISCELL
  standard offpage *
  page45_i58
#ISCELL
  standard offpage *
  page45_i59
#ISCELL
  standard offpage *
  page45_i60
#ISCELL
  standard offpage *
  page45_i61
#ISCELL
  standard offpage *
  page45_i62
#ISCELL
  standard offpage *
  page45_i67
#CELL
  pure_quanta q_res *
  page45_i69
#ISCELL
  standard offpage *
  page45_i7
#CELL
  pure_quanta q_res *
  page45_i70
#ISCELL
  standard offpage *
  page45_i71
#ISCELL
  standard offpage *
  page45_i72
#CELL
  pure_quanta q_res *
  page45_i73
#CELL
  pure_quanta q_res *
  page45_i74
#ISCELL
  logical_power universal_power *
  page45_i75
#ISCELL
  standard offpage *
  page45_i78
#ISCELL
  standard offpage *
  page45_i79
#ISCELL
  standard offpage *
  page45_i8
#CELL
  pure_quanta q_res *
  page45_i81
#CELL
  pure_quanta q_res *
  page45_i82
#ISCELL
  standard offpage *
  page45_i83
#ISCELL
  standard offpage *
  page45_i9
#ISCELL
  pure_quanta quanta_title_block_c *
  *
#ISCELL
  standard offpage *
  page46_i1
#ISCELL
  standard offpage *
  page46_i10
#ISCELL
  standard offpage *
  page46_i11
#ISCELL
  standard offpage *
  page46_i12
#ISCELL
  standard offpage *
  page46_i13
#ISCELL
  standard offpage *
  page46_i14
#ISCELL
  standard offpage *
  page46_i15
#ISCELL
  standard offpage *
  page46_i16
#ISCELL
  standard offpage *
  page46_i17
#ISCELL
  standard offpage *
  page46_i18
#ISCELL
  standard offpage *
  page46_i2
#ISCELL
  standard offpage *
  page46_i26
#ISCELL
  standard offpage *
  page46_i37
#ISCELL
  standard offpage *
  page46_i4
#CELL
  pure_quanta socket4677_azif0045p001c01cs *
  page46_i5
#ISCELL
  pure_quanta quanta_title_block_c *
  *
#ISCELL
  standard offpage *
  page47_i1
#ISCELL
  standard offpage *
  page47_i10
#ISCELL
  standard offpage *
  page47_i11
#CELL
  pure_quanta socket4677_azif0045p001c01cs *
  page47_i16
#ISCELL
  standard offpage *
  page47_i2
#CELL
  pure_quanta q_res *
  page47_i22
#CELL
  pure_quanta q_res *
  page47_i23
#CELL
  pure_quanta q_res *
  page47_i24
#CELL
  pure_quanta q_res *
  page47_i25
#ISCELL
  standard offpage *
  page47_i26
#ISCELL
  standard offpage *
  page47_i3
#ISCELL
  standard offpage *
  page47_i30
#ISCELL
  standard offpage *
  page47_i31
#ISCELL
  standard offpage *
  page47_i32
#ISCELL
  standard offpage *
  page47_i33
#CELL
  pure_quanta q_res *
  page47_i34
#CELL
  pure_quanta q_res *
  page47_i35
#ISCELL
  logical_power universal_power *
  page47_i36
#ISCELL
  standard offpage *
  page47_i4
#ISCELL
  standard offpage *
  page47_i5
#ISCELL
  standard offpage *
  page47_i6
#ISCELL
  standard offpage *
  page47_i7
#ISCELL
  standard offpage *
  page47_i8
#ISCELL
  standard offpage *
  page47_i9
#ISCELL
  pure_quanta quanta_title_block_c *
  *
#CELL
  pure_quanta socket4677_azif0045p001c01cs *
  page48_i1
#ISCELL
  pure_quanta quanta_title_block_c *
  *
#CELL
  pure_quanta socket4677_azif0045p001c01cs *
  page49_i2
#ISCELL
  pure_quanta quanta_title_block_c *
  *
#ISCELL
  standard offpage *
  page50_i19
#ISCELL
  standard offpage *
  page50_i20
#ISCELL
  standard offpage *
  page50_i21
#ISCELL
  standard offpage *
  page50_i22
#CELL
  pure_quanta socket4677_azif0045p001c01cs *
  page50_i23
#ISCELL
  pure_quanta quanta_title_block_c *
  *
#ISCELL
  standard tap *
  page51_i1
#ISCELL
  standard tap *
  page51_i10
#ISCELL
  standard tap *
  page51_i100
#ISCELL
  standard tap *
  page51_i101
#ISCELL
  standard tap *
  page51_i102
#ISCELL
  standard tap *
  page51_i103
#ISCELL
  standard tap *
  page51_i104
#ISCELL
  standard tap *
  page51_i105
#ISCELL
  standard tap *
  page51_i106
#ISCELL
  standard tap *
  page51_i107
#ISCELL
  standard tap *
  page51_i108
#ISCELL
  standard tap *
  page51_i109
#ISCELL
  standard tap *
  page51_i11
#ISCELL
  standard tap *
  page51_i110
#ISCELL
  standard tap *
  page51_i111
#ISCELL
  standard tap *
  page51_i112
#ISCELL
  standard tap *
  page51_i113
#ISCELL
  standard tap *
  page51_i114
#ISCELL
  standard offpage *
  page51_i115
#ISCELL
  standard offpage *
  page51_i116
#ISCELL
  standard offpage *
  page51_i117
#ISCELL
  standard offpage *
  page51_i118
#ISCELL
  standard offpage *
  page51_i119
#ISCELL
  standard tap *
  page51_i12
#ISCELL
  standard offpage *
  page51_i120
#ISCELL
  standard offpage *
  page51_i121
#ISCELL
  standard offpage *
  page51_i122
#ISCELL
  standard offpage *
  page51_i123
#ISCELL
  standard offpage *
  page51_i124
#ISCELL
  standard tap *
  page51_i125
#ISCELL
  standard tap *
  page51_i126
#ISCELL
  standard tap *
  page51_i127
#ISCELL
  standard tap *
  page51_i128
#ISCELL
  standard tap *
  page51_i129
#ISCELL
  standard tap *
  page51_i13
#ISCELL
  standard tap *
  page51_i130
#ISCELL
  standard tap *
  page51_i131
#ISCELL
  standard tap *
  page51_i132
#ISCELL
  standard tap *
  page51_i133
#ISCELL
  standard tap *
  page51_i134
#ISCELL
  standard tap *
  page51_i135
#ISCELL
  standard tap *
  page51_i136
#ISCELL
  standard tap *
  page51_i137
#ISCELL
  standard tap *
  page51_i138
#ISCELL
  standard tap *
  page51_i139
#ISCELL
  standard tap *
  page51_i14
#ISCELL
  standard tap *
  page51_i140
#ISCELL
  standard tap *
  page51_i141
#ISCELL
  standard tap *
  page51_i142
#ISCELL
  standard tap *
  page51_i143
#ISCELL
  standard tap *
  page51_i144
#ISCELL
  standard tap *
  page51_i145
#ISCELL
  standard tap *
  page51_i146
#ISCELL
  standard tap *
  page51_i147
#ISCELL
  standard tap *
  page51_i148
#ISCELL
  standard tap *
  page51_i149
#ISCELL
  standard tap *
  page51_i15
#ISCELL
  standard tap *
  page51_i150
#ISCELL
  standard tap *
  page51_i151
#ISCELL
  standard tap *
  page51_i152
#ISCELL
  standard tap *
  page51_i153
#ISCELL
  standard tap *
  page51_i154
#ISCELL
  standard tap *
  page51_i155
#ISCELL
  standard tap *
  page51_i156
#ISCELL
  standard tap *
  page51_i157
#ISCELL
  standard tap *
  page51_i158
#ISCELL
  standard tap *
  page51_i159
#ISCELL
  standard tap *
  page51_i16
#ISCELL
  standard tap *
  page51_i160
#ISCELL
  standard tap *
  page51_i161
#ISCELL
  standard offpage *
  page51_i162
#ISCELL
  standard offpage *
  page51_i163
#ISCELL
  standard offpage *
  page51_i164
#ISCELL
  standard tap *
  page51_i165
#ISCELL
  standard tap *
  page51_i166
#ISCELL
  standard tap *
  page51_i167
#ISCELL
  standard offpage *
  page51_i168
#ISCELL
  standard tap *
  page51_i17
#ISCELL
  standard tap *
  page51_i18
#ISCELL
  standard tap *
  page51_i19
#CELL
  pure_quanta socket4677_azif0045p001c01cs *
  page51_i2
#ISCELL
  standard tap *
  page51_i20
#ISCELL
  standard tap *
  page51_i21
#ISCELL
  standard tap *
  page51_i22
#ISCELL
  standard tap *
  page51_i23
#ISCELL
  standard tap *
  page51_i24
#ISCELL
  standard tap *
  page51_i25
#ISCELL
  standard tap *
  page51_i26
#ISCELL
  standard tap *
  page51_i27
#ISCELL
  standard tap *
  page51_i28
#ISCELL
  standard tap *
  page51_i29
#ISCELL
  standard offpage *
  page51_i3
#ISCELL
  standard tap *
  page51_i30
#ISCELL
  standard tap *
  page51_i31
#ISCELL
  standard tap *
  page51_i32
#ISCELL
  standard tap *
  page51_i33
#ISCELL
  standard tap *
  page51_i34
#ISCELL
  standard tap *
  page51_i35
#ISCELL
  standard tap *
  page51_i36
#ISCELL
  standard tap *
  page51_i37
#ISCELL
  standard tap *
  page51_i38
#ISCELL
  standard tap *
  page51_i39
#ISCELL
  standard offpage *
  page51_i4
#ISCELL
  standard tap *
  page51_i40
#ISCELL
  standard tap *
  page51_i41
#ISCELL
  standard tap *
  page51_i42
#ISCELL
  standard tap *
  page51_i43
#ISCELL
  standard tap *
  page51_i44
#ISCELL
  standard offpage *
  page51_i45
#ISCELL
  standard offpage *
  page51_i46
#ISCELL
  standard tap *
  page51_i47
#ISCELL
  standard tap *
  page51_i48
#ISCELL
  standard tap *
  page51_i49
#ISCELL
  standard offpage *
  page51_i5
#ISCELL
  standard tap *
  page51_i50
#ISCELL
  standard tap *
  page51_i51
#ISCELL
  standard tap *
  page51_i52
#ISCELL
  standard tap *
  page51_i53
#ISCELL
  standard tap *
  page51_i54
#ISCELL
  standard tap *
  page51_i55
#ISCELL
  standard tap *
  page51_i56
#ISCELL
  standard tap *
  page51_i57
#ISCELL
  standard tap *
  page51_i58
#ISCELL
  standard tap *
  page51_i59
#ISCELL
  standard tap *
  page51_i6
#ISCELL
  standard tap *
  page51_i60
#ISCELL
  standard tap *
  page51_i61
#ISCELL
  standard tap *
  page51_i62
#ISCELL
  standard tap *
  page51_i63
#ISCELL
  standard tap *
  page51_i64
#ISCELL
  standard tap *
  page51_i65
#ISCELL
  standard tap *
  page51_i66
#ISCELL
  standard tap *
  page51_i67
#ISCELL
  standard tap *
  page51_i68
#ISCELL
  standard tap *
  page51_i69
#ISCELL
  standard tap *
  page51_i7
#ISCELL
  standard tap *
  page51_i70
#ISCELL
  standard tap *
  page51_i71
#ISCELL
  standard tap *
  page51_i72
#ISCELL
  standard tap *
  page51_i73
#ISCELL
  standard tap *
  page51_i74
#ISCELL
  standard tap *
  page51_i75
#ISCELL
  standard tap *
  page51_i76
#ISCELL
  standard tap *
  page51_i77
#ISCELL
  standard tap *
  page51_i78
#ISCELL
  standard tap *
  page51_i79
#ISCELL
  standard tap *
  page51_i8
#ISCELL
  standard tap *
  page51_i80
#ISCELL
  standard tap *
  page51_i81
#ISCELL
  standard tap *
  page51_i82
#ISCELL
  standard tap *
  page51_i83
#ISCELL
  standard tap *
  page51_i84
#ISCELL
  standard tap *
  page51_i85
#ISCELL
  standard tap *
  page51_i86
#ISCELL
  standard tap *
  page51_i87
#ISCELL
  standard offpage *
  page51_i88
#ISCELL
  standard tap *
  page51_i89
#ISCELL
  standard tap *
  page51_i9
#ISCELL
  standard tap *
  page51_i90
#ISCELL
  standard tap *
  page51_i91
#ISCELL
  standard offpage *
  page51_i92
#ISCELL
  standard tap *
  page51_i93
#ISCELL
  standard tap *
  page51_i94
#ISCELL
  standard tap *
  page51_i95
#ISCELL
  standard tap *
  page51_i96
#ISCELL
  standard tap *
  page51_i97
#ISCELL
  standard tap *
  page51_i98
#ISCELL
  standard tap *
  page51_i99
#ISCELL
  pure_quanta quanta_title_block_c *
  *
#ISCELL
  standard offpage *
  page52_i1
#ISCELL
  standard tap *
  page52_i10
#ISCELL
  standard tap *
  page52_i100
#ISCELL
  standard tap *
  page52_i101
#ISCELL
  standard tap *
  page52_i102
#ISCELL
  standard tap *
  page52_i103
#ISCELL
  standard tap *
  page52_i104
#ISCELL
  standard tap *
  page52_i105
#ISCELL
  standard tap *
  page52_i106
#ISCELL
  standard tap *
  page52_i107
#ISCELL
  standard tap *
  page52_i108
#ISCELL
  standard tap *
  page52_i109
#ISCELL
  standard tap *
  page52_i11
#ISCELL
  standard tap *
  page52_i110
#ISCELL
  standard tap *
  page52_i111
#ISCELL
  standard tap *
  page52_i112
#ISCELL
  standard tap *
  page52_i113
#ISCELL
  standard tap *
  page52_i114
#ISCELL
  standard tap *
  page52_i115
#ISCELL
  standard tap *
  page52_i116
#ISCELL
  standard tap *
  page52_i117
#ISCELL
  standard tap *
  page52_i118
#ISCELL
  standard tap *
  page52_i119
#ISCELL
  standard tap *
  page52_i12
#ISCELL
  standard tap *
  page52_i120
#ISCELL
  standard tap *
  page52_i121
#ISCELL
  standard tap *
  page52_i122
#ISCELL
  standard tap *
  page52_i123
#ISCELL
  standard tap *
  page52_i124
#ISCELL
  standard tap *
  page52_i125
#ISCELL
  standard tap *
  page52_i126
#ISCELL
  standard tap *
  page52_i127
#ISCELL
  standard tap *
  page52_i128
#ISCELL
  standard tap *
  page52_i129
#ISCELL
  standard tap *
  page52_i13
#ISCELL
  standard tap *
  page52_i130
#ISCELL
  standard tap *
  page52_i131
#ISCELL
  standard tap *
  page52_i132
#ISCELL
  standard tap *
  page52_i133
#ISCELL
  standard tap *
  page52_i134
#ISCELL
  standard tap *
  page52_i135
#ISCELL
  standard tap *
  page52_i136
#ISCELL
  standard tap *
  page52_i137
#ISCELL
  standard tap *
  page52_i138
#ISCELL
  standard tap *
  page52_i139
#ISCELL
  standard tap *
  page52_i14
#ISCELL
  standard tap *
  page52_i140
#ISCELL
  standard tap *
  page52_i141
#ISCELL
  standard tap *
  page52_i142
#ISCELL
  standard tap *
  page52_i143
#ISCELL
  standard tap *
  page52_i144
#ISCELL
  standard tap *
  page52_i145
#ISCELL
  standard tap *
  page52_i146
#ISCELL
  standard tap *
  page52_i147
#ISCELL
  standard tap *
  page52_i148
#ISCELL
  standard tap *
  page52_i149
#ISCELL
  standard tap *
  page52_i15
#ISCELL
  standard tap *
  page52_i150
#ISCELL
  standard tap *
  page52_i151
#ISCELL
  standard tap *
  page52_i152
#ISCELL
  standard tap *
  page52_i153
#ISCELL
  standard tap *
  page52_i154
#ISCELL
  standard tap *
  page52_i155
#ISCELL
  standard tap *
  page52_i156
#ISCELL
  standard tap *
  page52_i157
#ISCELL
  standard offpage *
  page52_i158
#ISCELL
  standard offpage *
  page52_i159
#ISCELL
  standard tap *
  page52_i16
#ISCELL
  standard offpage *
  page52_i160
#ISCELL
  standard offpage *
  page52_i161
#ISCELL
  standard offpage *
  page52_i162
#ISCELL
  standard offpage *
  page52_i163
#ISCELL
  standard offpage *
  page52_i164
#ISCELL
  standard offpage *
  page52_i165
#ISCELL
  standard offpage *
  page52_i166
#ISCELL
  standard offpage *
  page52_i167
#ISCELL
  standard offpage *
  page52_i168
#ISCELL
  standard tap *
  page52_i17
#ISCELL
  standard tap *
  page52_i18
#ISCELL
  standard tap *
  page52_i19
#ISCELL
  standard offpage *
  page52_i2
#ISCELL
  standard tap *
  page52_i20
#ISCELL
  standard tap *
  page52_i21
#ISCELL
  standard tap *
  page52_i22
#ISCELL
  standard tap *
  page52_i23
#ISCELL
  standard tap *
  page52_i24
#ISCELL
  standard tap *
  page52_i25
#ISCELL
  standard tap *
  page52_i26
#ISCELL
  standard tap *
  page52_i27
#ISCELL
  standard tap *
  page52_i28
#ISCELL
  standard tap *
  page52_i29
#ISCELL
  standard tap *
  page52_i3
#ISCELL
  standard tap *
  page52_i30
#ISCELL
  standard tap *
  page52_i31
#ISCELL
  standard tap *
  page52_i32
#ISCELL
  standard tap *
  page52_i33
#ISCELL
  standard tap *
  page52_i34
#ISCELL
  standard tap *
  page52_i35
#ISCELL
  standard tap *
  page52_i36
#ISCELL
  standard tap *
  page52_i37
#ISCELL
  standard tap *
  page52_i38
#ISCELL
  standard tap *
  page52_i39
#ISCELL
  standard tap *
  page52_i4
#ISCELL
  standard tap *
  page52_i40
#ISCELL
  standard tap *
  page52_i41
#ISCELL
  standard tap *
  page52_i42
#ISCELL
  standard tap *
  page52_i43
#ISCELL
  standard tap *
  page52_i44
#ISCELL
  standard tap *
  page52_i45
#ISCELL
  standard tap *
  page52_i46
#ISCELL
  standard tap *
  page52_i47
#ISCELL
  standard tap *
  page52_i48
#ISCELL
  standard tap *
  page52_i49
#ISCELL
  standard tap *
  page52_i5
#ISCELL
  standard offpage *
  page52_i50
#ISCELL
  standard offpage *
  page52_i51
#ISCELL
  standard tap *
  page52_i52
#ISCELL
  standard tap *
  page52_i53
#ISCELL
  standard tap *
  page52_i54
#ISCELL
  standard tap *
  page52_i55
#ISCELL
  standard tap *
  page52_i56
#ISCELL
  standard tap *
  page52_i57
#ISCELL
  standard tap *
  page52_i58
#ISCELL
  standard tap *
  page52_i59
#ISCELL
  standard tap *
  page52_i6
#ISCELL
  standard tap *
  page52_i60
#ISCELL
  standard tap *
  page52_i61
#ISCELL
  standard tap *
  page52_i62
#ISCELL
  standard tap *
  page52_i63
#ISCELL
  standard tap *
  page52_i64
#ISCELL
  standard tap *
  page52_i65
#ISCELL
  standard tap *
  page52_i66
#ISCELL
  standard tap *
  page52_i67
#ISCELL
  standard tap *
  page52_i68
#ISCELL
  standard tap *
  page52_i69
#ISCELL
  standard offpage *
  page52_i7
#ISCELL
  standard tap *
  page52_i70
#ISCELL
  standard tap *
  page52_i71
#ISCELL
  standard tap *
  page52_i72
#ISCELL
  standard tap *
  page52_i73
#ISCELL
  standard tap *
  page52_i74
#ISCELL
  standard tap *
  page52_i75
#ISCELL
  standard tap *
  page52_i76
#ISCELL
  standard tap *
  page52_i77
#ISCELL
  standard tap *
  page52_i78
#ISCELL
  standard tap *
  page52_i79
#ISCELL
  standard offpage *
  page52_i8
#ISCELL
  standard tap *
  page52_i80
#ISCELL
  standard tap *
  page52_i81
#ISCELL
  standard tap *
  page52_i82
#ISCELL
  standard tap *
  page52_i83
#ISCELL
  standard tap *
  page52_i84
#ISCELL
  standard tap *
  page52_i85
#ISCELL
  standard tap *
  page52_i86
#ISCELL
  standard tap *
  page52_i87
#ISCELL
  standard tap *
  page52_i88
#ISCELL
  standard tap *
  page52_i89
#ISCELL
  standard tap *
  page52_i9
#ISCELL
  standard tap *
  page52_i90
#CELL
  pure_quanta socket4677_azif0045p001c01cs *
  page52_i91
#ISCELL
  standard offpage *
  page52_i92
#ISCELL
  standard offpage *
  page52_i93
#ISCELL
  standard offpage *
  page52_i94
#ISCELL
  standard offpage *
  page52_i95
#ISCELL
  standard tap *
  page52_i96
#ISCELL
  standard tap *
  page52_i97
#ISCELL
  standard tap *
  page52_i98
#ISCELL
  standard tap *
  page52_i99
#ISCELL
  pure_quanta quanta_title_block_c *
  *
#ISCELL
  standard offpage *
  page53_i1
#ISCELL
  standard tap *
  page53_i10
#ISCELL
  standard tap *
  page53_i100
#ISCELL
  standard tap *
  page53_i101
#ISCELL
  standard tap *
  page53_i102
#ISCELL
  standard tap *
  page53_i103
#ISCELL
  standard tap *
  page53_i104
#ISCELL
  standard tap *
  page53_i105
#ISCELL
  standard tap *
  page53_i106
#ISCELL
  standard tap *
  page53_i107
#ISCELL
  standard tap *
  page53_i108
#ISCELL
  standard tap *
  page53_i109
#ISCELL
  standard tap *
  page53_i11
#ISCELL
  standard tap *
  page53_i110
#ISCELL
  standard tap *
  page53_i111
#ISCELL
  standard tap *
  page53_i112
#ISCELL
  standard tap *
  page53_i113
#ISCELL
  standard tap *
  page53_i114
#ISCELL
  standard tap *
  page53_i115
#ISCELL
  standard tap *
  page53_i116
#ISCELL
  standard tap *
  page53_i117
#ISCELL
  standard tap *
  page53_i118
#ISCELL
  standard tap *
  page53_i119
#ISCELL
  standard tap *
  page53_i12
#ISCELL
  standard tap *
  page53_i120
#ISCELL
  standard tap *
  page53_i121
#ISCELL
  standard tap *
  page53_i122
#ISCELL
  standard tap *
  page53_i123
#ISCELL
  standard tap *
  page53_i124
#ISCELL
  standard tap *
  page53_i125
#ISCELL
  standard tap *
  page53_i126
#ISCELL
  standard tap *
  page53_i127
#ISCELL
  standard tap *
  page53_i128
#ISCELL
  standard tap *
  page53_i129
#ISCELL
  standard tap *
  page53_i13
#ISCELL
  standard tap *
  page53_i130
#ISCELL
  standard tap *
  page53_i131
#ISCELL
  standard tap *
  page53_i132
#ISCELL
  standard tap *
  page53_i133
#ISCELL
  standard tap *
  page53_i134
#ISCELL
  standard tap *
  page53_i135
#ISCELL
  standard tap *
  page53_i136
#ISCELL
  standard tap *
  page53_i137
#ISCELL
  standard tap *
  page53_i138
#ISCELL
  standard tap *
  page53_i139
#ISCELL
  standard offpage *
  page53_i14
#ISCELL
  standard tap *
  page53_i140
#ISCELL
  standard tap *
  page53_i141
#ISCELL
  standard tap *
  page53_i142
#ISCELL
  standard tap *
  page53_i143
#ISCELL
  standard tap *
  page53_i144
#ISCELL
  standard tap *
  page53_i145
#ISCELL
  standard tap *
  page53_i146
#ISCELL
  standard tap *
  page53_i147
#ISCELL
  standard tap *
  page53_i148
#ISCELL
  standard tap *
  page53_i149
#ISCELL
  standard offpage *
  page53_i15
#ISCELL
  standard tap *
  page53_i150
#ISCELL
  standard tap *
  page53_i151
#ISCELL
  standard tap *
  page53_i152
#ISCELL
  standard tap *
  page53_i153
#ISCELL
  standard tap *
  page53_i154
#ISCELL
  standard tap *
  page53_i155
#ISCELL
  standard tap *
  page53_i156
#ISCELL
  standard tap *
  page53_i157
#ISCELL
  standard tap *
  page53_i158
#ISCELL
  standard offpage *
  page53_i159
#ISCELL
  standard offpage *
  page53_i16
#ISCELL
  standard offpage *
  page53_i160
#ISCELL
  standard offpage *
  page53_i161
#ISCELL
  standard offpage *
  page53_i162
#ISCELL
  standard offpage *
  page53_i163
#ISCELL
  standard offpage *
  page53_i164
#ISCELL
  standard offpage *
  page53_i165
#ISCELL
  standard offpage *
  page53_i166
#ISCELL
  standard offpage *
  page53_i167
#ISCELL
  standard offpage *
  page53_i168
#ISCELL
  standard tap *
  page53_i17
#ISCELL
  standard tap *
  page53_i18
#ISCELL
  standard tap *
  page53_i19
#ISCELL
  standard offpage *
  page53_i2
#ISCELL
  standard tap *
  page53_i20
#ISCELL
  standard tap *
  page53_i21
#ISCELL
  standard tap *
  page53_i22
#ISCELL
  standard tap *
  page53_i23
#ISCELL
  standard tap *
  page53_i24
#ISCELL
  standard tap *
  page53_i25
#ISCELL
  standard tap *
  page53_i26
#ISCELL
  standard tap *
  page53_i27
#ISCELL
  standard tap *
  page53_i28
#ISCELL
  standard tap *
  page53_i29
#ISCELL
  standard tap *
  page53_i3
#ISCELL
  standard tap *
  page53_i30
#ISCELL
  standard tap *
  page53_i31
#ISCELL
  standard tap *
  page53_i32
#ISCELL
  standard tap *
  page53_i33
#ISCELL
  standard tap *
  page53_i34
#ISCELL
  standard tap *
  page53_i35
#ISCELL
  standard tap *
  page53_i36
#ISCELL
  standard tap *
  page53_i37
#ISCELL
  standard tap *
  page53_i38
#ISCELL
  standard tap *
  page53_i39
#ISCELL
  standard tap *
  page53_i4
#ISCELL
  standard tap *
  page53_i40
#ISCELL
  standard tap *
  page53_i41
#ISCELL
  standard tap *
  page53_i42
#ISCELL
  standard tap *
  page53_i43
#ISCELL
  standard tap *
  page53_i44
#ISCELL
  standard tap *
  page53_i45
#ISCELL
  standard tap *
  page53_i46
#ISCELL
  standard tap *
  page53_i47
#ISCELL
  standard tap *
  page53_i48
#ISCELL
  standard tap *
  page53_i49
#ISCELL
  standard tap *
  page53_i5
#ISCELL
  standard tap *
  page53_i50
#ISCELL
  standard tap *
  page53_i51
#ISCELL
  standard tap *
  page53_i52
#ISCELL
  standard tap *
  page53_i53
#ISCELL
  standard tap *
  page53_i54
#ISCELL
  standard tap *
  page53_i55
#ISCELL
  standard tap *
  page53_i56
#ISCELL
  standard offpage *
  page53_i57
#ISCELL
  standard tap *
  page53_i58
#ISCELL
  standard tap *
  page53_i59
#ISCELL
  standard tap *
  page53_i6
#ISCELL
  standard tap *
  page53_i60
#ISCELL
  standard tap *
  page53_i61
#ISCELL
  standard tap *
  page53_i62
#ISCELL
  standard tap *
  page53_i63
#ISCELL
  standard tap *
  page53_i64
#ISCELL
  standard tap *
  page53_i65
#ISCELL
  standard tap *
  page53_i66
#ISCELL
  standard tap *
  page53_i67
#ISCELL
  standard tap *
  page53_i68
#ISCELL
  standard tap *
  page53_i69
#ISCELL
  standard tap *
  page53_i7
#ISCELL
  standard tap *
  page53_i70
#ISCELL
  standard tap *
  page53_i71
#ISCELL
  standard tap *
  page53_i72
#ISCELL
  standard tap *
  page53_i73
#ISCELL
  standard tap *
  page53_i74
#ISCELL
  standard tap *
  page53_i75
#ISCELL
  standard tap *
  page53_i76
#ISCELL
  standard tap *
  page53_i77
#ISCELL
  standard tap *
  page53_i78
#ISCELL
  standard tap *
  page53_i79
#ISCELL
  standard tap *
  page53_i8
#ISCELL
  standard tap *
  page53_i80
#ISCELL
  standard tap *
  page53_i81
#ISCELL
  standard tap *
  page53_i82
#ISCELL
  standard tap *
  page53_i83
#ISCELL
  standard tap *
  page53_i84
#ISCELL
  standard tap *
  page53_i85
#ISCELL
  standard tap *
  page53_i86
#ISCELL
  standard tap *
  page53_i87
#ISCELL
  standard tap *
  page53_i88
#ISCELL
  standard tap *
  page53_i89
#ISCELL
  standard tap *
  page53_i9
#ISCELL
  standard tap *
  page53_i90
#CELL
  pure_quanta socket4677_azif0045p001c01cs *
  page53_i91
#ISCELL
  standard tap *
  page53_i92
#ISCELL
  standard tap *
  page53_i93
#ISCELL
  standard tap *
  page53_i94
#ISCELL
  standard offpage *
  page53_i95
#ISCELL
  standard offpage *
  page53_i96
#ISCELL
  standard offpage *
  page53_i97
#ISCELL
  standard offpage *
  page53_i98
#ISCELL
  standard offpage *
  page53_i99
#ISCELL
  pure_quanta quanta_title_block_c *
  *
#ISCELL
  standard offpage *
  page54_i1
#ISCELL
  standard offpage *
  page54_i10
#ISCELL
  standard tap *
  page54_i100
#ISCELL
  standard tap *
  page54_i101
#ISCELL
  standard tap *
  page54_i102
#ISCELL
  standard tap *
  page54_i103
#ISCELL
  standard tap *
  page54_i104
#ISCELL
  standard tap *
  page54_i105
#ISCELL
  standard tap *
  page54_i106
#ISCELL
  standard tap *
  page54_i107
#ISCELL
  standard tap *
  page54_i108
#ISCELL
  standard tap *
  page54_i109
#ISCELL
  standard tap *
  page54_i11
#ISCELL
  standard tap *
  page54_i110
#ISCELL
  standard tap *
  page54_i111
#ISCELL
  standard tap *
  page54_i112
#ISCELL
  standard tap *
  page54_i113
#ISCELL
  standard tap *
  page54_i114
#ISCELL
  standard tap *
  page54_i115
#ISCELL
  standard tap *
  page54_i116
#ISCELL
  standard tap *
  page54_i117
#ISCELL
  standard tap *
  page54_i118
#ISCELL
  standard tap *
  page54_i119
#ISCELL
  standard tap *
  page54_i12
#ISCELL
  standard tap *
  page54_i120
#ISCELL
  standard tap *
  page54_i121
#ISCELL
  standard tap *
  page54_i122
#ISCELL
  standard tap *
  page54_i123
#ISCELL
  standard tap *
  page54_i124
#ISCELL
  standard tap *
  page54_i125
#ISCELL
  standard tap *
  page54_i126
#ISCELL
  standard tap *
  page54_i127
#ISCELL
  standard tap *
  page54_i128
#ISCELL
  standard tap *
  page54_i129
#ISCELL
  standard tap *
  page54_i13
#ISCELL
  standard tap *
  page54_i130
#ISCELL
  standard tap *
  page54_i131
#ISCELL
  standard tap *
  page54_i132
#ISCELL
  standard tap *
  page54_i133
#ISCELL
  standard tap *
  page54_i134
#ISCELL
  standard tap *
  page54_i135
#ISCELL
  standard tap *
  page54_i136
#ISCELL
  standard tap *
  page54_i137
#ISCELL
  standard tap *
  page54_i138
#ISCELL
  standard tap *
  page54_i139
#ISCELL
  standard tap *
  page54_i14
#ISCELL
  standard tap *
  page54_i140
#ISCELL
  standard tap *
  page54_i141
#ISCELL
  standard tap *
  page54_i142
#ISCELL
  standard tap *
  page54_i143
#ISCELL
  standard tap *
  page54_i144
#ISCELL
  standard tap *
  page54_i145
#ISCELL
  standard tap *
  page54_i146
#ISCELL
  standard tap *
  page54_i147
#ISCELL
  standard tap *
  page54_i148
#ISCELL
  standard tap *
  page54_i149
#ISCELL
  standard tap *
  page54_i15
#ISCELL
  standard tap *
  page54_i150
#ISCELL
  standard tap *
  page54_i151
#ISCELL
  standard tap *
  page54_i152
#ISCELL
  standard tap *
  page54_i153
#ISCELL
  standard tap *
  page54_i154
#ISCELL
  standard tap *
  page54_i155
#ISCELL
  standard tap *
  page54_i156
#ISCELL
  standard tap *
  page54_i157
#ISCELL
  standard tap *
  page54_i158
#ISCELL
  standard offpage *
  page54_i159
#ISCELL
  standard tap *
  page54_i16
#ISCELL
  standard offpage *
  page54_i160
#ISCELL
  standard offpage *
  page54_i161
#ISCELL
  standard offpage *
  page54_i162
#ISCELL
  standard offpage *
  page54_i163
#ISCELL
  standard offpage *
  page54_i164
#ISCELL
  standard offpage *
  page54_i165
#ISCELL
  standard offpage *
  page54_i166
#ISCELL
  standard offpage *
  page54_i167
#ISCELL
  standard offpage *
  page54_i168
#ISCELL
  standard tap *
  page54_i17
#ISCELL
  standard tap *
  page54_i18
#ISCELL
  standard tap *
  page54_i19
#ISCELL
  standard offpage *
  page54_i2
#ISCELL
  standard tap *
  page54_i20
#ISCELL
  standard tap *
  page54_i21
#ISCELL
  standard tap *
  page54_i22
#ISCELL
  standard tap *
  page54_i23
#ISCELL
  standard tap *
  page54_i24
#ISCELL
  standard tap *
  page54_i25
#ISCELL
  standard tap *
  page54_i26
#ISCELL
  standard tap *
  page54_i27
#ISCELL
  standard tap *
  page54_i28
#ISCELL
  standard tap *
  page54_i29
#ISCELL
  standard tap *
  page54_i3
#ISCELL
  standard tap *
  page54_i30
#ISCELL
  standard tap *
  page54_i31
#ISCELL
  standard tap *
  page54_i32
#ISCELL
  standard tap *
  page54_i33
#ISCELL
  standard tap *
  page54_i34
#ISCELL
  standard tap *
  page54_i35
#ISCELL
  standard tap *
  page54_i36
#ISCELL
  standard tap *
  page54_i37
#ISCELL
  standard tap *
  page54_i38
#ISCELL
  standard tap *
  page54_i39
#ISCELL
  standard tap *
  page54_i4
#ISCELL
  standard tap *
  page54_i40
#ISCELL
  standard tap *
  page54_i41
#ISCELL
  standard tap *
  page54_i42
#ISCELL
  standard tap *
  page54_i43
#ISCELL
  standard tap *
  page54_i44
#ISCELL
  standard tap *
  page54_i45
#ISCELL
  standard tap *
  page54_i46
#ISCELL
  standard tap *
  page54_i47
#ISCELL
  standard tap *
  page54_i48
#ISCELL
  standard tap *
  page54_i49
#ISCELL
  standard tap *
  page54_i5
#ISCELL
  standard tap *
  page54_i50
#ISCELL
  standard offpage *
  page54_i51
#ISCELL
  standard offpage *
  page54_i52
#ISCELL
  standard tap *
  page54_i53
#ISCELL
  standard tap *
  page54_i54
#ISCELL
  standard tap *
  page54_i55
#ISCELL
  standard tap *
  page54_i56
#ISCELL
  standard tap *
  page54_i57
#ISCELL
  standard tap *
  page54_i58
#ISCELL
  standard tap *
  page54_i59
#ISCELL
  standard tap *
  page54_i6
#ISCELL
  standard tap *
  page54_i60
#ISCELL
  standard tap *
  page54_i61
#ISCELL
  standard tap *
  page54_i62
#ISCELL
  standard tap *
  page54_i63
#ISCELL
  standard tap *
  page54_i64
#ISCELL
  standard tap *
  page54_i65
#ISCELL
  standard tap *
  page54_i66
#ISCELL
  standard tap *
  page54_i67
#ISCELL
  standard tap *
  page54_i68
#ISCELL
  standard tap *
  page54_i69
#ISCELL
  standard tap *
  page54_i7
#ISCELL
  standard tap *
  page54_i70
#ISCELL
  standard tap *
  page54_i71
#ISCELL
  standard tap *
  page54_i72
#ISCELL
  standard tap *
  page54_i73
#ISCELL
  standard tap *
  page54_i74
#ISCELL
  standard tap *
  page54_i75
#ISCELL
  standard tap *
  page54_i76
#ISCELL
  standard tap *
  page54_i77
#ISCELL
  standard tap *
  page54_i78
#ISCELL
  standard tap *
  page54_i79
#ISCELL
  standard tap *
  page54_i8
#ISCELL
  standard tap *
  page54_i80
#ISCELL
  standard tap *
  page54_i81
#ISCELL
  standard tap *
  page54_i82
#ISCELL
  standard tap *
  page54_i83
#ISCELL
  standard tap *
  page54_i84
#ISCELL
  standard tap *
  page54_i85
#ISCELL
  standard tap *
  page54_i86
#ISCELL
  standard tap *
  page54_i87
#ISCELL
  standard tap *
  page54_i88
#ISCELL
  standard tap *
  page54_i89
#ISCELL
  standard offpage *
  page54_i9
#ISCELL
  standard tap *
  page54_i90
#CELL
  pure_quanta socket4677_azif0045p001c01cs *
  page54_i91
#ISCELL
  standard offpage *
  page54_i92
#ISCELL
  standard offpage *
  page54_i93
#ISCELL
  standard offpage *
  page54_i94
#ISCELL
  standard offpage *
  page54_i95
#ISCELL
  standard offpage *
  page54_i96
#ISCELL
  standard tap *
  page54_i97
#ISCELL
  standard tap *
  page54_i98
#ISCELL
  standard tap *
  page54_i99
#ISCELL
  pure_quanta quanta_title_block_c *
  *
#ISCELL
  standard offpage *
  page55_i1
#ISCELL
  standard tap *
  page55_i10
#ISCELL
  standard tap *
  page55_i100
#ISCELL
  standard tap *
  page55_i101
#ISCELL
  standard tap *
  page55_i102
#ISCELL
  standard tap *
  page55_i103
#ISCELL
  standard tap *
  page55_i104
#ISCELL
  standard tap *
  page55_i105
#ISCELL
  standard tap *
  page55_i106
#ISCELL
  standard tap *
  page55_i107
#ISCELL
  standard tap *
  page55_i108
#ISCELL
  standard tap *
  page55_i109
#ISCELL
  standard tap *
  page55_i11
#ISCELL
  standard tap *
  page55_i110
#ISCELL
  standard tap *
  page55_i111
#ISCELL
  standard tap *
  page55_i112
#ISCELL
  standard tap *
  page55_i113
#ISCELL
  standard tap *
  page55_i114
#ISCELL
  standard tap *
  page55_i115
#ISCELL
  standard tap *
  page55_i116
#ISCELL
  standard tap *
  page55_i117
#ISCELL
  standard tap *
  page55_i118
#ISCELL
  standard tap *
  page55_i119
#ISCELL
  standard tap *
  page55_i12
#ISCELL
  standard tap *
  page55_i120
#ISCELL
  standard offpage *
  page55_i121
#ISCELL
  standard offpage *
  page55_i122
#ISCELL
  standard offpage *
  page55_i123
#ISCELL
  standard offpage *
  page55_i124
#ISCELL
  standard offpage *
  page55_i125
#ISCELL
  standard offpage *
  page55_i126
#ISCELL
  standard offpage *
  page55_i127
#ISCELL
  standard offpage *
  page55_i128
#ISCELL
  standard tap *
  page55_i129
#ISCELL
  standard tap *
  page55_i13
#ISCELL
  standard tap *
  page55_i130
#ISCELL
  standard tap *
  page55_i131
#ISCELL
  standard tap *
  page55_i132
#ISCELL
  standard tap *
  page55_i133
#ISCELL
  standard tap *
  page55_i134
#ISCELL
  standard tap *
  page55_i135
#ISCELL
  standard tap *
  page55_i136
#ISCELL
  standard tap *
  page55_i137
#ISCELL
  standard tap *
  page55_i138
#ISCELL
  standard tap *
  page55_i139
#ISCELL
  standard tap *
  page55_i14
#ISCELL
  standard tap *
  page55_i140
#ISCELL
  standard tap *
  page55_i141
#ISCELL
  standard tap *
  page55_i142
#ISCELL
  standard tap *
  page55_i143
#ISCELL
  standard tap *
  page55_i144
#ISCELL
  standard tap *
  page55_i145
#ISCELL
  standard tap *
  page55_i146
#ISCELL
  standard tap *
  page55_i147
#ISCELL
  standard tap *
  page55_i148
#ISCELL
  standard tap *
  page55_i149
#ISCELL
  standard tap *
  page55_i15
#ISCELL
  standard tap *
  page55_i150
#ISCELL
  standard tap *
  page55_i151
#ISCELL
  standard tap *
  page55_i152
#ISCELL
  standard tap *
  page55_i153
#ISCELL
  standard tap *
  page55_i154
#ISCELL
  standard tap *
  page55_i155
#ISCELL
  standard tap *
  page55_i156
#ISCELL
  standard tap *
  page55_i157
#ISCELL
  standard tap *
  page55_i158
#ISCELL
  standard tap *
  page55_i159
#ISCELL
  standard tap *
  page55_i16
#ISCELL
  standard tap *
  page55_i160
#ISCELL
  standard tap *
  page55_i161
#ISCELL
  standard tap *
  page55_i162
#ISCELL
  standard tap *
  page55_i163
#ISCELL
  standard tap *
  page55_i164
#ISCELL
  standard offpage *
  page55_i165
#ISCELL
  standard offpage *
  page55_i166
#ISCELL
  standard offpage *
  page55_i167
#ISCELL
  standard offpage *
  page55_i168
#ISCELL
  standard tap *
  page55_i17
#ISCELL
  standard tap *
  page55_i18
#ISCELL
  standard tap *
  page55_i19
#ISCELL
  standard offpage *
  page55_i2
#ISCELL
  standard tap *
  page55_i20
#ISCELL
  standard tap *
  page55_i21
#ISCELL
  standard tap *
  page55_i22
#ISCELL
  standard tap *
  page55_i23
#ISCELL
  standard tap *
  page55_i24
#ISCELL
  standard tap *
  page55_i25
#ISCELL
  standard tap *
  page55_i26
#ISCELL
  standard tap *
  page55_i27
#ISCELL
  standard tap *
  page55_i28
#ISCELL
  standard tap *
  page55_i29
#ISCELL
  standard tap *
  page55_i3
#ISCELL
  standard tap *
  page55_i30
#ISCELL
  standard tap *
  page55_i31
#ISCELL
  standard tap *
  page55_i32
#ISCELL
  standard tap *
  page55_i33
#ISCELL
  standard tap *
  page55_i34
#ISCELL
  standard tap *
  page55_i35
#ISCELL
  standard tap *
  page55_i36
#ISCELL
  standard tap *
  page55_i37
#ISCELL
  standard tap *
  page55_i38
#ISCELL
  standard tap *
  page55_i39
#ISCELL
  standard tap *
  page55_i4
#ISCELL
  standard tap *
  page55_i40
#ISCELL
  standard tap *
  page55_i41
#ISCELL
  standard tap *
  page55_i42
#ISCELL
  standard tap *
  page55_i43
#ISCELL
  standard tap *
  page55_i44
#ISCELL
  standard tap *
  page55_i45
#ISCELL
  standard tap *
  page55_i46
#ISCELL
  standard tap *
  page55_i47
#ISCELL
  standard tap *
  page55_i48
#ISCELL
  standard tap *
  page55_i49
#ISCELL
  standard tap *
  page55_i5
#ISCELL
  standard offpage *
  page55_i50
#ISCELL
  standard offpage *
  page55_i51
#ISCELL
  standard tap *
  page55_i52
#ISCELL
  standard tap *
  page55_i53
#ISCELL
  standard tap *
  page55_i54
#ISCELL
  standard tap *
  page55_i55
#ISCELL
  standard tap *
  page55_i56
#ISCELL
  standard tap *
  page55_i57
#ISCELL
  standard tap *
  page55_i58
#ISCELL
  standard tap *
  page55_i59
#ISCELL
  standard tap *
  page55_i6
#ISCELL
  standard tap *
  page55_i60
#ISCELL
  standard tap *
  page55_i61
#ISCELL
  standard tap *
  page55_i62
#ISCELL
  standard tap *
  page55_i63
#ISCELL
  standard tap *
  page55_i64
#ISCELL
  standard tap *
  page55_i65
#ISCELL
  standard tap *
  page55_i66
#ISCELL
  standard tap *
  page55_i67
#ISCELL
  standard tap *
  page55_i68
#ISCELL
  standard tap *
  page55_i69
#CELL
  pure_quanta socket4677_azif0045p001c01cs *
  page55_i7
#ISCELL
  standard tap *
  page55_i70
#ISCELL
  standard tap *
  page55_i71
#ISCELL
  standard tap *
  page55_i72
#ISCELL
  standard tap *
  page55_i73
#ISCELL
  standard tap *
  page55_i74
#ISCELL
  standard tap *
  page55_i75
#ISCELL
  standard tap *
  page55_i76
#ISCELL
  standard tap *
  page55_i77
#ISCELL
  standard tap *
  page55_i78
#ISCELL
  standard tap *
  page55_i79
#ISCELL
  standard offpage *
  page55_i8
#ISCELL
  standard tap *
  page55_i80
#ISCELL
  standard tap *
  page55_i81
#ISCELL
  standard tap *
  page55_i82
#ISCELL
  standard tap *
  page55_i83
#ISCELL
  standard tap *
  page55_i84
#ISCELL
  standard tap *
  page55_i85
#ISCELL
  standard tap *
  page55_i86
#ISCELL
  standard tap *
  page55_i87
#ISCELL
  standard tap *
  page55_i88
#ISCELL
  standard tap *
  page55_i89
#ISCELL
  standard offpage *
  page55_i9
#ISCELL
  standard tap *
  page55_i90
#ISCELL
  standard tap *
  page55_i91
#ISCELL
  standard offpage *
  page55_i92
#ISCELL
  standard offpage *
  page55_i93
#ISCELL
  standard offpage *
  page55_i94
#ISCELL
  standard tap *
  page55_i95
#ISCELL
  standard tap *
  page55_i96
#ISCELL
  standard tap *
  page55_i97
#ISCELL
  standard tap *
  page55_i98
#ISCELL
  standard tap *
  page55_i99
#ISCELL
  pure_quanta quanta_title_block_c *
  *
#ISCELL
  standard offpage *
  page56_i1
#ISCELL
  standard offpage *
  page56_i10
#ISCELL
  standard tap *
  page56_i100
#ISCELL
  standard tap *
  page56_i101
#ISCELL
  standard tap *
  page56_i102
#ISCELL
  standard tap *
  page56_i103
#ISCELL
  standard tap *
  page56_i104
#ISCELL
  standard tap *
  page56_i105
#ISCELL
  standard tap *
  page56_i106
#ISCELL
  standard tap *
  page56_i107
#ISCELL
  standard tap *
  page56_i108
#ISCELL
  standard tap *
  page56_i109
#ISCELL
  standard offpage *
  page56_i11
#ISCELL
  standard tap *
  page56_i110
#ISCELL
  standard tap *
  page56_i111
#ISCELL
  standard tap *
  page56_i112
#ISCELL
  standard tap *
  page56_i113
#ISCELL
  standard tap *
  page56_i114
#ISCELL
  standard tap *
  page56_i115
#ISCELL
  standard tap *
  page56_i116
#ISCELL
  standard tap *
  page56_i117
#ISCELL
  standard tap *
  page56_i118
#ISCELL
  standard tap *
  page56_i119
#ISCELL
  standard tap *
  page56_i12
#ISCELL
  standard tap *
  page56_i120
#ISCELL
  standard tap *
  page56_i121
#ISCELL
  standard tap *
  page56_i122
#ISCELL
  standard tap *
  page56_i123
#ISCELL
  standard tap *
  page56_i124
#ISCELL
  standard tap *
  page56_i125
#ISCELL
  standard tap *
  page56_i126
#ISCELL
  standard tap *
  page56_i127
#ISCELL
  standard tap *
  page56_i128
#ISCELL
  standard tap *
  page56_i129
#ISCELL
  standard tap *
  page56_i13
#ISCELL
  standard tap *
  page56_i130
#ISCELL
  standard tap *
  page56_i131
#ISCELL
  standard tap *
  page56_i132
#ISCELL
  standard tap *
  page56_i133
#ISCELL
  standard tap *
  page56_i134
#ISCELL
  standard tap *
  page56_i135
#ISCELL
  standard tap *
  page56_i136
#ISCELL
  standard tap *
  page56_i137
#ISCELL
  standard tap *
  page56_i138
#ISCELL
  standard tap *
  page56_i139
#ISCELL
  standard tap *
  page56_i14
#ISCELL
  standard tap *
  page56_i140
#ISCELL
  standard tap *
  page56_i141
#ISCELL
  standard tap *
  page56_i142
#ISCELL
  standard tap *
  page56_i143
#ISCELL
  standard tap *
  page56_i144
#ISCELL
  standard tap *
  page56_i145
#ISCELL
  standard tap *
  page56_i146
#ISCELL
  standard tap *
  page56_i147
#ISCELL
  standard tap *
  page56_i148
#ISCELL
  standard tap *
  page56_i149
#ISCELL
  standard tap *
  page56_i15
#ISCELL
  standard tap *
  page56_i150
#ISCELL
  standard tap *
  page56_i151
#ISCELL
  standard tap *
  page56_i152
#ISCELL
  standard tap *
  page56_i153
#ISCELL
  standard tap *
  page56_i154
#ISCELL
  standard tap *
  page56_i155
#ISCELL
  standard tap *
  page56_i156
#ISCELL
  standard tap *
  page56_i157
#ISCELL
  standard offpage *
  page56_i158
#ISCELL
  standard offpage *
  page56_i159
#ISCELL
  standard tap *
  page56_i16
#ISCELL
  standard offpage *
  page56_i160
#ISCELL
  standard offpage *
  page56_i161
#ISCELL
  standard offpage *
  page56_i162
#ISCELL
  standard offpage *
  page56_i163
#ISCELL
  standard offpage *
  page56_i164
#ISCELL
  standard offpage *
  page56_i165
#ISCELL
  standard offpage *
  page56_i166
#ISCELL
  standard offpage *
  page56_i167
#CELL
  pure_quanta socket4677_azif0045p001c01cs *
  page56_i168
#ISCELL
  standard tap *
  page56_i17
#ISCELL
  standard tap *
  page56_i18
#ISCELL
  standard tap *
  page56_i19
#ISCELL
  standard offpage *
  page56_i2
#ISCELL
  standard tap *
  page56_i20
#ISCELL
  standard tap *
  page56_i21
#ISCELL
  standard tap *
  page56_i22
#ISCELL
  standard tap *
  page56_i23
#ISCELL
  standard tap *
  page56_i24
#ISCELL
  standard tap *
  page56_i25
#ISCELL
  standard tap *
  page56_i26
#ISCELL
  standard tap *
  page56_i27
#ISCELL
  standard tap *
  page56_i28
#ISCELL
  standard tap *
  page56_i29
#ISCELL
  standard tap *
  page56_i3
#ISCELL
  standard tap *
  page56_i30
#ISCELL
  standard tap *
  page56_i31
#ISCELL
  standard tap *
  page56_i32
#ISCELL
  standard tap *
  page56_i33
#ISCELL
  standard tap *
  page56_i34
#ISCELL
  standard tap *
  page56_i35
#ISCELL
  standard tap *
  page56_i36
#ISCELL
  standard tap *
  page56_i37
#ISCELL
  standard tap *
  page56_i38
#ISCELL
  standard tap *
  page56_i39
#ISCELL
  standard tap *
  page56_i4
#ISCELL
  standard tap *
  page56_i40
#ISCELL
  standard tap *
  page56_i41
#ISCELL
  standard tap *
  page56_i42
#ISCELL
  standard tap *
  page56_i43
#ISCELL
  standard tap *
  page56_i44
#ISCELL
  standard tap *
  page56_i45
#ISCELL
  standard tap *
  page56_i46
#ISCELL
  standard tap *
  page56_i47
#ISCELL
  standard tap *
  page56_i48
#ISCELL
  standard tap *
  page56_i49
#ISCELL
  standard tap *
  page56_i5
#ISCELL
  standard tap *
  page56_i50
#ISCELL
  standard tap *
  page56_i51
#ISCELL
  standard offpage *
  page56_i52
#ISCELL
  standard offpage *
  page56_i53
#ISCELL
  standard tap *
  page56_i54
#ISCELL
  standard tap *
  page56_i55
#ISCELL
  standard tap *
  page56_i56
#ISCELL
  standard tap *
  page56_i57
#ISCELL
  standard tap *
  page56_i58
#ISCELL
  standard tap *
  page56_i59
#ISCELL
  standard tap *
  page56_i6
#ISCELL
  standard tap *
  page56_i60
#ISCELL
  standard tap *
  page56_i61
#ISCELL
  standard tap *
  page56_i62
#ISCELL
  standard tap *
  page56_i63
#ISCELL
  standard tap *
  page56_i64
#ISCELL
  standard tap *
  page56_i65
#ISCELL
  standard tap *
  page56_i66
#ISCELL
  standard tap *
  page56_i67
#ISCELL
  standard tap *
  page56_i68
#ISCELL
  standard tap *
  page56_i69
#ISCELL
  standard tap *
  page56_i7
#ISCELL
  standard tap *
  page56_i70
#ISCELL
  standard tap *
  page56_i71
#ISCELL
  standard tap *
  page56_i72
#ISCELL
  standard tap *
  page56_i73
#ISCELL
  standard tap *
  page56_i74
#ISCELL
  standard tap *
  page56_i75
#ISCELL
  standard tap *
  page56_i76
#ISCELL
  standard tap *
  page56_i77
#ISCELL
  standard tap *
  page56_i78
#ISCELL
  standard tap *
  page56_i79
#ISCELL
  standard tap *
  page56_i8
#ISCELL
  standard tap *
  page56_i80
#ISCELL
  standard tap *
  page56_i81
#ISCELL
  standard tap *
  page56_i82
#ISCELL
  standard tap *
  page56_i83
#ISCELL
  standard tap *
  page56_i84
#ISCELL
  standard tap *
  page56_i85
#ISCELL
  standard tap *
  page56_i86
#ISCELL
  standard tap *
  page56_i87
#ISCELL
  standard tap *
  page56_i88
#ISCELL
  standard tap *
  page56_i89
#ISCELL
  standard tap *
  page56_i9
#ISCELL
  standard tap *
  page56_i90
#ISCELL
  standard offpage *
  page56_i91
#ISCELL
  standard offpage *
  page56_i92
#ISCELL
  standard offpage *
  page56_i93
#ISCELL
  standard offpage *
  page56_i94
#ISCELL
  standard offpage *
  page56_i95
#ISCELL
  standard tap *
  page56_i96
#ISCELL
  standard tap *
  page56_i97
#ISCELL
  standard tap *
  page56_i98
#ISCELL
  standard tap *
  page56_i99
#ISCELL
  pure_quanta quanta_title_block_c *
  *
#ISCELL
  standard offpage *
  page57_i1
#ISCELL
  standard tap *
  page57_i10
#ISCELL
  standard tap *
  page57_i100
#ISCELL
  standard tap *
  page57_i101
#ISCELL
  standard tap *
  page57_i102
#ISCELL
  standard tap *
  page57_i103
#ISCELL
  standard tap *
  page57_i104
#ISCELL
  standard tap *
  page57_i105
#ISCELL
  standard tap *
  page57_i106
#ISCELL
  standard tap *
  page57_i107
#ISCELL
  standard tap *
  page57_i108
#ISCELL
  standard tap *
  page57_i109
#ISCELL
  standard tap *
  page57_i11
#ISCELL
  standard tap *
  page57_i110
#ISCELL
  standard tap *
  page57_i111
#ISCELL
  standard tap *
  page57_i112
#ISCELL
  standard tap *
  page57_i113
#ISCELL
  standard tap *
  page57_i114
#ISCELL
  standard tap *
  page57_i115
#ISCELL
  standard tap *
  page57_i116
#ISCELL
  standard tap *
  page57_i117
#ISCELL
  standard tap *
  page57_i118
#ISCELL
  standard tap *
  page57_i119
#ISCELL
  standard tap *
  page57_i12
#ISCELL
  standard tap *
  page57_i120
#ISCELL
  standard tap *
  page57_i121
#ISCELL
  standard tap *
  page57_i122
#ISCELL
  standard tap *
  page57_i123
#ISCELL
  standard tap *
  page57_i124
#ISCELL
  standard tap *
  page57_i125
#ISCELL
  standard tap *
  page57_i126
#ISCELL
  standard tap *
  page57_i127
#ISCELL
  standard tap *
  page57_i128
#ISCELL
  standard tap *
  page57_i129
#ISCELL
  standard tap *
  page57_i13
#ISCELL
  standard tap *
  page57_i130
#ISCELL
  standard tap *
  page57_i131
#ISCELL
  standard tap *
  page57_i132
#ISCELL
  standard tap *
  page57_i133
#ISCELL
  standard tap *
  page57_i134
#ISCELL
  standard tap *
  page57_i135
#ISCELL
  standard tap *
  page57_i136
#ISCELL
  standard tap *
  page57_i137
#ISCELL
  standard tap *
  page57_i138
#ISCELL
  standard tap *
  page57_i139
#ISCELL
  standard tap *
  page57_i14
#ISCELL
  standard tap *
  page57_i140
#ISCELL
  standard tap *
  page57_i141
#ISCELL
  standard tap *
  page57_i142
#ISCELL
  standard tap *
  page57_i143
#ISCELL
  standard tap *
  page57_i144
#ISCELL
  standard tap *
  page57_i145
#ISCELL
  standard tap *
  page57_i146
#ISCELL
  standard tap *
  page57_i147
#ISCELL
  standard tap *
  page57_i148
#ISCELL
  standard tap *
  page57_i149
#ISCELL
  standard tap *
  page57_i15
#ISCELL
  standard tap *
  page57_i150
#ISCELL
  standard tap *
  page57_i151
#ISCELL
  standard tap *
  page57_i152
#ISCELL
  standard tap *
  page57_i153
#ISCELL
  standard tap *
  page57_i154
#ISCELL
  standard tap *
  page57_i155
#ISCELL
  standard offpage *
  page57_i156
#ISCELL
  standard offpage *
  page57_i157
#ISCELL
  standard offpage *
  page57_i158
#ISCELL
  standard offpage *
  page57_i159
#ISCELL
  standard tap *
  page57_i16
#ISCELL
  standard offpage *
  page57_i160
#ISCELL
  standard offpage *
  page57_i161
#ISCELL
  standard offpage *
  page57_i162
#ISCELL
  standard offpage *
  page57_i163
#ISCELL
  standard offpage *
  page57_i164
#ISCELL
  standard offpage *
  page57_i165
#ISCELL
  standard offpage *
  page57_i166
#ISCELL
  standard offpage *
  page57_i167
#CELL
  pure_quanta socket4677_azif0045p001c01cs *
  page57_i168
#ISCELL
  standard tap *
  page57_i17
#ISCELL
  standard tap *
  page57_i18
#ISCELL
  standard tap *
  page57_i19
#ISCELL
  standard offpage *
  page57_i2
#ISCELL
  standard tap *
  page57_i20
#ISCELL
  standard tap *
  page57_i21
#ISCELL
  standard tap *
  page57_i22
#ISCELL
  standard tap *
  page57_i23
#ISCELL
  standard tap *
  page57_i24
#ISCELL
  standard tap *
  page57_i25
#ISCELL
  standard tap *
  page57_i26
#ISCELL
  standard tap *
  page57_i27
#ISCELL
  standard tap *
  page57_i28
#ISCELL
  standard tap *
  page57_i29
#ISCELL
  standard tap *
  page57_i3
#ISCELL
  standard tap *
  page57_i30
#ISCELL
  standard tap *
  page57_i31
#ISCELL
  standard tap *
  page57_i32
#ISCELL
  standard tap *
  page57_i33
#ISCELL
  standard tap *
  page57_i34
#ISCELL
  standard tap *
  page57_i35
#ISCELL
  standard tap *
  page57_i36
#ISCELL
  standard tap *
  page57_i37
#ISCELL
  standard tap *
  page57_i38
#ISCELL
  standard tap *
  page57_i39
#ISCELL
  standard tap *
  page57_i4
#ISCELL
  standard tap *
  page57_i40
#ISCELL
  standard tap *
  page57_i41
#ISCELL
  standard tap *
  page57_i42
#ISCELL
  standard tap *
  page57_i43
#ISCELL
  standard tap *
  page57_i44
#ISCELL
  standard tap *
  page57_i45
#ISCELL
  standard tap *
  page57_i46
#ISCELL
  standard tap *
  page57_i47
#ISCELL
  standard offpage *
  page57_i48
#ISCELL
  standard offpage *
  page57_i49
#ISCELL
  standard tap *
  page57_i5
#ISCELL
  standard tap *
  page57_i50
#ISCELL
  standard tap *
  page57_i51
#ISCELL
  standard tap *
  page57_i52
#ISCELL
  standard tap *
  page57_i53
#ISCELL
  standard tap *
  page57_i54
#ISCELL
  standard tap *
  page57_i55
#ISCELL
  standard tap *
  page57_i56
#ISCELL
  standard tap *
  page57_i57
#ISCELL
  standard tap *
  page57_i58
#ISCELL
  standard tap *
  page57_i59
#ISCELL
  standard tap *
  page57_i6
#ISCELL
  standard tap *
  page57_i60
#ISCELL
  standard tap *
  page57_i61
#ISCELL
  standard tap *
  page57_i62
#ISCELL
  standard tap *
  page57_i63
#ISCELL
  standard tap *
  page57_i64
#ISCELL
  standard tap *
  page57_i65
#ISCELL
  standard tap *
  page57_i66
#ISCELL
  standard tap *
  page57_i67
#ISCELL
  standard tap *
  page57_i68
#ISCELL
  standard tap *
  page57_i69
#ISCELL
  standard offpage *
  page57_i7
#ISCELL
  standard tap *
  page57_i70
#ISCELL
  standard tap *
  page57_i71
#ISCELL
  standard tap *
  page57_i72
#ISCELL
  standard tap *
  page57_i73
#ISCELL
  standard tap *
  page57_i74
#ISCELL
  standard tap *
  page57_i75
#ISCELL
  standard tap *
  page57_i76
#ISCELL
  standard tap *
  page57_i77
#ISCELL
  standard tap *
  page57_i78
#ISCELL
  standard tap *
  page57_i79
#ISCELL
  standard offpage *
  page57_i8
#ISCELL
  standard tap *
  page57_i80
#ISCELL
  standard tap *
  page57_i81
#ISCELL
  standard tap *
  page57_i82
#ISCELL
  standard tap *
  page57_i83
#ISCELL
  standard tap *
  page57_i84
#ISCELL
  standard tap *
  page57_i85
#ISCELL
  standard tap *
  page57_i86
#ISCELL
  standard tap *
  page57_i87
#ISCELL
  standard tap *
  page57_i88
#ISCELL
  standard tap *
  page57_i89
#ISCELL
  standard tap *
  page57_i9
#ISCELL
  standard tap *
  page57_i90
#ISCELL
  standard offpage *
  page57_i91
#ISCELL
  standard offpage *
  page57_i92
#ISCELL
  standard offpage *
  page57_i93
#ISCELL
  standard tap *
  page57_i94
#ISCELL
  standard tap *
  page57_i95
#ISCELL
  standard tap *
  page57_i96
#ISCELL
  standard tap *
  page57_i97
#ISCELL
  standard tap *
  page57_i98
#ISCELL
  standard tap *
  page57_i99
#ISCELL
  pure_quanta quanta_title_block_c *
  *
#ISCELL
  standard offpage *
  page58_i1
#ISCELL
  standard tap *
  page58_i10
#ISCELL
  standard tap *
  page58_i100
#ISCELL
  standard tap *
  page58_i101
#ISCELL
  standard tap *
  page58_i102
#ISCELL
  standard tap *
  page58_i103
#ISCELL
  standard tap *
  page58_i104
#ISCELL
  standard tap *
  page58_i105
#ISCELL
  standard tap *
  page58_i106
#ISCELL
  standard tap *
  page58_i107
#ISCELL
  standard tap *
  page58_i108
#ISCELL
  standard tap *
  page58_i109
#ISCELL
  standard tap *
  page58_i11
#ISCELL
  standard offpage *
  page58_i110
#ISCELL
  standard offpage *
  page58_i111
#ISCELL
  standard offpage *
  page58_i112
#ISCELL
  standard offpage *
  page58_i113
#ISCELL
  standard offpage *
  page58_i114
#ISCELL
  standard offpage *
  page58_i115
#ISCELL
  standard offpage *
  page58_i116
#ISCELL
  standard offpage *
  page58_i117
#ISCELL
  standard offpage *
  page58_i118
#ISCELL
  standard offpage *
  page58_i119
#ISCELL
  standard tap *
  page58_i12
#ISCELL
  standard tap *
  page58_i120
#ISCELL
  standard tap *
  page58_i121
#ISCELL
  standard tap *
  page58_i122
#ISCELL
  standard tap *
  page58_i123
#ISCELL
  standard tap *
  page58_i124
#ISCELL
  standard tap *
  page58_i125
#ISCELL
  standard tap *
  page58_i126
#ISCELL
  standard tap *
  page58_i127
#ISCELL
  standard tap *
  page58_i128
#ISCELL
  standard tap *
  page58_i129
#ISCELL
  standard tap *
  page58_i13
#ISCELL
  standard tap *
  page58_i130
#ISCELL
  standard tap *
  page58_i131
#ISCELL
  standard tap *
  page58_i132
#ISCELL
  standard tap *
  page58_i133
#ISCELL
  standard tap *
  page58_i134
#ISCELL
  standard tap *
  page58_i135
#ISCELL
  standard tap *
  page58_i136
#ISCELL
  standard tap *
  page58_i137
#ISCELL
  standard tap *
  page58_i138
#ISCELL
  standard tap *
  page58_i139
#ISCELL
  standard tap *
  page58_i14
#ISCELL
  standard tap *
  page58_i140
#ISCELL
  standard tap *
  page58_i141
#ISCELL
  standard tap *
  page58_i142
#ISCELL
  standard tap *
  page58_i143
#ISCELL
  standard tap *
  page58_i144
#ISCELL
  standard tap *
  page58_i145
#ISCELL
  standard tap *
  page58_i146
#ISCELL
  standard tap *
  page58_i147
#ISCELL
  standard tap *
  page58_i148
#ISCELL
  standard tap *
  page58_i149
#ISCELL
  standard tap *
  page58_i15
#ISCELL
  standard tap *
  page58_i150
#ISCELL
  standard tap *
  page58_i151
#ISCELL
  standard tap *
  page58_i152
#ISCELL
  standard tap *
  page58_i153
#ISCELL
  standard tap *
  page58_i154
#ISCELL
  standard offpage *
  page58_i155
#ISCELL
  standard offpage *
  page58_i156
#ISCELL
  standard offpage *
  page58_i157
#ISCELL
  standard offpage *
  page58_i158
#ISCELL
  standard tap *
  page58_i159
#ISCELL
  standard tap *
  page58_i16
#ISCELL
  standard tap *
  page58_i160
#ISCELL
  standard tap *
  page58_i161
#ISCELL
  standard tap *
  page58_i162
#ISCELL
  standard tap *
  page58_i163
#ISCELL
  standard tap *
  page58_i164
#ISCELL
  standard tap *
  page58_i165
#ISCELL
  standard tap *
  page58_i166
#ISCELL
  standard tap *
  page58_i167
#ISCELL
  standard offpage *
  page58_i168
#ISCELL
  standard tap *
  page58_i17
#ISCELL
  standard tap *
  page58_i18
#ISCELL
  standard tap *
  page58_i19
#ISCELL
  standard offpage *
  page58_i2
#CELL
  pure_quanta socket4677_azif0045p001c01cs *
  page58_i20
#ISCELL
  standard tap *
  page58_i21
#ISCELL
  standard tap *
  page58_i22
#ISCELL
  standard tap *
  page58_i23
#ISCELL
  standard tap *
  page58_i24
#ISCELL
  standard tap *
  page58_i25
#ISCELL
  standard tap *
  page58_i26
#ISCELL
  standard tap *
  page58_i27
#ISCELL
  standard tap *
  page58_i28
#ISCELL
  standard tap *
  page58_i29
#ISCELL
  standard offpage *
  page58_i3
#ISCELL
  standard tap *
  page58_i30
#ISCELL
  standard tap *
  page58_i31
#ISCELL
  standard tap *
  page58_i32
#ISCELL
  standard tap *
  page58_i33
#ISCELL
  standard tap *
  page58_i34
#ISCELL
  standard tap *
  page58_i35
#ISCELL
  standard tap *
  page58_i36
#ISCELL
  standard tap *
  page58_i37
#ISCELL
  standard tap *
  page58_i38
#ISCELL
  standard tap *
  page58_i39
#ISCELL
  standard offpage *
  page58_i4
#ISCELL
  standard tap *
  page58_i40
#ISCELL
  standard tap *
  page58_i41
#ISCELL
  standard tap *
  page58_i42
#ISCELL
  standard tap *
  page58_i43
#ISCELL
  standard tap *
  page58_i44
#ISCELL
  standard tap *
  page58_i45
#ISCELL
  standard tap *
  page58_i46
#ISCELL
  standard tap *
  page58_i47
#ISCELL
  standard tap *
  page58_i48
#ISCELL
  standard tap *
  page58_i49
#ISCELL
  standard offpage *
  page58_i5
#ISCELL
  standard tap *
  page58_i50
#ISCELL
  standard tap *
  page58_i51
#ISCELL
  standard tap *
  page58_i52
#ISCELL
  standard tap *
  page58_i53
#ISCELL
  standard tap *
  page58_i54
#ISCELL
  standard tap *
  page58_i55
#ISCELL
  standard tap *
  page58_i56
#ISCELL
  standard tap *
  page58_i57
#ISCELL
  standard tap *
  page58_i58
#ISCELL
  standard tap *
  page58_i59
#ISCELL
  standard tap *
  page58_i6
#ISCELL
  standard tap *
  page58_i60
#ISCELL
  standard tap *
  page58_i61
#ISCELL
  standard tap *
  page58_i62
#ISCELL
  standard tap *
  page58_i63
#ISCELL
  standard tap *
  page58_i64
#ISCELL
  standard tap *
  page58_i65
#ISCELL
  standard tap *
  page58_i66
#ISCELL
  standard tap *
  page58_i67
#ISCELL
  standard tap *
  page58_i68
#ISCELL
  standard tap *
  page58_i69
#ISCELL
  standard tap *
  page58_i7
#ISCELL
  standard tap *
  page58_i70
#ISCELL
  standard tap *
  page58_i71
#ISCELL
  standard tap *
  page58_i72
#ISCELL
  standard tap *
  page58_i73
#ISCELL
  standard tap *
  page58_i74
#ISCELL
  standard tap *
  page58_i75
#ISCELL
  standard tap *
  page58_i76
#ISCELL
  standard tap *
  page58_i77
#ISCELL
  standard tap *
  page58_i78
#ISCELL
  standard tap *
  page58_i79
#ISCELL
  standard tap *
  page58_i8
#ISCELL
  standard tap *
  page58_i80
#ISCELL
  standard tap *
  page58_i81
#ISCELL
  standard offpage *
  page58_i82
#ISCELL
  standard tap *
  page58_i83
#ISCELL
  standard tap *
  page58_i84
#ISCELL
  standard tap *
  page58_i85
#ISCELL
  standard tap *
  page58_i86
#ISCELL
  standard tap *
  page58_i87
#ISCELL
  standard tap *
  page58_i88
#ISCELL
  standard tap *
  page58_i89
#ISCELL
  standard tap *
  page58_i9
#ISCELL
  standard tap *
  page58_i90
#ISCELL
  standard tap *
  page58_i91
#ISCELL
  standard tap *
  page58_i92
#ISCELL
  standard tap *
  page58_i93
#ISCELL
  standard tap *
  page58_i94
#ISCELL
  standard tap *
  page58_i95
#ISCELL
  standard tap *
  page58_i96
#ISCELL
  standard tap *
  page58_i97
#ISCELL
  standard tap *
  page58_i98
#ISCELL
  standard tap *
  page58_i99
#ISCELL
  pure_quanta quanta_title_block_c *
  *
#ISCELL
  standard tap *
  page59_i10
#ISCELL
  standard tap *
  page59_i11
#ISCELL
  standard tap *
  page59_i12
#ISCELL
  standard tap *
  page59_i13
#ISCELL
  standard tap *
  page59_i14
#ISCELL
  standard tap *
  page59_i15
#ISCELL
  standard tap *
  page59_i16
#ISCELL
  standard tap *
  page59_i17
#ISCELL
  standard tap *
  page59_i18
#ISCELL
  standard tap *
  page59_i19
#CELL
  pure_quanta socket4677_azif0045p001c01cs *
  page59_i20
#ISCELL
  standard tap *
  page59_i21
#ISCELL
  standard tap *
  page59_i22
#ISCELL
  standard tap *
  page59_i23
#ISCELL
  standard tap *
  page59_i24
#ISCELL
  standard tap *
  page59_i25
#ISCELL
  standard tap *
  page59_i26
#ISCELL
  standard tap *
  page59_i27
#ISCELL
  standard tap *
  page59_i28
#ISCELL
  standard tap *
  page59_i29
#ISCELL
  standard tap *
  page59_i30
#ISCELL
  standard tap *
  page59_i31
#ISCELL
  standard tap *
  page59_i32
#ISCELL
  standard tap *
  page59_i33
#ISCELL
  standard tap *
  page59_i34
#ISCELL
  standard tap *
  page59_i35
#ISCELL
  standard tap *
  page59_i36
#ISCELL
  standard tap *
  page59_i4
#ISCELL
  standard tap *
  page59_i5
#ISCELL
  standard tap *
  page59_i6
#ISCELL
  standard tap *
  page59_i7
#ISCELL
  standard tap *
  page59_i8
#ISCELL
  standard tap *
  page59_i9
#ISCELL
  pure_quanta quanta_title_block_c *
  *
#ISCELL
  standard tap *
  page60_i304
#ISCELL
  standard tap *
  page60_i305
#ISCELL
  standard tap *
  page60_i306
#ISCELL
  standard tap *
  page60_i307
#ISCELL
  standard tap *
  page60_i308
#ISCELL
  standard tap *
  page60_i309
#ISCELL
  standard tap *
  page60_i310
#ISCELL
  standard tap *
  page60_i311
#ISCELL
  standard tap *
  page60_i312
#ISCELL
  standard tap *
  page60_i313
#ISCELL
  standard tap *
  page60_i314
#ISCELL
  standard tap *
  page60_i315
#ISCELL
  standard tap *
  page60_i316
#ISCELL
  standard tap *
  page60_i317
#ISCELL
  standard tap *
  page60_i318
#ISCELL
  standard tap *
  page60_i319
#ISCELL
  standard offpage *
  page60_i320
#ISCELL
  standard tap *
  page60_i321
#ISCELL
  standard tap *
  page60_i322
#ISCELL
  standard tap *
  page60_i323
#ISCELL
  standard tap *
  page60_i324
#ISCELL
  standard tap *
  page60_i325
#ISCELL
  standard tap *
  page60_i326
#ISCELL
  standard tap *
  page60_i327
#ISCELL
  standard tap *
  page60_i328
#ISCELL
  standard tap *
  page60_i329
#ISCELL
  standard tap *
  page60_i330
#ISCELL
  standard tap *
  page60_i331
#ISCELL
  standard tap *
  page60_i332
#ISCELL
  standard tap *
  page60_i333
#ISCELL
  standard tap *
  page60_i334
#ISCELL
  standard tap *
  page60_i335
#ISCELL
  standard tap *
  page60_i336
#ISCELL
  standard offpage *
  page60_i337
#ISCELL
  standard tap *
  page60_i338
#ISCELL
  standard tap *
  page60_i339
#ISCELL
  standard tap *
  page60_i340
#ISCELL
  standard tap *
  page60_i341
#ISCELL
  standard tap *
  page60_i342
#ISCELL
  standard tap *
  page60_i343
#ISCELL
  standard tap *
  page60_i344
#ISCELL
  standard tap *
  page60_i345
#ISCELL
  standard tap *
  page60_i346
#ISCELL
  standard tap *
  page60_i347
#ISCELL
  standard tap *
  page60_i348
#ISCELL
  standard tap *
  page60_i349
#ISCELL
  standard tap *
  page60_i350
#ISCELL
  standard tap *
  page60_i351
#ISCELL
  standard tap *
  page60_i352
#ISCELL
  standard tap *
  page60_i353
#ISCELL
  standard tap *
  page60_i354
#ISCELL
  standard tap *
  page60_i355
#ISCELL
  standard tap *
  page60_i356
#ISCELL
  standard tap *
  page60_i357
#ISCELL
  standard tap *
  page60_i358
#ISCELL
  standard tap *
  page60_i359
#ISCELL
  standard tap *
  page60_i360
#ISCELL
  standard tap *
  page60_i361
#ISCELL
  standard tap *
  page60_i362
#ISCELL
  standard tap *
  page60_i363
#ISCELL
  standard tap *
  page60_i364
#ISCELL
  standard tap *
  page60_i365
#ISCELL
  standard tap *
  page60_i366
#ISCELL
  standard tap *
  page60_i367
#ISCELL
  standard tap *
  page60_i368
#ISCELL
  standard tap *
  page60_i369
#ISCELL
  standard offpage *
  page60_i370
#ISCELL
  standard offpage *
  page60_i371
#ISCELL
  standard tap *
  page60_i440
#ISCELL
  standard tap *
  page60_i441
#ISCELL
  standard tap *
  page60_i442
#ISCELL
  standard tap *
  page60_i443
#ISCELL
  standard tap *
  page60_i444
#ISCELL
  standard tap *
  page60_i445
#ISCELL
  standard tap *
  page60_i446
#ISCELL
  standard tap *
  page60_i447
#ISCELL
  standard tap *
  page60_i448
#ISCELL
  standard tap *
  page60_i449
#ISCELL
  standard tap *
  page60_i450
#ISCELL
  standard tap *
  page60_i451
#ISCELL
  standard tap *
  page60_i452
#ISCELL
  standard tap *
  page60_i453
#ISCELL
  standard tap *
  page60_i454
#ISCELL
  standard tap *
  page60_i455
#ISCELL
  standard tap *
  page60_i456
#ISCELL
  standard tap *
  page60_i457
#ISCELL
  standard tap *
  page60_i458
#ISCELL
  standard tap *
  page60_i459
#ISCELL
  standard tap *
  page60_i460
#ISCELL
  standard tap *
  page60_i461
#ISCELL
  standard tap *
  page60_i462
#ISCELL
  standard tap *
  page60_i463
#ISCELL
  standard tap *
  page60_i464
#ISCELL
  standard tap *
  page60_i465
#ISCELL
  standard tap *
  page60_i466
#ISCELL
  standard tap *
  page60_i467
#ISCELL
  standard tap *
  page60_i468
#ISCELL
  standard tap *
  page60_i469
#ISCELL
  standard offpage *
  page60_i470
#ISCELL
  standard offpage *
  page60_i471
#ISCELL
  standard tap *
  page60_i472
#ISCELL
  standard tap *
  page60_i473
#ISCELL
  standard offpage *
  page60_i474
#ISCELL
  standard offpage *
  page60_i475
#ISCELL
  standard tap *
  page60_i476
#ISCELL
  standard tap *
  page60_i477
#ISCELL
  standard tap *
  page60_i478
#ISCELL
  standard tap *
  page60_i479
#ISCELL
  standard tap *
  page60_i480
#ISCELL
  standard tap *
  page60_i481
#ISCELL
  standard tap *
  page60_i482
#ISCELL
  standard tap *
  page60_i483
#ISCELL
  standard tap *
  page60_i484
#ISCELL
  standard tap *
  page60_i485
#ISCELL
  standard tap *
  page60_i486
#ISCELL
  standard tap *
  page60_i487
#ISCELL
  standard tap *
  page60_i488
#ISCELL
  standard tap *
  page60_i489
#ISCELL
  standard tap *
  page60_i490
#ISCELL
  standard tap *
  page60_i491
#ISCELL
  standard tap *
  page60_i492
#ISCELL
  standard tap *
  page60_i493
#ISCELL
  standard tap *
  page60_i494
#ISCELL
  standard tap *
  page60_i495
#ISCELL
  standard tap *
  page60_i496
#ISCELL
  standard tap *
  page60_i497
#ISCELL
  standard tap *
  page60_i498
#ISCELL
  standard tap *
  page60_i499
#ISCELL
  standard tap *
  page60_i500
#ISCELL
  standard tap *
  page60_i501
#ISCELL
  standard tap *
  page60_i502
#ISCELL
  standard tap *
  page60_i503
#ISCELL
  standard tap *
  page60_i504
#ISCELL
  standard tap *
  page60_i505
#ISCELL
  standard tap *
  page60_i506
#ISCELL
  standard tap *
  page60_i507
#CELL
  pure_quanta socket4677_azif0045p001c01cs *
  page60_i69
#CELL
  pure_quanta socket4677_azif0045p001c01cs *
  page60_i80
#ISCELL
  pure_quanta quanta_title_block_c *
  *
#ISCELL
  standard tap *
  page61_i1
#ISCELL
  standard tap *
  page61_i10
#ISCELL
  standard tap *
  page61_i100
#ISCELL
  standard tap *
  page61_i101
#ISCELL
  standard tap *
  page61_i102
#ISCELL
  standard offpage *
  page61_i103
#ISCELL
  standard offpage *
  page61_i104
#ISCELL
  standard tap *
  page61_i11
#CELL
  pure_quanta socket4677_azif0045p001c01cs *
  page61_i12
#ISCELL
  standard tap *
  page61_i13
#ISCELL
  standard offpage *
  page61_i14
#ISCELL
  standard offpage *
  page61_i15
#ISCELL
  standard tap *
  page61_i16
#ISCELL
  standard tap *
  page61_i17
#ISCELL
  standard tap *
  page61_i18
#ISCELL
  standard tap *
  page61_i19
#ISCELL
  standard tap *
  page61_i2
#ISCELL
  standard tap *
  page61_i20
#ISCELL
  standard tap *
  page61_i21
#ISCELL
  standard tap *
  page61_i22
#ISCELL
  standard offpage *
  page61_i223
#ISCELL
  standard offpage *
  page61_i224
#ISCELL
  standard tap *
  page61_i225
#ISCELL
  standard tap *
  page61_i226
#ISCELL
  standard tap *
  page61_i227
#ISCELL
  standard tap *
  page61_i228
#ISCELL
  standard tap *
  page61_i229
#ISCELL
  standard tap *
  page61_i23
#ISCELL
  standard tap *
  page61_i230
#ISCELL
  standard tap *
  page61_i231
#ISCELL
  standard tap *
  page61_i232
#ISCELL
  standard tap *
  page61_i233
#ISCELL
  standard tap *
  page61_i234
#ISCELL
  standard tap *
  page61_i235
#ISCELL
  standard tap *
  page61_i236
#ISCELL
  standard tap *
  page61_i237
#ISCELL
  standard tap *
  page61_i238
#ISCELL
  standard tap *
  page61_i239
#ISCELL
  standard tap *
  page61_i24
#ISCELL
  standard tap *
  page61_i240
#ISCELL
  standard tap *
  page61_i241
#ISCELL
  standard tap *
  page61_i242
#ISCELL
  standard tap *
  page61_i243
#ISCELL
  standard tap *
  page61_i244
#ISCELL
  standard tap *
  page61_i245
#ISCELL
  standard tap *
  page61_i246
#ISCELL
  standard tap *
  page61_i247
#ISCELL
  standard tap *
  page61_i248
#ISCELL
  standard tap *
  page61_i249
#ISCELL
  standard tap *
  page61_i25
#ISCELL
  standard tap *
  page61_i250
#ISCELL
  standard tap *
  page61_i251
#ISCELL
  standard tap *
  page61_i252
#ISCELL
  standard tap *
  page61_i253
#ISCELL
  standard tap *
  page61_i254
#ISCELL
  standard tap *
  page61_i255
#ISCELL
  standard tap *
  page61_i256
#ISCELL
  standard tap *
  page61_i257
#ISCELL
  standard tap *
  page61_i258
#ISCELL
  standard tap *
  page61_i259
#ISCELL
  standard tap *
  page61_i26
#ISCELL
  standard tap *
  page61_i260
#ISCELL
  standard tap *
  page61_i261
#ISCELL
  standard tap *
  page61_i262
#ISCELL
  standard tap *
  page61_i263
#ISCELL
  standard tap *
  page61_i264
#ISCELL
  standard tap *
  page61_i265
#ISCELL
  standard tap *
  page61_i266
#ISCELL
  standard tap *
  page61_i267
#ISCELL
  standard tap *
  page61_i268
#ISCELL
  standard tap *
  page61_i269
#ISCELL
  standard tap *
  page61_i27
#ISCELL
  standard tap *
  page61_i270
#ISCELL
  standard tap *
  page61_i271
#ISCELL
  standard tap *
  page61_i272
#ISCELL
  standard tap *
  page61_i273
#ISCELL
  standard tap *
  page61_i274
#ISCELL
  standard tap *
  page61_i275
#ISCELL
  standard tap *
  page61_i276
#ISCELL
  standard tap *
  page61_i277
#ISCELL
  standard tap *
  page61_i278
#ISCELL
  standard tap *
  page61_i279
#ISCELL
  standard tap *
  page61_i28
#ISCELL
  standard tap *
  page61_i280
#ISCELL
  standard tap *
  page61_i281
#ISCELL
  standard tap *
  page61_i282
#ISCELL
  standard tap *
  page61_i283
#ISCELL
  standard tap *
  page61_i284
#ISCELL
  standard tap *
  page61_i285
#ISCELL
  standard tap *
  page61_i286
#ISCELL
  standard tap *
  page61_i287
#ISCELL
  standard offpage *
  page61_i288
#ISCELL
  standard offpage *
  page61_i289
#ISCELL
  standard tap *
  page61_i29
#ISCELL
  standard tap *
  page61_i290
#ISCELL
  standard tap *
  page61_i3
#ISCELL
  standard tap *
  page61_i30
#ISCELL
  standard tap *
  page61_i31
#ISCELL
  standard tap *
  page61_i32
#ISCELL
  standard tap *
  page61_i33
#ISCELL
  standard tap *
  page61_i34
#ISCELL
  standard tap *
  page61_i35
#ISCELL
  standard tap *
  page61_i4
#ISCELL
  standard tap *
  page61_i5
#CELL
  pure_quanta socket4677_azif0045p001c01cs *
  page61_i54
#ISCELL
  standard tap *
  page61_i6
#ISCELL
  standard tap *
  page61_i7
#ISCELL
  standard tap *
  page61_i71
#ISCELL
  standard tap *
  page61_i72
#ISCELL
  standard tap *
  page61_i73
#ISCELL
  standard tap *
  page61_i74
#ISCELL
  standard tap *
  page61_i75
#ISCELL
  standard tap *
  page61_i76
#ISCELL
  standard tap *
  page61_i77
#ISCELL
  standard tap *
  page61_i78
#ISCELL
  standard tap *
  page61_i79
#ISCELL
  standard tap *
  page61_i8
#ISCELL
  standard tap *
  page61_i80
#ISCELL
  standard tap *
  page61_i81
#ISCELL
  standard tap *
  page61_i82
#ISCELL
  standard tap *
  page61_i83
#ISCELL
  standard tap *
  page61_i84
#ISCELL
  standard tap *
  page61_i85
#ISCELL
  standard tap *
  page61_i86
#ISCELL
  standard tap *
  page61_i87
#ISCELL
  standard tap *
  page61_i88
#ISCELL
  standard tap *
  page61_i89
#ISCELL
  standard tap *
  page61_i9
#ISCELL
  standard tap *
  page61_i90
#ISCELL
  standard tap *
  page61_i91
#ISCELL
  standard tap *
  page61_i92
#ISCELL
  standard tap *
  page61_i93
#ISCELL
  standard tap *
  page61_i94
#ISCELL
  standard tap *
  page61_i95
#ISCELL
  standard tap *
  page61_i96
#ISCELL
  standard tap *
  page61_i97
#ISCELL
  standard tap *
  page61_i98
#ISCELL
  standard tap *
  page61_i99
#ISCELL
  pure_quanta quanta_title_block_c *
  *
#ISCELL
  standard tap *
  page62_i100
#ISCELL
  standard tap *
  page62_i101
#ISCELL
  standard tap *
  page62_i102
#ISCELL
  standard tap *
  page62_i103
#ISCELL
  standard tap *
  page62_i104
#ISCELL
  standard tap *
  page62_i105
#ISCELL
  standard tap *
  page62_i106
#ISCELL
  standard tap *
  page62_i107
#ISCELL
  standard tap *
  page62_i108
#ISCELL
  standard tap *
  page62_i109
#ISCELL
  standard tap *
  page62_i110
#ISCELL
  standard tap *
  page62_i111
#ISCELL
  standard tap *
  page62_i112
#ISCELL
  standard tap *
  page62_i113
#ISCELL
  standard tap *
  page62_i114
#ISCELL
  standard tap *
  page62_i115
#ISCELL
  standard tap *
  page62_i116
#ISCELL
  standard tap *
  page62_i117
#ISCELL
  standard tap *
  page62_i118
#ISCELL
  standard tap *
  page62_i119
#ISCELL
  standard tap *
  page62_i120
#ISCELL
  standard tap *
  page62_i121
#ISCELL
  standard tap *
  page62_i122
#ISCELL
  standard tap *
  page62_i123
#ISCELL
  standard tap *
  page62_i124
#ISCELL
  standard tap *
  page62_i125
#ISCELL
  standard tap *
  page62_i126
#ISCELL
  standard tap *
  page62_i127
#ISCELL
  standard tap *
  page62_i128
#ISCELL
  standard tap *
  page62_i129
#ISCELL
  standard tap *
  page62_i130
#ISCELL
  standard tap *
  page62_i131
#ISCELL
  standard tap *
  page62_i132
#ISCELL
  standard tap *
  page62_i133
#ISCELL
  standard tap *
  page62_i134
#ISCELL
  standard tap *
  page62_i135
#ISCELL
  standard tap *
  page62_i136
#ISCELL
  standard tap *
  page62_i137
#ISCELL
  standard tap *
  page62_i138
#ISCELL
  standard tap *
  page62_i139
#ISCELL
  standard tap *
  page62_i140
#ISCELL
  standard tap *
  page62_i141
#ISCELL
  standard tap *
  page62_i142
#ISCELL
  standard tap *
  page62_i143
#ISCELL
  standard tap *
  page62_i144
#ISCELL
  standard tap *
  page62_i145
#ISCELL
  standard tap *
  page62_i146
#ISCELL
  standard tap *
  page62_i147
#ISCELL
  standard tap *
  page62_i148
#ISCELL
  standard tap *
  page62_i149
#ISCELL
  standard tap *
  page62_i150
#ISCELL
  standard tap *
  page62_i151
#ISCELL
  standard tap *
  page62_i152
#ISCELL
  standard tap *
  page62_i153
#ISCELL
  standard tap *
  page62_i154
#ISCELL
  standard tap *
  page62_i155
#ISCELL
  standard tap *
  page62_i156
#ISCELL
  standard tap *
  page62_i157
#ISCELL
  standard tap *
  page62_i158
#ISCELL
  standard tap *
  page62_i159
#ISCELL
  standard tap *
  page62_i160
#ISCELL
  standard tap *
  page62_i161
#ISCELL
  standard offpage *
  page62_i162
#ISCELL
  standard offpage *
  page62_i163
#CELL
  pure_quanta socket4677_azif0045p001c01cs *
  page62_i18
#ISCELL
  standard offpage *
  page62_i96
#ISCELL
  standard offpage *
  page62_i97
#ISCELL
  standard tap *
  page62_i98
#ISCELL
  standard tap *
  page62_i99
#ISCELL
  pure_quanta quanta_title_block_c *
  *
#ISCELL
  standard tap *
  page63_i1
#ISCELL
  standard tap *
  page63_i10
#ISCELL
  standard offpage *
  page63_i100
#ISCELL
  standard offpage *
  page63_i101
#ISCELL
  standard tap *
  page63_i11
#ISCELL
  standard tap *
  page63_i12
#ISCELL
  standard tap *
  page63_i13
#ISCELL
  standard tap *
  page63_i14
#ISCELL
  standard tap *
  page63_i15
#ISCELL
  standard tap *
  page63_i16
#ISCELL
  standard offpage *
  page63_i17
#ISCELL
  standard offpage *
  page63_i18
#ISCELL
  standard tap *
  page63_i19
#ISCELL
  standard tap *
  page63_i2
#ISCELL
  standard tap *
  page63_i20
#ISCELL
  standard tap *
  page63_i21
#ISCELL
  standard tap *
  page63_i22
#ISCELL
  standard tap *
  page63_i23
#ISCELL
  standard tap *
  page63_i24
#ISCELL
  standard tap *
  page63_i25
#ISCELL
  standard tap *
  page63_i26
#ISCELL
  standard tap *
  page63_i27
#ISCELL
  standard tap *
  page63_i28
#ISCELL
  standard tap *
  page63_i29
#ISCELL
  standard tap *
  page63_i3
#ISCELL
  standard tap *
  page63_i30
#ISCELL
  standard tap *
  page63_i31
#ISCELL
  standard tap *
  page63_i32
#ISCELL
  standard tap *
  page63_i33
#ISCELL
  standard tap *
  page63_i34
#ISCELL
  standard tap *
  page63_i35
#ISCELL
  standard tap *
  page63_i36
#ISCELL
  standard tap *
  page63_i37
#ISCELL
  standard tap *
  page63_i38
#ISCELL
  standard tap *
  page63_i39
#ISCELL
  standard tap *
  page63_i4
#ISCELL
  standard tap *
  page63_i40
#ISCELL
  standard tap *
  page63_i41
#ISCELL
  standard tap *
  page63_i42
#ISCELL
  standard tap *
  page63_i43
#ISCELL
  standard tap *
  page63_i44
#ISCELL
  standard tap *
  page63_i45
#ISCELL
  standard tap *
  page63_i46
#ISCELL
  standard tap *
  page63_i47
#ISCELL
  standard tap *
  page63_i48
#ISCELL
  standard tap *
  page63_i49
#ISCELL
  standard tap *
  page63_i5
#ISCELL
  standard tap *
  page63_i50
#CELL
  pure_quanta socket4677_azif0045p001c01cs *
  page63_i51
#ISCELL
  standard tap *
  page63_i52
#ISCELL
  standard tap *
  page63_i53
#ISCELL
  standard tap *
  page63_i54
#ISCELL
  standard tap *
  page63_i55
#ISCELL
  standard tap *
  page63_i56
#ISCELL
  standard tap *
  page63_i57
#ISCELL
  standard tap *
  page63_i58
#ISCELL
  standard tap *
  page63_i59
#ISCELL
  standard tap *
  page63_i6
#ISCELL
  standard tap *
  page63_i60
#ISCELL
  standard tap *
  page63_i61
#ISCELL
  standard tap *
  page63_i62
#ISCELL
  standard tap *
  page63_i63
#ISCELL
  standard tap *
  page63_i64
#ISCELL
  standard tap *
  page63_i65
#ISCELL
  standard tap *
  page63_i66
#ISCELL
  standard tap *
  page63_i67
#ISCELL
  standard tap *
  page63_i68
#ISCELL
  standard tap *
  page63_i69
#ISCELL
  standard tap *
  page63_i7
#ISCELL
  standard tap *
  page63_i70
#ISCELL
  standard tap *
  page63_i71
#ISCELL
  standard tap *
  page63_i72
#ISCELL
  standard tap *
  page63_i73
#ISCELL
  standard tap *
  page63_i74
#ISCELL
  standard tap *
  page63_i75
#ISCELL
  standard tap *
  page63_i76
#ISCELL
  standard tap *
  page63_i77
#ISCELL
  standard tap *
  page63_i78
#ISCELL
  standard tap *
  page63_i79
#ISCELL
  standard tap *
  page63_i8
#ISCELL
  standard tap *
  page63_i80
#ISCELL
  standard tap *
  page63_i81
#ISCELL
  standard tap *
  page63_i82
#ISCELL
  standard tap *
  page63_i83
#ISCELL
  standard tap *
  page63_i84
#ISCELL
  standard tap *
  page63_i85
#ISCELL
  standard tap *
  page63_i86
#ISCELL
  standard tap *
  page63_i87
#ISCELL
  standard tap *
  page63_i88
#ISCELL
  standard tap *
  page63_i89
#ISCELL
  standard tap *
  page63_i9
#ISCELL
  standard tap *
  page63_i90
#ISCELL
  standard tap *
  page63_i91
#ISCELL
  standard tap *
  page63_i92
#ISCELL
  standard tap *
  page63_i93
#ISCELL
  standard tap *
  page63_i94
#ISCELL
  standard tap *
  page63_i95
#ISCELL
  standard tap *
  page63_i96
#ISCELL
  standard tap *
  page63_i97
#ISCELL
  standard tap *
  page63_i98
#ISCELL
  standard tap *
  page63_i99
#ISCELL
  pure_quanta quanta_title_block_c *
  *
#ISCELL
  standard offpage *
  page64_i1
#ISCELL
  standard offpage *
  page64_i100
#ISCELL
  standard offpage *
  page64_i101
#ISCELL
  standard tap *
  page64_i102
#ISCELL
  standard tap *
  page64_i103
#ISCELL
  standard tap *
  page64_i104
#ISCELL
  standard tap *
  page64_i105
#ISCELL
  standard tap *
  page64_i106
#ISCELL
  standard tap *
  page64_i107
#ISCELL
  standard tap *
  page64_i108
#ISCELL
  standard tap *
  page64_i109
#ISCELL
  standard tap *
  page64_i110
#ISCELL
  standard tap *
  page64_i111
#ISCELL
  standard tap *
  page64_i112
#ISCELL
  standard tap *
  page64_i113
#ISCELL
  standard tap *
  page64_i114
#ISCELL
  standard tap *
  page64_i115
#ISCELL
  standard tap *
  page64_i116
#ISCELL
  standard tap *
  page64_i117
#ISCELL
  standard tap *
  page64_i118
#ISCELL
  standard tap *
  page64_i119
#ISCELL
  standard tap *
  page64_i120
#ISCELL
  standard tap *
  page64_i121
#ISCELL
  standard tap *
  page64_i122
#ISCELL
  standard tap *
  page64_i123
#ISCELL
  standard tap *
  page64_i124
#ISCELL
  standard tap *
  page64_i125
#ISCELL
  standard offpage *
  page64_i126
#ISCELL
  standard tap *
  page64_i15
#ISCELL
  standard tap *
  page64_i16
#ISCELL
  standard tap *
  page64_i19
#CELL
  pure_quanta socket4677_azif0045p001c01cs *
  page64_i21
#ISCELL
  standard tap *
  page64_i23
#ISCELL
  standard tap *
  page64_i25
#ISCELL
  standard tap *
  page64_i26
#ISCELL
  standard tap *
  page64_i28
#ISCELL
  standard tap *
  page64_i29
#ISCELL
  standard tap *
  page64_i30
#ISCELL
  standard tap *
  page64_i31
#ISCELL
  standard tap *
  page64_i32
#ISCELL
  standard tap *
  page64_i33
#ISCELL
  standard tap *
  page64_i34
#ISCELL
  standard tap *
  page64_i35
#ISCELL
  standard tap *
  page64_i36
#ISCELL
  standard tap *
  page64_i37
#ISCELL
  standard tap *
  page64_i38
#ISCELL
  standard tap *
  page64_i39
#ISCELL
  standard tap *
  page64_i41
#ISCELL
  standard tap *
  page64_i44
#ISCELL
  standard tap *
  page64_i45
#ISCELL
  standard tap *
  page64_i46
#ISCELL
  standard tap *
  page64_i47
#ISCELL
  standard tap *
  page64_i51
#ISCELL
  standard tap *
  page64_i52
#ISCELL
  standard tap *
  page64_i53
#ISCELL
  standard tap *
  page64_i54
#ISCELL
  standard tap *
  page64_i55
#ISCELL
  standard tap *
  page64_i56
#ISCELL
  standard tap *
  page64_i57
#ISCELL
  standard tap *
  page64_i58
#ISCELL
  standard tap *
  page64_i59
#ISCELL
  standard tap *
  page64_i60
#ISCELL
  standard tap *
  page64_i61
#ISCELL
  standard tap *
  page64_i62
#ISCELL
  standard tap *
  page64_i63
#ISCELL
  standard tap *
  page64_i64
#ISCELL
  standard tap *
  page64_i65
#ISCELL
  standard tap *
  page64_i66
#ISCELL
  standard tap *
  page64_i67
#ISCELL
  standard tap *
  page64_i68
#ISCELL
  standard tap *
  page64_i69
#ISCELL
  standard tap *
  page64_i70
#ISCELL
  standard tap *
  page64_i71
#ISCELL
  standard tap *
  page64_i72
#ISCELL
  standard tap *
  page64_i73
#ISCELL
  standard tap *
  page64_i74
#ISCELL
  standard tap *
  page64_i75
#ISCELL
  standard tap *
  page64_i76
#ISCELL
  standard tap *
  page64_i77
#ISCELL
  standard tap *
  page64_i78
#ISCELL
  standard tap *
  page64_i79
#ISCELL
  standard tap *
  page64_i80
#ISCELL
  standard tap *
  page64_i81
#ISCELL
  standard tap *
  page64_i82
#ISCELL
  standard tap *
  page64_i83
#ISCELL
  standard tap *
  page64_i84
#ISCELL
  standard tap *
  page64_i85
#ISCELL
  standard tap *
  page64_i86
#ISCELL
  standard tap *
  page64_i87
#ISCELL
  standard tap *
  page64_i88
#ISCELL
  standard tap *
  page64_i89
#ISCELL
  standard tap *
  page64_i90
#ISCELL
  standard tap *
  page64_i91
#ISCELL
  standard tap *
  page64_i92
#ISCELL
  standard tap *
  page64_i93
#ISCELL
  standard tap *
  page64_i94
#ISCELL
  standard tap *
  page64_i95
#ISCELL
  standard tap *
  page64_i96
#ISCELL
  standard tap *
  page64_i97
#ISCELL
  standard tap *
  page64_i98
#ISCELL
  standard tap *
  page64_i99
#ISCELL
  pure_quanta quanta_title_block_c *
  *
#ISCELL
  standard offpage *
  page65_i1
#ISCELL
  standard tap *
  page65_i10
#ISCELL
  standard offpage *
  page65_i100
#ISCELL
  standard offpage *
  page65_i101
#ISCELL
  standard tap *
  page65_i11
#ISCELL
  standard tap *
  page65_i12
#ISCELL
  standard tap *
  page65_i13
#ISCELL
  standard tap *
  page65_i14
#ISCELL
  standard tap *
  page65_i15
#CELL
  pure_quanta socket4677_azif0045p001c01cs *
  page65_i16
#ISCELL
  standard tap *
  page65_i17
#ISCELL
  standard tap *
  page65_i18
#ISCELL
  standard tap *
  page65_i19
#ISCELL
  standard offpage *
  page65_i2
#ISCELL
  standard tap *
  page65_i20
#ISCELL
  standard tap *
  page65_i21
#ISCELL
  standard tap *
  page65_i22
#ISCELL
  standard tap *
  page65_i23
#ISCELL
  standard tap *
  page65_i24
#ISCELL
  standard tap *
  page65_i25
#ISCELL
  standard tap *
  page65_i26
#ISCELL
  standard tap *
  page65_i27
#ISCELL
  standard tap *
  page65_i28
#ISCELL
  standard tap *
  page65_i29
#ISCELL
  standard tap *
  page65_i3
#ISCELL
  standard tap *
  page65_i30
#ISCELL
  standard tap *
  page65_i31
#ISCELL
  standard tap *
  page65_i32
#ISCELL
  standard tap *
  page65_i33
#ISCELL
  standard tap *
  page65_i34
#ISCELL
  standard tap *
  page65_i35
#ISCELL
  standard tap *
  page65_i36
#ISCELL
  standard tap *
  page65_i37
#ISCELL
  standard tap *
  page65_i38
#ISCELL
  standard tap *
  page65_i39
#ISCELL
  standard tap *
  page65_i4
#ISCELL
  standard tap *
  page65_i40
#ISCELL
  standard tap *
  page65_i41
#ISCELL
  standard tap *
  page65_i42
#ISCELL
  standard tap *
  page65_i43
#ISCELL
  standard tap *
  page65_i44
#ISCELL
  standard tap *
  page65_i45
#ISCELL
  standard tap *
  page65_i46
#ISCELL
  standard tap *
  page65_i47
#ISCELL
  standard tap *
  page65_i48
#ISCELL
  standard tap *
  page65_i49
#ISCELL
  standard tap *
  page65_i5
#ISCELL
  standard tap *
  page65_i50
#ISCELL
  standard tap *
  page65_i51
#ISCELL
  standard tap *
  page65_i52
#ISCELL
  standard tap *
  page65_i53
#ISCELL
  standard tap *
  page65_i54
#ISCELL
  standard tap *
  page65_i55
#ISCELL
  standard tap *
  page65_i56
#ISCELL
  standard tap *
  page65_i57
#ISCELL
  standard tap *
  page65_i58
#ISCELL
  standard tap *
  page65_i59
#ISCELL
  standard tap *
  page65_i6
#ISCELL
  standard tap *
  page65_i60
#ISCELL
  standard tap *
  page65_i61
#ISCELL
  standard tap *
  page65_i62
#ISCELL
  standard tap *
  page65_i63
#ISCELL
  standard tap *
  page65_i64
#ISCELL
  standard tap *
  page65_i65
#ISCELL
  standard tap *
  page65_i66
#ISCELL
  standard tap *
  page65_i67
#ISCELL
  standard tap *
  page65_i68
#ISCELL
  standard tap *
  page65_i69
#ISCELL
  standard tap *
  page65_i7
#ISCELL
  standard tap *
  page65_i70
#ISCELL
  standard tap *
  page65_i71
#ISCELL
  standard tap *
  page65_i72
#ISCELL
  standard tap *
  page65_i73
#ISCELL
  standard tap *
  page65_i74
#ISCELL
  standard tap *
  page65_i75
#ISCELL
  standard tap *
  page65_i76
#ISCELL
  standard tap *
  page65_i77
#ISCELL
  standard tap *
  page65_i78
#ISCELL
  standard tap *
  page65_i79
#ISCELL
  standard tap *
  page65_i8
#ISCELL
  standard tap *
  page65_i80
#ISCELL
  standard tap *
  page65_i81
#ISCELL
  standard tap *
  page65_i82
#ISCELL
  standard tap *
  page65_i83
#ISCELL
  standard tap *
  page65_i84
#ISCELL
  standard tap *
  page65_i85
#ISCELL
  standard tap *
  page65_i86
#ISCELL
  standard tap *
  page65_i87
#ISCELL
  standard tap *
  page65_i88
#ISCELL
  standard tap *
  page65_i89
#ISCELL
  standard tap *
  page65_i9
#ISCELL
  standard tap *
  page65_i90
#ISCELL
  standard tap *
  page65_i91
#ISCELL
  standard tap *
  page65_i92
#ISCELL
  standard tap *
  page65_i93
#ISCELL
  standard tap *
  page65_i94
#ISCELL
  standard tap *
  page65_i95
#ISCELL
  standard tap *
  page65_i96
#ISCELL
  standard tap *
  page65_i97
#ISCELL
  standard tap *
  page65_i98
#ISCELL
  standard tap *
  page65_i99
#ISCELL
  pure_quanta quanta_title_block_c *
  *
#CELL
  pure_quanta socket4677_azif0045p001c01cs *
  page66_i16
#ISCELL
  logical_power universal_gnd *
  page66_i17
#ISCELL
  pure_quanta quanta_title_block_c *
  *
#CELL
  pure_quanta socket4677_azif0045p001c01cs *
  page67_i1
#ISCELL
  logical_power vcc_core *
  page67_i2
#CELL
  pure_quanta socket4677_azif0045p001c01cs *
  page67_i3
#ISCELL
  logical_power vcc_core *
  page67_i4
#ISCELL
  logical_power vcc_core *
  page67_i5
#ISCELL
  logical_power vcc_core *
  page67_i6
#ISCELL
  pure_quanta quanta_title_block_c *
  *
#CELL
  pure_quanta socket4677_azif0045p001c01cs *
  page68_i1
#ISCELL
  logical_power vcc_core *
  page68_i10
#ISCELL
  logical_power vcc_core *
  page68_i11
#ISCELL
  logical_power vcc_core *
  page68_i12
#ISCELL
  logical_power vcc_core *
  page68_i13
#ISCELL
  logical_power vcc_core *
  page68_i2
#ISCELL
  logical_power vcc_core *
  page68_i3
#CELL
  pure_quanta q_cap *
  page68_i4
#ISCELL
  logical_power universal_gnd *
  page68_i5
#ISCELL
  logical_power vcc_core *
  page68_i6
#ISCELL
  logical_power vcc_core *
  page68_i7
#CELL
  pure_quanta socket4677_azif0045p001c01cs *
  page68_i8
#ISCELL
  logical_power vcc_core *
  page68_i9
#ISCELL
  pure_quanta quanta_title_block_c *
  *
#CELL
  pure_quanta socket4677_azif0045p001c01cs *
  page69_i1
#ISCELL
  logical_power vcc_core *
  page69_i2
#ISCELL
  logical_power vcc_core *
  page69_i3
#ISCELL
  pure_quanta quanta_title_block_c *
  *
#ISCELL
  logical_power universal_gnd *
  page70_i1
#CELL
  pure_quanta socket4677_azif0045p001c01cs *
  page70_i2
#ISCELL
  logical_power universal_gnd *
  page70_i3
#ISCELL
  logical_power universal_gnd *
  page70_i4
#CELL
  pure_quanta socket4677_azif0045p001c01cs *
  page70_i5
#ISCELL
  logical_power universal_gnd *
  page70_i6
#ISCELL
  logical_power universal_gnd *
  page70_i7
#CELL
  pure_quanta socket4677_azif0045p001c01cs *
  page70_i8
#ISCELL
  logical_power universal_gnd *
  page70_i9
#ISCELL
  pure_quanta quanta_title_block_c *
  *
#ISCELL
  logical_power universal_gnd *
  page71_i1
#CELL
  pure_quanta socket4677_azif0045p001c01cs *
  page71_i2
#ISCELL
  logical_power universal_gnd *
  page71_i3
#ISCELL
  logical_power universal_gnd *
  page71_i4
#CELL
  pure_quanta socket4677_azif0045p001c01cs *
  page71_i5
#ISCELL
  logical_power universal_gnd *
  page71_i6
#ISCELL
  logical_power universal_gnd *
  page71_i7
#CELL
  pure_quanta socket4677_azif0045p001c01cs *
  page71_i8
#ISCELL
  logical_power universal_gnd *
  page71_i9
#ISCELL
  pure_quanta quanta_title_block_c *
  *
#ISCELL
  logical_power universal_gnd *
  page72_i1
#CELL
  pure_quanta socket4677_azif0045p001c01cs *
  page72_i2
#ISCELL
  logical_power universal_gnd *
  page72_i3
#ISCELL
  logical_power universal_gnd *
  page72_i4
#CELL
  pure_quanta socket4677_azif0045p001c01cs *
  page72_i5
#ISCELL
  logical_power universal_gnd *
  page72_i6
#ISCELL
  logical_power universal_gnd *
  page72_i7
#CELL
  pure_quanta socket4677_azif0045p001c01cs *
  page72_i8
#ISCELL
  logical_power universal_gnd *
  page72_i9
#ISCELL
  pure_quanta quanta_title_block_c *
  *
#ISCELL
  logical_power universal_gnd *
  page73_i1
#CELL
  pure_quanta socket4677_azif0045p001c01cs *
  page73_i2
#ISCELL
  logical_power universal_gnd *
  page73_i3
#ISCELL
  logical_power universal_gnd *
  page73_i4
#CELL
  pure_quanta socket4677_azif0045p001c01cs *
  page73_i5
#ISCELL
  logical_power universal_gnd *
  page73_i6
#ISCELL
  logical_power universal_gnd *
  page73_i7
#CELL
  pure_quanta socket4677_azif0045p001c01cs *
  page73_i8
#ISCELL
  pure_quanta quanta_title_block_c *
  *
#CELL
  pure_quanta q_cap *
  page74_i1
#CELL
  pure_quanta q_cap *
  page74_i10
#CELL
  pure_quanta q_cap *
  page74_i100
#ISCELL
  logical_power universal_gnd *
  page74_i101
#CELL
  pure_quanta q_cap *
  page74_i102
#CELL
  pure_quanta q_cap *
  page74_i103
#ISCELL
  logical_power universal_power *
  page74_i104
#CELL
  pure_quanta q_cap *
  page74_i105
#CELL
  pure_quanta q_cap *
  page74_i106
#CELL
  pure_quanta q_cap *
  page74_i107
#CELL
  pure_quanta q_cap *
  page74_i108
#CELL
  pure_quanta q_cap *
  page74_i109
#CELL
  pure_quanta q_cap *
  page74_i11
#CELL
  pure_quanta q_cap *
  page74_i110
#CELL
  pure_quanta q_cap *
  page74_i111
#CELL
  pure_quanta q_cap *
  page74_i112
#CELL
  pure_quanta q_cap *
  page74_i113
#CELL
  pure_quanta q_cap *
  page74_i114
#CELL
  pure_quanta q_cap *
  page74_i115
#CELL
  pure_quanta q_cap *
  page74_i116
#CELL
  pure_quanta q_cap *
  page74_i117
#CELL
  pure_quanta q_cap *
  page74_i118
#CELL
  pure_quanta q_cap *
  page74_i119
#ISCELL
  logical_power universal_power *
  page74_i12
#CELL
  pure_quanta q_cap *
  page74_i120
#CELL
  pure_quanta q_cap *
  page74_i121
#CELL
  pure_quanta q_cap *
  page74_i122
#CELL
  pure_quanta q_cap *
  page74_i123
#CELL
  pure_quanta q_cap *
  page74_i124
#CELL
  pure_quanta q_cap *
  page74_i125
#ISCELL
  logical_power universal_power *
  page74_i126
#CELL
  pure_quanta q_cap *
  page74_i127
#CELL
  pure_quanta q_cap *
  page74_i128
#ISCELL
  logical_power universal_gnd *
  page74_i129
#CELL
  pure_quanta q_cap *
  page74_i13
#CELL
  pure_quanta q_cap *
  page74_i130
#CELL
  pure_quanta q_cap *
  page74_i131
#CELL
  pure_quanta q_cap *
  page74_i132
#CELL
  pure_quanta q_cap *
  page74_i133
#CELL
  pure_quanta q_cap *
  page74_i134
#CELL
  pure_quanta q_cap *
  page74_i135
#ISCELL
  logical_power universal_gnd *
  page74_i136
#CELL
  pure_quanta q_cap *
  page74_i137
#ISCELL
  logical_power universal_gnd *
  page74_i138
#CELL
  pure_quanta q_cap *
  page74_i139
#ISCELL
  logical_power universal_power *
  page74_i14
#ISCELL
  logical_power universal_gnd *
  page74_i140
#CELL
  pure_quanta q_cap *
  page74_i141
#CELL
  pure_quanta q_cap *
  page74_i142
#CELL
  pure_quanta q_cap *
  page74_i15
#ISCELL
  logical_power universal_power *
  page74_i16
#CELL
  pure_quanta q_cap *
  page74_i17
#CELL
  pure_quanta q_cap *
  page74_i18
#CELL
  pure_quanta q_cap *
  page74_i19
#ISCELL
  logical_power universal_power *
  page74_i2
#CELL
  pure_quanta q_cap *
  page74_i20
#CELL
  pure_quanta q_cap *
  page74_i21
#CELL
  pure_quanta q_cap *
  page74_i22
#CELL
  pure_quanta q_cap *
  page74_i23
#ISCELL
  logical_power universal_power *
  page74_i24
#CELL
  pure_quanta q_cap *
  page74_i25
#ISCELL
  logical_power universal_power *
  page74_i26
#CELL
  pure_quanta q_cap *
  page74_i27
#CELL
  pure_quanta q_cap *
  page74_i28
#CELL
  pure_quanta q_cap *
  page74_i29
#CELL
  pure_quanta q_cap *
  page74_i3
#CELL
  pure_quanta q_cap *
  page74_i30
#CELL
  pure_quanta q_cap *
  page74_i31
#CELL
  pure_quanta q_cap *
  page74_i32
#CELL
  pure_quanta q_cap *
  page74_i33
#CELL
  pure_quanta q_cap *
  page74_i34
#CELL
  pure_quanta q_cap *
  page74_i35
#CELL
  pure_quanta q_cap *
  page74_i36
#CELL
  pure_quanta q_cap *
  page74_i37
#CELL
  pure_quanta q_cap *
  page74_i38
#ISCELL
  logical_power universal_power *
  page74_i39
#CELL
  pure_quanta q_cap *
  page74_i4
#CELL
  pure_quanta q_cap *
  page74_i40
#CELL
  pure_quanta q_cap *
  page74_i41
#CELL
  pure_quanta q_cap *
  page74_i42
#CELL
  pure_quanta q_cap *
  page74_i43
#CELL
  pure_quanta q_cap *
  page74_i44
#CELL
  pure_quanta q_cap *
  page74_i45
#CELL
  pure_quanta q_cap *
  page74_i46
#CELL
  pure_quanta q_cap *
  page74_i47
#CELL
  pure_quanta q_cap *
  page74_i48
#CELL
  pure_quanta q_cap *
  page74_i49
#CELL
  pure_quanta q_cap *
  page74_i5
#CELL
  pure_quanta q_cap *
  page74_i50
#CELL
  pure_quanta q_cap *
  page74_i51
#CELL
  pure_quanta q_cap *
  page74_i52
#CELL
  pure_quanta q_cap *
  page74_i53
#CELL
  pure_quanta q_cap *
  page74_i54
#CELL
  pure_quanta q_cap *
  page74_i55
#CELL
  pure_quanta q_cap *
  page74_i56
#CELL
  pure_quanta q_cap *
  page74_i57
#CELL
  pure_quanta q_cap *
  page74_i58
#CELL
  pure_quanta q_cap *
  page74_i59
#ISCELL
  logical_power universal_gnd *
  page74_i6
#CELL
  pure_quanta q_cap *
  page74_i60
#CELL
  pure_quanta q_cap *
  page74_i61
#CELL
  pure_quanta q_cap *
  page74_i62
#ISCELL
  logical_power universal_power *
  page74_i63
#CELL
  pure_quanta q_cap *
  page74_i64
#CELL
  pure_quanta q_cap *
  page74_i65
#ISCELL
  logical_power universal_gnd *
  page74_i66
#ISCELL
  logical_power universal_gnd *
  page74_i67
#CELL
  pure_quanta q_cap *
  page74_i68
#ISCELL
  logical_power universal_gnd *
  page74_i69
#CELL
  pure_quanta q_cap *
  page74_i7
#CELL
  pure_quanta q_cap *
  page74_i70
#CELL
  pure_quanta q_cap *
  page74_i71
#CELL
  pure_quanta q_cap *
  page74_i72
#ISCELL
  logical_power universal_gnd *
  page74_i73
#CELL
  pure_quanta q_cap *
  page74_i74
#CELL
  pure_quanta q_cap *
  page74_i75
#ISCELL
  logical_power universal_gnd *
  page74_i76
#CELL
  pure_quanta q_cap *
  page74_i77
#CELL
  pure_quanta q_cap *
  page74_i78
#ISCELL
  logical_power universal_power *
  page74_i79
#CELL
  pure_quanta q_cap *
  page74_i8
#CELL
  pure_quanta q_cap *
  page74_i80
#CELL
  pure_quanta q_cap *
  page74_i81
#ISCELL
  logical_power universal_gnd *
  page74_i82
#CELL
  pure_quanta q_cap *
  page74_i83
#ISCELL
  logical_power universal_gnd *
  page74_i84
#CELL
  pure_quanta q_cap *
  page74_i85
#CELL
  pure_quanta q_cap *
  page74_i86
#CELL
  pure_quanta q_cap *
  page74_i87
#ISCELL
  logical_power universal_gnd *
  page74_i88
#CELL
  pure_quanta q_cap *
  page74_i89
#CELL
  pure_quanta q_cap *
  page74_i9
#CELL
  pure_quanta q_cap *
  page74_i90
#ISCELL
  logical_power universal_power *
  page74_i91
#CELL
  pure_quanta q_cap *
  page74_i92
#CELL
  pure_quanta q_cap *
  page74_i93
#ISCELL
  logical_power universal_power *
  page74_i94
#CELL
  pure_quanta q_cap *
  page74_i95
#CELL
  pure_quanta q_cap *
  page74_i96
#CELL
  pure_quanta q_cap *
  page74_i97
#CELL
  pure_quanta q_cap *
  page74_i98
#ISCELL
  logical_power universal_power *
  page74_i99
#ISCELL
  pure_quanta quanta_title_block_c *
  *
#CELL
  pure_quanta q_cap *
  page75_i1
#ISCELL
  logical_power universal_power *
  page75_i10
#CELL
  pure_quanta q_cap *
  page75_i11
#ISCELL
  logical_power universal_power *
  page75_i12
#CELL
  pure_quanta q_cap *
  page75_i13
#CELL
  pure_quanta q_cap *
  page75_i14
#ISCELL
  logical_power universal_gnd *
  page75_i15
#CELL
  pure_quanta q_cap *
  page75_i16
#CELL
  pure_quanta q_cap *
  page75_i17
#CELL
  pure_quanta q_cap *
  page75_i18
#CELL
  pure_quanta q_cap *
  page75_i19
#ISCELL
  logical_power universal_power *
  page75_i2
#ISCELL
  logical_power universal_power *
  page75_i20
#CELL
  pure_quanta q_cap *
  page75_i21
#ISCELL
  logical_power universal_power *
  page75_i22
#CELL
  pure_quanta q_cap *
  page75_i23
#ISCELL
  logical_power universal_power *
  page75_i24
#CELL
  pure_quanta q_cap *
  page75_i25
#CELL
  pure_quanta q_cap *
  page75_i26
#CELL
  pure_quanta q_cap *
  page75_i27
#CELL
  pure_quanta q_cap *
  page75_i28
#CELL
  pure_quanta q_cap *
  page75_i29
#CELL
  pure_quanta q_cap *
  page75_i3
#ISCELL
  logical_power universal_gnd *
  page75_i30
#CELL
  pure_quanta q_cap *
  page75_i31
#CELL
  pure_quanta q_cap *
  page75_i32
#CELL
  pure_quanta q_cap *
  page75_i33
#CELL
  pure_quanta q_cap *
  page75_i34
#CELL
  pure_quanta q_cap *
  page75_i35
#CELL
  pure_quanta q_cap *
  page75_i36
#CELL
  pure_quanta q_cap *
  page75_i37
#CELL
  pure_quanta q_cap *
  page75_i38
#CELL
  pure_quanta q_cap *
  page75_i39
#CELL
  pure_quanta q_cap *
  page75_i4
#CELL
  pure_quanta q_cap *
  page75_i40
#CELL
  pure_quanta q_cap *
  page75_i41
#ISCELL
  logical_power universal_power *
  page75_i42
#CELL
  pure_quanta q_cap *
  page75_i43
#CELL
  pure_quanta q_cap *
  page75_i44
#ISCELL
  logical_power universal_power *
  page75_i45
#CELL
  pure_quanta q_cap *
  page75_i46
#CELL
  pure_quanta q_cap *
  page75_i47
#CELL
  pure_quanta q_cap *
  page75_i48
#CELL
  pure_quanta q_cap *
  page75_i49
#ISCELL
  logical_power universal_gnd *
  page75_i5
#CELL
  pure_quanta q_cap *
  page75_i50
#CELL
  pure_quanta q_cap *
  page75_i51
#CELL
  pure_quanta q_cap *
  page75_i52
#ISCELL
  logical_power universal_gnd *
  page75_i53
#CELL
  pure_quanta q_cap *
  page75_i54
#CELL
  pure_quanta q_cap *
  page75_i55
#CELL
  pure_quanta q_cap *
  page75_i56
#ISCELL
  logical_power universal_gnd *
  page75_i57
#CELL
  pure_quanta q_cap *
  page75_i58
#CELL
  pure_quanta q_cap *
  page75_i59
#CELL
  pure_quanta q_cap *
  page75_i6
#ISCELL
  logical_power universal_gnd *
  page75_i60
#CELL
  pure_quanta q_cap *
  page75_i61
#CELL
  pure_quanta q_cap *
  page75_i62
#ISCELL
  logical_power universal_gnd *
  page75_i63
#CELL
  pure_quanta q_cap *
  page75_i64
#ISCELL
  logical_power universal_power *
  page75_i65
#ISCELL
  logical_power universal_gnd *
  page75_i66
#CELL
  pure_quanta q_cap *
  page75_i67
#CELL
  pure_quanta q_cap *
  page75_i68
#ISCELL
  logical_power universal_gnd *
  page75_i7
#CELL
  pure_quanta q_cap *
  page75_i8
#CELL
  pure_quanta q_cap *
  page75_i9
#ISCELL
  pure_quanta quanta_title_block_c *
  *
#CELL
  pure_quanta q_cap *
  page76_i1
#CELL
  pure_quanta q_cap *
  page76_i10
#CELL
  pure_quanta q_cap *
  page76_i11
#ISCELL
  logical_power universal_power *
  page76_i12
#CELL
  pure_quanta q_cap *
  page76_i13
#CELL
  pure_quanta q_cap *
  page76_i14
#ISCELL
  logical_power universal_gnd *
  page76_i15
#CELL
  pure_quanta q_cap *
  page76_i16
#ISCELL
  logical_power universal_power *
  page76_i17
#CELL
  pure_quanta q_cap *
  page76_i18
#ISCELL
  logical_power universal_power *
  page76_i19
#CELL
  pure_quanta q_cap *
  page76_i2
#CELL
  pure_quanta q_cap *
  page76_i20
#CELL
  pure_quanta q_cap *
  page76_i21
#CELL
  pure_quanta q_cap *
  page76_i22
#CELL
  pure_quanta q_cap *
  page76_i23
#ISCELL
  logical_power universal_power *
  page76_i24
#CELL
  pure_quanta q_cap *
  page76_i25
#CELL
  pure_quanta q_cap *
  page76_i26
#CELL
  pure_quanta q_cap *
  page76_i27
#CELL
  pure_quanta q_cap *
  page76_i28
#CELL
  pure_quanta q_cap *
  page76_i29
#CELL
  pure_quanta q_cap *
  page76_i3
#ISCELL
  logical_power universal_gnd *
  page76_i30
#CELL
  pure_quanta q_cap *
  page76_i31
#CELL
  pure_quanta q_cap *
  page76_i32
#CELL
  pure_quanta q_cap *
  page76_i33
#ISCELL
  logical_power universal_gnd *
  page76_i34
#CELL
  pure_quanta q_cap *
  page76_i35
#CELL
  pure_quanta q_cap *
  page76_i36
#CELL
  pure_quanta q_cap *
  page76_i37
#CELL
  pure_quanta q_cap *
  page76_i38
#CELL
  pure_quanta q_cap *
  page76_i39
#ISCELL
  logical_power universal_power *
  page76_i4
#ISCELL
  logical_power universal_gnd *
  page76_i40
#CELL
  pure_quanta q_cap *
  page76_i41
#ISCELL
  logical_power universal_gnd *
  page76_i42
#CELL
  pure_quanta q_cap *
  page76_i43
#CELL
  pure_quanta q_cap *
  page76_i44
#CELL
  pure_quanta q_cap *
  page76_i45
#CELL
  pure_quanta q_cap *
  page76_i46
#CELL
  pure_quanta q_cap *
  page76_i47
#CELL
  pure_quanta q_cap *
  page76_i48
#CELL
  pure_quanta q_cap *
  page76_i49
#CELL
  pure_quanta q_cap *
  page76_i5
#CELL
  pure_quanta q_cap *
  page76_i50
#CELL
  pure_quanta q_cap *
  page76_i51
#CELL
  pure_quanta q_cap *
  page76_i52
#CELL
  pure_quanta q_cap *
  page76_i53
#CELL
  pure_quanta q_cap *
  page76_i54
#ISCELL
  logical_power universal_gnd *
  page76_i55
#CELL
  pure_quanta q_cap *
  page76_i6
#CELL
  pure_quanta q_cap *
  page76_i7
#ISCELL
  logical_power universal_power *
  page76_i8
#CELL
  pure_quanta q_cap *
  page76_i9
#ISCELL
  pure_quanta quanta_title_block_c *
  *
#CELL
  pure_quanta q_cap *
  page77_i1
#CELL
  pure_quanta q_cap *
  page77_i10
#CELL
  pure_quanta q_cap *
  page77_i100
#CELL
  pure_quanta q_cap *
  page77_i101
#CELL
  pure_quanta q_cap *
  page77_i102
#CELL
  pure_quanta q_cap *
  page77_i103
#CELL
  pure_quanta q_cap *
  page77_i104
#CELL
  pure_quanta q_cap *
  page77_i105
#CELL
  pure_quanta q_cap *
  page77_i106
#ISCELL
  logical_power universal_power *
  page77_i107
#ISCELL
  logical_power universal_gnd *
  page77_i108
#CELL
  pure_quanta q_cap *
  page77_i109
#CELL
  pure_quanta q_cap *
  page77_i11
#CELL
  pure_quanta q_cap *
  page77_i110
#CELL
  pure_quanta q_cap *
  page77_i111
#CELL
  pure_quanta q_cap *
  page77_i112
#CELL
  pure_quanta q_cap *
  page77_i113
#CELL
  pure_quanta q_cap *
  page77_i114
#CELL
  pure_quanta q_cap *
  page77_i115
#ISCELL
  logical_power universal_gnd *
  page77_i116
#CELL
  pure_quanta q_cap *
  page77_i117
#CELL
  pure_quanta q_cap *
  page77_i118
#CELL
  pure_quanta q_cap *
  page77_i119
#ISCELL
  logical_power universal_power *
  page77_i12
#CELL
  pure_quanta q_cap *
  page77_i120
#CELL
  pure_quanta q_cap *
  page77_i121
#CELL
  pure_quanta q_cap *
  page77_i122
#CELL
  pure_quanta q_cap *
  page77_i123
#CELL
  pure_quanta q_cap *
  page77_i124
#CELL
  pure_quanta q_cap *
  page77_i125
#CELL
  pure_quanta q_cap *
  page77_i126
#CELL
  pure_quanta q_cap *
  page77_i127
#CELL
  pure_quanta q_cap *
  page77_i128
#CELL
  pure_quanta q_cap *
  page77_i129
#CELL
  pure_quanta q_cap *
  page77_i13
#CELL
  pure_quanta q_cap *
  page77_i130
#CELL
  pure_quanta q_cap *
  page77_i131
#CELL
  pure_quanta q_cap *
  page77_i132
#CELL
  pure_quanta q_cap *
  page77_i133
#CELL
  pure_quanta q_cap *
  page77_i134
#ISCELL
  logical_power universal_gnd *
  page77_i135
#CELL
  pure_quanta q_cap *
  page77_i136
#ISCELL
  logical_power universal_gnd *
  page77_i137
#CELL
  pure_quanta q_cap *
  page77_i138
#CELL
  pure_quanta q_cap *
  page77_i139
#CELL
  pure_quanta q_cap *
  page77_i14
#CELL
  pure_quanta q_cap *
  page77_i140
#ISCELL
  logical_power universal_gnd *
  page77_i141
#CELL
  pure_quanta q_cap *
  page77_i142
#CELL
  pure_quanta q_cap *
  page77_i15
#CELL
  pure_quanta q_cap *
  page77_i16
#CELL
  pure_quanta q_cap *
  page77_i17
#CELL
  pure_quanta q_cap *
  page77_i18
#CELL
  pure_quanta q_cap *
  page77_i19
#CELL
  pure_quanta q_cap *
  page77_i2
#CELL
  pure_quanta q_cap *
  page77_i20
#ISCELL
  logical_power universal_power *
  page77_i21
#CELL
  pure_quanta q_cap *
  page77_i22
#CELL
  pure_quanta q_cap *
  page77_i23
#ISCELL
  logical_power universal_power *
  page77_i24
#CELL
  pure_quanta q_cap *
  page77_i25
#CELL
  pure_quanta q_cap *
  page77_i26
#ISCELL
  logical_power universal_power *
  page77_i27
#CELL
  pure_quanta q_cap *
  page77_i28
#CELL
  pure_quanta q_cap *
  page77_i29
#ISCELL
  logical_power universal_power *
  page77_i3
#CELL
  pure_quanta q_cap *
  page77_i30
#CELL
  pure_quanta q_cap *
  page77_i31
#CELL
  pure_quanta q_cap *
  page77_i32
#CELL
  pure_quanta q_cap *
  page77_i33
#CELL
  pure_quanta q_cap *
  page77_i34
#CELL
  pure_quanta q_cap *
  page77_i35
#ISCELL
  logical_power universal_power *
  page77_i36
#CELL
  pure_quanta q_cap *
  page77_i37
#CELL
  pure_quanta q_cap *
  page77_i38
#CELL
  pure_quanta q_cap *
  page77_i39
#CELL
  pure_quanta q_cap *
  page77_i4
#CELL
  pure_quanta q_cap *
  page77_i40
#CELL
  pure_quanta q_cap *
  page77_i41
#CELL
  pure_quanta q_cap *
  page77_i42
#ISCELL
  logical_power universal_power *
  page77_i43
#CELL
  pure_quanta q_cap *
  page77_i44
#CELL
  pure_quanta q_cap *
  page77_i45
#CELL
  pure_quanta q_cap *
  page77_i46
#CELL
  pure_quanta q_cap *
  page77_i47
#CELL
  pure_quanta q_cap *
  page77_i48
#CELL
  pure_quanta q_cap *
  page77_i49
#CELL
  pure_quanta q_cap *
  page77_i5
#CELL
  pure_quanta q_cap *
  page77_i50
#CELL
  pure_quanta q_cap *
  page77_i51
#CELL
  pure_quanta q_cap *
  page77_i52
#CELL
  pure_quanta q_cap *
  page77_i53
#ISCELL
  logical_power universal_gnd *
  page77_i54
#CELL
  pure_quanta q_cap *
  page77_i55
#ISCELL
  logical_power universal_gnd *
  page77_i56
#CELL
  pure_quanta q_cap *
  page77_i57
#CELL
  pure_quanta q_cap *
  page77_i58
#CELL
  pure_quanta q_cap *
  page77_i59
#ISCELL
  logical_power universal_gnd *
  page77_i6
#ISCELL
  logical_power universal_gnd *
  page77_i60
#CELL
  pure_quanta q_cap *
  page77_i61
#CELL
  pure_quanta q_cap *
  page77_i62
#CELL
  pure_quanta q_cap *
  page77_i63
#CELL
  pure_quanta q_cap *
  page77_i64
#ISCELL
  logical_power universal_gnd *
  page77_i65
#CELL
  pure_quanta q_cap *
  page77_i66
#CELL
  pure_quanta q_cap *
  page77_i67
#ISCELL
  logical_power universal_power *
  page77_i68
#ISCELL
  logical_power universal_gnd *
  page77_i69
#CELL
  pure_quanta q_cap *
  page77_i7
#CELL
  pure_quanta q_cap *
  page77_i70
#CELL
  pure_quanta q_cap *
  page77_i71
#ISCELL
  logical_power universal_power *
  page77_i72
#CELL
  pure_quanta q_cap *
  page77_i73
#CELL
  pure_quanta q_cap *
  page77_i74
#CELL
  pure_quanta q_cap *
  page77_i75
#CELL
  pure_quanta q_cap *
  page77_i76
#CELL
  pure_quanta q_cap *
  page77_i77
#CELL
  pure_quanta q_cap *
  page77_i78
#CELL
  pure_quanta q_cap *
  page77_i79
#CELL
  pure_quanta q_cap *
  page77_i8
#CELL
  pure_quanta q_cap *
  page77_i80
#CELL
  pure_quanta q_cap *
  page77_i81
#CELL
  pure_quanta q_cap *
  page77_i82
#CELL
  pure_quanta q_cap *
  page77_i83
#CELL
  pure_quanta q_cap *
  page77_i84
#CELL
  pure_quanta q_cap *
  page77_i85
#CELL
  pure_quanta q_cap *
  page77_i86
#ISCELL
  logical_power universal_gnd *
  page77_i87
#CELL
  pure_quanta q_cap *
  page77_i88
#ISCELL
  logical_power universal_gnd *
  page77_i89
#ISCELL
  logical_power universal_power *
  page77_i9
#ISCELL
  logical_power universal_power *
  page77_i90
#CELL
  pure_quanta q_cap *
  page77_i91
#ISCELL
  logical_power universal_power *
  page77_i92
#CELL
  pure_quanta q_cap *
  page77_i93
#CELL
  pure_quanta q_cap *
  page77_i94
#CELL
  pure_quanta q_cap *
  page77_i95
#ISCELL
  logical_power universal_gnd *
  page77_i96
#CELL
  pure_quanta q_cap *
  page77_i97
#CELL
  pure_quanta q_cap *
  page77_i98
#ISCELL
  logical_power universal_power *
  page77_i99
#ISCELL
  pure_quanta quanta_title_block_c *
  *
#CELL
  pure_quanta q_cap *
  page78_i1
#CELL
  pure_quanta q_cap *
  page78_i10
#ISCELL
  logical_power universal_power *
  page78_i11
#CELL
  pure_quanta q_cap *
  page78_i12
#ISCELL
  logical_power universal_power *
  page78_i13
#CELL
  pure_quanta q_cap *
  page78_i14
#ISCELL
  logical_power universal_power *
  page78_i15
#CELL
  pure_quanta q_cap *
  page78_i16
#ISCELL
  logical_power universal_power *
  page78_i17
#CELL
  pure_quanta q_cap *
  page78_i18
#CELL
  pure_quanta q_cap *
  page78_i19
#ISCELL
  logical_power universal_power *
  page78_i2
#ISCELL
  logical_power universal_gnd *
  page78_i20
#CELL
  pure_quanta q_cap *
  page78_i21
#ISCELL
  logical_power universal_gnd *
  page78_i22
#CELL
  pure_quanta q_cap *
  page78_i23
#CELL
  pure_quanta q_cap *
  page78_i24
#CELL
  pure_quanta q_cap *
  page78_i25
#CELL
  pure_quanta q_cap *
  page78_i26
#CELL
  pure_quanta q_cap *
  page78_i27
#ISCELL
  logical_power universal_gnd *
  page78_i28
#CELL
  pure_quanta q_cap *
  page78_i29
#CELL
  pure_quanta q_cap *
  page78_i3
#CELL
  pure_quanta q_cap *
  page78_i30
#CELL
  pure_quanta q_cap *
  page78_i31
#CELL
  pure_quanta q_cap *
  page78_i32
#CELL
  pure_quanta q_cap *
  page78_i33
#CELL
  pure_quanta q_cap *
  page78_i34
#CELL
  pure_quanta q_cap *
  page78_i35
#CELL
  pure_quanta q_cap *
  page78_i36
#CELL
  pure_quanta q_cap *
  page78_i37
#CELL
  pure_quanta q_cap *
  page78_i38
#CELL
  pure_quanta q_cap *
  page78_i39
#CELL
  pure_quanta q_cap *
  page78_i4
#CELL
  pure_quanta q_cap *
  page78_i40
#CELL
  pure_quanta q_cap *
  page78_i41
#CELL
  pure_quanta q_cap *
  page78_i42
#CELL
  pure_quanta q_cap *
  page78_i43
#CELL
  pure_quanta q_cap *
  page78_i44
#CELL
  pure_quanta q_cap *
  page78_i45
#CELL
  pure_quanta q_cap *
  page78_i46
#ISCELL
  logical_power universal_power *
  page78_i47
#CELL
  pure_quanta q_cap *
  page78_i48
#CELL
  pure_quanta q_cap *
  page78_i49
#CELL
  pure_quanta q_cap *
  page78_i5
#ISCELL
  logical_power universal_power *
  page78_i50
#CELL
  pure_quanta q_cap *
  page78_i51
#CELL
  pure_quanta q_cap *
  page78_i52
#CELL
  pure_quanta q_cap *
  page78_i53
#ISCELL
  logical_power universal_gnd *
  page78_i54
#CELL
  pure_quanta q_cap *
  page78_i55
#ISCELL
  logical_power universal_gnd *
  page78_i56
#CELL
  pure_quanta q_cap *
  page78_i57
#CELL
  pure_quanta q_cap *
  page78_i58
#ISCELL
  logical_power universal_gnd *
  page78_i59
#ISCELL
  logical_power universal_gnd *
  page78_i6
#CELL
  pure_quanta q_cap *
  page78_i60
#ISCELL
  logical_power universal_gnd *
  page78_i61
#ISCELL
  logical_power universal_gnd *
  page78_i62
#CELL
  pure_quanta q_cap *
  page78_i63
#CELL
  pure_quanta q_cap *
  page78_i64
#CELL
  pure_quanta q_cap *
  page78_i65
#CELL
  pure_quanta q_cap *
  page78_i66
#ISCELL
  logical_power universal_power *
  page78_i67
#CELL
  pure_quanta q_cap *
  page78_i68
#CELL
  pure_quanta q_cap *
  page78_i7
#CELL
  pure_quanta q_cap *
  page78_i8
#ISCELL
  logical_power universal_power *
  page78_i9
#ISCELL
  pure_quanta quanta_title_block_c *
  *
#CELL
  pure_quanta q_cap *
  page79_i1
#CELL
  pure_quanta q_cap *
  page79_i10
#CELL
  pure_quanta q_cap *
  page79_i11
#CELL
  pure_quanta q_cap *
  page79_i12
#CELL
  pure_quanta q_cap *
  page79_i13
#ISCELL
  logical_power universal_power *
  page79_i14
#CELL
  pure_quanta q_cap *
  page79_i15
#CELL
  pure_quanta q_cap *
  page79_i16
#CELL
  pure_quanta q_cap *
  page79_i17
#ISCELL
  logical_power universal_power *
  page79_i18
#CELL
  pure_quanta q_cap *
  page79_i19
#ISCELL
  logical_power universal_power *
  page79_i2
#CELL
  pure_quanta q_cap *
  page79_i20
#CELL
  pure_quanta q_cap *
  page79_i21
#ISCELL
  logical_power universal_power *
  page79_i22
#CELL
  pure_quanta q_cap *
  page79_i23
#CELL
  pure_quanta q_cap *
  page79_i24
#CELL
  pure_quanta q_cap *
  page79_i25
#CELL
  pure_quanta q_cap *
  page79_i26
#CELL
  pure_quanta q_cap *
  page79_i27
#ISCELL
  logical_power universal_gnd *
  page79_i28
#CELL
  pure_quanta q_cap *
  page79_i29
#CELL
  pure_quanta q_cap *
  page79_i3
#ISCELL
  logical_power universal_gnd *
  page79_i30
#CELL
  pure_quanta q_cap *
  page79_i31
#CELL
  pure_quanta q_cap *
  page79_i32
#CELL
  pure_quanta q_cap *
  page79_i33
#CELL
  pure_quanta q_cap *
  page79_i34
#CELL
  pure_quanta q_cap *
  page79_i35
#ISCELL
  logical_power universal_power *
  page79_i36
#CELL
  pure_quanta q_cap *
  page79_i37
#CELL
  pure_quanta q_cap *
  page79_i38
#CELL
  pure_quanta q_cap *
  page79_i39
#CELL
  pure_quanta q_cap *
  page79_i4
#ISCELL
  logical_power universal_gnd *
  page79_i40
#CELL
  pure_quanta q_cap *
  page79_i41
#CELL
  pure_quanta q_cap *
  page79_i42
#CELL
  pure_quanta q_cap *
  page79_i43
#CELL
  pure_quanta q_cap *
  page79_i44
#ISCELL
  logical_power universal_power *
  page79_i45
#CELL
  pure_quanta q_cap *
  page79_i46
#CELL
  pure_quanta q_cap *
  page79_i47
#ISCELL
  logical_power universal_gnd *
  page79_i48
#CELL
  pure_quanta q_cap *
  page79_i49
#CELL
  pure_quanta q_cap *
  page79_i5
#CELL
  pure_quanta q_cap *
  page79_i50
#CELL
  pure_quanta q_cap *
  page79_i51
#CELL
  pure_quanta q_cap *
  page79_i52
#CELL
  pure_quanta q_cap *
  page79_i53
#ISCELL
  logical_power universal_gnd *
  page79_i54
#CELL
  pure_quanta q_cap *
  page79_i55
#ISCELL
  logical_power universal_gnd *
  page79_i6
#CELL
  pure_quanta q_cap *
  page79_i7
#CELL
  pure_quanta q_cap *
  page79_i8
#CELL
  pure_quanta q_cap *
  page79_i9
#ISCELL
  mstr_misc dns *
  *
#ISCELL
  pure_quanta quanta_title_block_c *
  *
#CELL
  pure_quanta q_res *
  page80_i1
#ISCELL
  logical_power universal_power *
  page80_i10
#ISCELL
  logical_power universal_power *
  page80_i11
#CELL
  pure_quanta q_res *
  page80_i12
#CELL
  pure_quanta q_res *
  page80_i13
#ISCELL
  standard offpage *
  page80_i14
#ISCELL
  standard offpage *
  page80_i15
#ISCELL
  standard offpage *
  page80_i16
#ISCELL
  standard offpage *
  page80_i17
#ISCELL
  logical_power universal_power *
  page80_i18
#ISCELL
  logical_power universal_gnd *
  page80_i19
#CELL
  pure_quanta q_res *
  page80_i2
#CELL
  pure_quanta q_cap *
  page80_i20
#ISCELL
  logical_power universal_power *
  page80_i21
#CELL
  pure_quanta q_res *
  page80_i22
#ISCELL
  standard offpage *
  page80_i23
#ISCELL
  standard offpage *
  page80_i24
#CELL
  pure_quanta q_res *
  page80_i25
#CELL
  pure_quanta q_res *
  page80_i26
#CELL
  pure_quanta q_res *
  page80_i27
#CELL
  pure_quanta q_cap *
  page80_i28
#ISCELL
  standard offpage *
  page80_i29
#ISCELL
  logical_power universal_power *
  page80_i3
#ISCELL
  standard offpage *
  page80_i30
#ISCELL
  logical_power universal_power *
  page80_i31
#ISCELL
  logical_power universal_power *
  page80_i32
#ISCELL
  logical_power universal_power *
  page80_i33
#CELL
  pure_quanta q_res *
  page80_i34
#CELL
  pure_quanta q_res *
  page80_i35
#ISCELL
  logical_power universal_power *
  page80_i36
#ISCELL
  logical_power universal_gnd *
  page80_i4
#CELL
  pure_quanta q_cap *
  page80_i5
#ISCELL
  logical_power universal_power *
  page80_i6
#CELL
  pure_quanta q_res *
  page80_i7
#CELL
  pure_quanta q_res *
  page80_i8
#CELL
  pure_quanta q_cap *
  page80_i9
#ISCELL
  pure_quanta quanta_title_block_c *
  *
#ISCELL
  logical_power bom_note *
  *
#ISCELL
  logical_power cad_note *
  *
#ISCELL
  pure_quanta quanta_title_block_c *
  *
#ISCELL
  standard tap *
  page82_i10
#ISCELL
  standard offpage *
  page82_i100
#ISCELL
  standard offpage *
  page82_i101
#ISCELL
  standard offpage *
  page82_i102
#ISCELL
  standard offpage *
  page82_i103
#ISCELL
  standard tap *
  page82_i104
#ISCELL
  standard tap *
  page82_i105
#ISCELL
  standard tap *
  page82_i106
#ISCELL
  standard tap *
  page82_i107
#ISCELL
  standard tap *
  page82_i108
#ISCELL
  standard tap *
  page82_i109
#ISCELL
  standard tap *
  page82_i11
#ISCELL
  standard tap *
  page82_i110
#ISCELL
  standard tap *
  page82_i111
#ISCELL
  standard tap *
  page82_i112
#ISCELL
  standard tap *
  page82_i113
#ISCELL
  standard tap *
  page82_i114
#ISCELL
  standard tap *
  page82_i115
#ISCELL
  standard tap *
  page82_i116
#ISCELL
  standard tap *
  page82_i117
#ISCELL
  standard tap *
  page82_i118
#ISCELL
  standard tap *
  page82_i119
#ISCELL
  standard tap *
  page82_i12
#ISCELL
  standard tap *
  page82_i120
#ISCELL
  standard tap *
  page82_i121
#ISCELL
  standard tap *
  page82_i122
#ISCELL
  standard tap *
  page82_i123
#ISCELL
  standard tap *
  page82_i124
#ISCELL
  standard tap *
  page82_i125
#ISCELL
  standard tap *
  page82_i126
#ISCELL
  standard tap *
  page82_i128
#ISCELL
  standard tap *
  page82_i129
#ISCELL
  standard tap *
  page82_i13
#ISCELL
  standard tap *
  page82_i130
#ISCELL
  standard tap *
  page82_i131
#ISCELL
  standard offpage *
  page82_i132
#ISCELL
  standard tap *
  page82_i133
#ISCELL
  standard tap *
  page82_i134
#ISCELL
  standard tap *
  page82_i135
#ISCELL
  standard tap *
  page82_i136
#ISCELL
  standard tap *
  page82_i137
#ISCELL
  standard tap *
  page82_i138
#ISCELL
  standard offpage *
  page82_i139
#ISCELL
  standard offpage *
  page82_i14
#ISCELL
  standard tap *
  page82_i140
#ISCELL
  standard offpage *
  page82_i142
#ISCELL
  standard offpage *
  page82_i143
#ISCELL
  standard offpage *
  page82_i144
#ISCELL
  standard offpage *
  page82_i145
#ISCELL
  standard offpage *
  page82_i146
#ISCELL
  standard offpage *
  page82_i147
#ISCELL
  standard offpage *
  page82_i148
#ISCELL
  standard offpage *
  page82_i149
#ISCELL
  standard tap *
  page82_i15
#ISCELL
  standard tap *
  page82_i157
#ISCELL
  standard tap *
  page82_i158
#ISCELL
  standard tap *
  page82_i16
#ISCELL
  standard tap *
  page82_i160
#ISCELL
  standard tap *
  page82_i161
#ISCELL
  standard tap *
  page82_i162
#ISCELL
  standard tap *
  page82_i163
#ISCELL
  standard tap *
  page82_i164
#ISCELL
  standard tap *
  page82_i165
#ISCELL
  standard offpage *
  page82_i166
#ISCELL
  standard tap *
  page82_i167
#ISCELL
  standard tap *
  page82_i168
#ISCELL
  standard tap *
  page82_i169
#ISCELL
  standard tap *
  page82_i17
#ISCELL
  standard tap *
  page82_i170
#ISCELL
  standard tap *
  page82_i171
#ISCELL
  standard tap *
  page82_i172
#ISCELL
  standard tap *
  page82_i173
#ISCELL
  standard tap *
  page82_i174
#ISCELL
  standard offpage *
  page82_i175
#ISCELL
  standard offpage *
  page82_i176
#ISCELL
  standard offpage *
  page82_i177
#ISCELL
  standard offpage *
  page82_i178
#ISCELL
  standard tap *
  page82_i18
#ISCELL
  standard offpage *
  page82_i180
#ISCELL
  standard offpage *
  page82_i181
#ISCELL
  standard offpage *
  page82_i182
#ISCELL
  logical_power vcc_core *
  page82_i183
#ISCELL
  logical_power universal_gnd *
  page82_i184
#ISCELL
  logical_power universal_gnd *
  page82_i185
#ISCELL
  logical_power vcc_core *
  page82_i186
#ISCELL
  logical_power vcc_core *
  page82_i187
#CELL
  pure_quanta q_cap *
  page82_i188
#ISCELL
  standard tap *
  page82_i19
#CELL
  pure_quanta q_cap *
  page82_i190
#ISCELL
  logical_power universal_gnd *
  page82_i191
#CELL
  pure_quanta q_cap *
  page82_i192
#ISCELL
  logical_power vcc_core *
  page82_i193
#ISCELL
  logical_power universal_gnd *
  page82_i194
#ISCELL
  standard offpage *
  page82_i195
#CELL
  pure_quanta q_res *
  page82_i196
#ISCELL
  logical_power universal_gnd *
  page82_i197
#CELL
  pure_quanta sconn288_adr50017p130cc *
  page82_i198
#ISCELL
  standard tap *
  page82_i20
#ISCELL
  standard offpage *
  page82_i201
#CELL
  pure_quanta sconn288_adr50017p130cc *
  page82_i202
#CELL
  pure_quanta sconn288_adr50017p130cc *
  page82_i203
#CELL
  pure_quanta q_res *
  page82_i204
#ISCELL
  standard offpage *
  page82_i205
#ISCELL
  standard tap *
  page82_i21
#ISCELL
  standard tap *
  page82_i22
#ISCELL
  standard tap *
  page82_i23
#ISCELL
  standard tap *
  page82_i24
#ISCELL
  standard tap *
  page82_i25
#ISCELL
  standard tap *
  page82_i26
#ISCELL
  standard tap *
  page82_i27
#ISCELL
  standard tap *
  page82_i28
#ISCELL
  standard tap *
  page82_i29
#ISCELL
  standard tap *
  page82_i30
#ISCELL
  standard tap *
  page82_i31
#ISCELL
  standard tap *
  page82_i32
#ISCELL
  standard tap *
  page82_i33
#ISCELL
  standard tap *
  page82_i34
#ISCELL
  standard tap *
  page82_i35
#ISCELL
  standard tap *
  page82_i36
#ISCELL
  standard tap *
  page82_i37
#ISCELL
  standard tap *
  page82_i38
#ISCELL
  standard tap *
  page82_i39
#ISCELL
  standard tap *
  page82_i4
#ISCELL
  standard tap *
  page82_i40
#ISCELL
  standard tap *
  page82_i41
#ISCELL
  standard tap *
  page82_i42
#ISCELL
  standard tap *
  page82_i43
#ISCELL
  standard tap *
  page82_i44
#ISCELL
  standard tap *
  page82_i45
#ISCELL
  standard tap *
  page82_i46
#ISCELL
  standard tap *
  page82_i47
#ISCELL
  standard tap *
  page82_i48
#ISCELL
  standard tap *
  page82_i49
#ISCELL
  standard tap *
  page82_i5
#ISCELL
  standard tap *
  page82_i50
#ISCELL
  standard tap *
  page82_i51
#ISCELL
  standard tap *
  page82_i52
#ISCELL
  standard tap *
  page82_i53
#ISCELL
  standard tap *
  page82_i54
#ISCELL
  standard tap *
  page82_i55
#ISCELL
  standard tap *
  page82_i56
#ISCELL
  standard tap *
  page82_i57
#ISCELL
  standard tap *
  page82_i58
#ISCELL
  standard tap *
  page82_i59
#ISCELL
  standard tap *
  page82_i6
#ISCELL
  standard tap *
  page82_i60
#ISCELL
  standard tap *
  page82_i61
#ISCELL
  standard tap *
  page82_i62
#ISCELL
  standard tap *
  page82_i63
#ISCELL
  standard tap *
  page82_i64
#ISCELL
  standard tap *
  page82_i65
#ISCELL
  standard tap *
  page82_i66
#ISCELL
  standard tap *
  page82_i67
#ISCELL
  standard offpage *
  page82_i68
#ISCELL
  standard tap *
  page82_i69
#ISCELL
  standard tap *
  page82_i7
#ISCELL
  standard tap *
  page82_i72
#ISCELL
  standard tap *
  page82_i74
#ISCELL
  standard tap *
  page82_i75
#ISCELL
  standard tap *
  page82_i78
#ISCELL
  standard tap *
  page82_i8
#ISCELL
  standard tap *
  page82_i80
#ISCELL
  standard tap *
  page82_i82
#ISCELL
  standard tap *
  page82_i84
#ISCELL
  standard tap *
  page82_i87
#ISCELL
  standard tap *
  page82_i88
#ISCELL
  standard tap *
  page82_i89
#ISCELL
  standard tap *
  page82_i9
#ISCELL
  standard tap *
  page82_i90
#ISCELL
  standard tap *
  page82_i91
#ISCELL
  standard tap *
  page82_i92
#ISCELL
  standard tap *
  page82_i93
#ISCELL
  standard tap *
  page82_i94
#ISCELL
  standard tap *
  page82_i95
#ISCELL
  standard tap *
  page82_i96
#ISCELL
  standard tap *
  page82_i97
#ISCELL
  standard tap *
  page82_i98
#ISCELL
  standard tap *
  page82_i99
#ISCELL
  logical_power bom_note *
  *
#ISCELL
  logical_power cad_note *
  *
#ISCELL
  pure_quanta quanta_title_block_c *
  *
#ISCELL
  logical_power universal_gnd *
  page83_i1
#CELL
  pure_quanta q_res *
  page83_i10
#ISCELL
  standard tap *
  page83_i100
#ISCELL
  standard tap *
  page83_i101
#ISCELL
  standard tap *
  page83_i102
#ISCELL
  standard tap *
  page83_i103
#ISCELL
  standard tap *
  page83_i104
#ISCELL
  standard tap *
  page83_i105
#ISCELL
  standard tap *
  page83_i106
#ISCELL
  standard tap *
  page83_i107
#ISCELL
  standard offpage *
  page83_i108
#ISCELL
  standard tap *
  page83_i109
#ISCELL
  standard tap *
  page83_i110
#ISCELL
  standard tap *
  page83_i111
#ISCELL
  standard tap *
  page83_i112
#ISCELL
  standard tap *
  page83_i113
#ISCELL
  standard tap *
  page83_i114
#ISCELL
  standard tap *
  page83_i115
#ISCELL
  standard tap *
  page83_i116
#ISCELL
  standard tap *
  page83_i117
#ISCELL
  standard tap *
  page83_i118
#ISCELL
  logical_power vcc_core *
  page83_i119
#ISCELL
  standard offpage *
  page83_i12
#CELL
  pure_quanta q_cap *
  page83_i120
#ISCELL
  logical_power universal_gnd *
  page83_i121
#CELL
  pure_quanta q_cap *
  page83_i122
#ISCELL
  logical_power vcc_core *
  page83_i123
#ISCELL
  standard offpage *
  page83_i124
#ISCELL
  standard tap *
  page83_i126
#ISCELL
  standard tap *
  page83_i127
#ISCELL
  standard tap *
  page83_i128
#ISCELL
  standard tap *
  page83_i129
#ISCELL
  logical_power vcc_core *
  page83_i13
#ISCELL
  standard tap *
  page83_i130
#ISCELL
  standard tap *
  page83_i131
#ISCELL
  standard tap *
  page83_i132
#ISCELL
  standard tap *
  page83_i133
#ISCELL
  standard tap *
  page83_i134
#ISCELL
  standard tap *
  page83_i135
#ISCELL
  standard tap *
  page83_i136
#ISCELL
  standard tap *
  page83_i137
#ISCELL
  standard tap *
  page83_i138
#ISCELL
  standard tap *
  page83_i139
#ISCELL
  standard offpage *
  page83_i14
#ISCELL
  standard tap *
  page83_i140
#ISCELL
  standard tap *
  page83_i141
#ISCELL
  standard tap *
  page83_i142
#ISCELL
  logical_power universal_gnd *
  page83_i143
#CELL
  pure_quanta q_cap *
  page83_i144
#ISCELL
  logical_power universal_gnd *
  page83_i145
#ISCELL
  standard tap *
  page83_i147
#ISCELL
  standard tap *
  page83_i148
#ISCELL
  standard tap *
  page83_i149
#ISCELL
  standard offpage *
  page83_i15
#ISCELL
  standard tap *
  page83_i150
#ISCELL
  standard tap *
  page83_i151
#ISCELL
  standard tap *
  page83_i152
#ISCELL
  standard tap *
  page83_i153
#ISCELL
  standard tap *
  page83_i154
#ISCELL
  standard tap *
  page83_i155
#ISCELL
  standard tap *
  page83_i156
#ISCELL
  standard tap *
  page83_i157
#ISCELL
  standard tap *
  page83_i158
#ISCELL
  standard tap *
  page83_i159
#ISCELL
  standard offpage *
  page83_i16
#ISCELL
  standard tap *
  page83_i160
#ISCELL
  standard tap *
  page83_i161
#ISCELL
  standard tap *
  page83_i162
#ISCELL
  standard tap *
  page83_i163
#ISCELL
  standard tap *
  page83_i164
#ISCELL
  standard offpage *
  page83_i165
#ISCELL
  standard offpage *
  page83_i166
#ISCELL
  standard offpage *
  page83_i167
#ISCELL
  standard tap *
  page83_i168
#ISCELL
  standard tap *
  page83_i169
#ISCELL
  standard offpage *
  page83_i17
#ISCELL
  standard tap *
  page83_i170
#ISCELL
  standard tap *
  page83_i171
#ISCELL
  standard tap *
  page83_i172
#ISCELL
  standard offpage *
  page83_i173
#ISCELL
  standard offpage *
  page83_i174
#ISCELL
  logical_power vcc_core *
  page83_i175
#ISCELL
  logical_power universal_gnd *
  page83_i176
#CELL
  pure_quanta sconn288_adr50017p087cc *
  page83_i177
#CELL
  pure_quanta sconn288_adr50017p087cc *
  page83_i179
#ISCELL
  standard offpage *
  page83_i18
#ISCELL
  standard offpage *
  page83_i180
#CELL
  pure_quanta sconn288_adr50017p087cc *
  page83_i181
#CELL
  pure_quanta q_res *
  page83_i182
#ISCELL
  standard offpage *
  page83_i183
#ISCELL
  standard offpage *
  page83_i19
#ISCELL
  standard offpage *
  page83_i2
#ISCELL
  standard offpage *
  page83_i20
#ISCELL
  standard offpage *
  page83_i21
#ISCELL
  standard offpage *
  page83_i22
#ISCELL
  standard offpage *
  page83_i23
#ISCELL
  standard tap *
  page83_i24
#ISCELL
  standard tap *
  page83_i25
#ISCELL
  standard tap *
  page83_i26
#ISCELL
  standard tap *
  page83_i27
#ISCELL
  standard tap *
  page83_i28
#ISCELL
  standard tap *
  page83_i29
#ISCELL
  standard offpage *
  page83_i3
#ISCELL
  standard tap *
  page83_i30
#ISCELL
  standard tap *
  page83_i31
#ISCELL
  standard tap *
  page83_i32
#ISCELL
  standard tap *
  page83_i33
#ISCELL
  standard tap *
  page83_i34
#ISCELL
  standard tap *
  page83_i35
#ISCELL
  standard tap *
  page83_i36
#ISCELL
  standard tap *
  page83_i37
#ISCELL
  standard tap *
  page83_i38
#ISCELL
  standard tap *
  page83_i39
#ISCELL
  standard offpage *
  page83_i4
#ISCELL
  standard tap *
  page83_i40
#ISCELL
  standard tap *
  page83_i41
#ISCELL
  standard tap *
  page83_i42
#ISCELL
  standard tap *
  page83_i43
#ISCELL
  standard tap *
  page83_i44
#ISCELL
  standard tap *
  page83_i45
#ISCELL
  standard tap *
  page83_i46
#ISCELL
  standard tap *
  page83_i47
#ISCELL
  standard tap *
  page83_i48
#ISCELL
  standard tap *
  page83_i49
#ISCELL
  standard tap *
  page83_i50
#ISCELL
  standard tap *
  page83_i51
#ISCELL
  standard tap *
  page83_i52
#ISCELL
  standard tap *
  page83_i53
#ISCELL
  standard tap *
  page83_i54
#ISCELL
  standard tap *
  page83_i55
#ISCELL
  standard tap *
  page83_i56
#ISCELL
  standard tap *
  page83_i57
#ISCELL
  standard tap *
  page83_i58
#ISCELL
  standard tap *
  page83_i59
#ISCELL
  standard offpage *
  page83_i6
#ISCELL
  standard tap *
  page83_i60
#ISCELL
  standard tap *
  page83_i61
#ISCELL
  standard tap *
  page83_i62
#ISCELL
  standard tap *
  page83_i63
#ISCELL
  standard tap *
  page83_i64
#ISCELL
  standard tap *
  page83_i65
#ISCELL
  standard tap *
  page83_i66
#ISCELL
  standard tap *
  page83_i67
#ISCELL
  standard tap *
  page83_i68
#ISCELL
  standard tap *
  page83_i69
#ISCELL
  standard offpage *
  page83_i7
#ISCELL
  standard tap *
  page83_i70
#ISCELL
  standard tap *
  page83_i71
#ISCELL
  standard tap *
  page83_i72
#ISCELL
  standard tap *
  page83_i73
#ISCELL
  standard tap *
  page83_i74
#ISCELL
  standard tap *
  page83_i75
#ISCELL
  standard tap *
  page83_i76
#ISCELL
  standard tap *
  page83_i77
#ISCELL
  standard tap *
  page83_i78
#ISCELL
  standard tap *
  page83_i79
#ISCELL
  standard offpage *
  page83_i8
#ISCELL
  standard tap *
  page83_i80
#ISCELL
  standard tap *
  page83_i81
#ISCELL
  standard tap *
  page83_i82
#ISCELL
  standard tap *
  page83_i83
#ISCELL
  standard tap *
  page83_i84
#ISCELL
  standard tap *
  page83_i85
#ISCELL
  standard tap *
  page83_i86
#ISCELL
  standard tap *
  page83_i87
#ISCELL
  standard tap *
  page83_i88
#ISCELL
  standard tap *
  page83_i89
#ISCELL
  standard offpage *
  page83_i9
#ISCELL
  standard tap *
  page83_i90
#ISCELL
  standard tap *
  page83_i91
#ISCELL
  standard tap *
  page83_i92
#ISCELL
  standard tap *
  page83_i93
#ISCELL
  standard tap *
  page83_i94
#ISCELL
  standard tap *
  page83_i95
#ISCELL
  standard tap *
  page83_i96
#ISCELL
  standard tap *
  page83_i97
#ISCELL
  standard tap *
  page83_i98
#ISCELL
  standard tap *
  page83_i99
#ISCELL
  logical_power cad_note *
  *
#ISCELL
  pure_quanta quanta_title_block_c *
  *
#ISCELL
  logical_power universal_gnd *
  page84_i1
#CELL
  pure_quanta q_res *
  page84_i10
#ISCELL
  standard tap *
  page84_i100
#ISCELL
  standard tap *
  page84_i101
#ISCELL
  standard tap *
  page84_i102
#ISCELL
  standard tap *
  page84_i103
#ISCELL
  standard tap *
  page84_i104
#ISCELL
  standard tap *
  page84_i105
#ISCELL
  standard tap *
  page84_i106
#ISCELL
  standard tap *
  page84_i107
#ISCELL
  standard offpage *
  page84_i108
#ISCELL
  standard tap *
  page84_i109
#ISCELL
  standard tap *
  page84_i110
#ISCELL
  standard tap *
  page84_i111
#ISCELL
  standard tap *
  page84_i112
#ISCELL
  standard tap *
  page84_i113
#ISCELL
  standard tap *
  page84_i114
#ISCELL
  standard tap *
  page84_i115
#ISCELL
  standard tap *
  page84_i116
#ISCELL
  standard tap *
  page84_i117
#ISCELL
  standard tap *
  page84_i118
#ISCELL
  logical_power vcc_core *
  page84_i119
#ISCELL
  standard offpage *
  page84_i12
#ISCELL
  logical_power universal_gnd *
  page84_i120
#CELL
  pure_quanta q_cap *
  page84_i121
#CELL
  pure_quanta q_cap *
  page84_i122
#ISCELL
  logical_power vcc_core *
  page84_i123
#ISCELL
  standard offpage *
  page84_i124
#ISCELL
  standard tap *
  page84_i126
#ISCELL
  standard tap *
  page84_i127
#ISCELL
  standard tap *
  page84_i128
#ISCELL
  standard tap *
  page84_i129
#ISCELL
  logical_power vcc_core *
  page84_i13
#ISCELL
  standard tap *
  page84_i130
#ISCELL
  standard tap *
  page84_i131
#ISCELL
  standard tap *
  page84_i132
#ISCELL
  standard tap *
  page84_i133
#ISCELL
  standard tap *
  page84_i134
#ISCELL
  standard tap *
  page84_i135
#ISCELL
  standard tap *
  page84_i136
#ISCELL
  standard tap *
  page84_i137
#ISCELL
  standard tap *
  page84_i138
#ISCELL
  standard tap *
  page84_i139
#ISCELL
  standard offpage *
  page84_i14
#ISCELL
  standard tap *
  page84_i140
#ISCELL
  standard tap *
  page84_i141
#ISCELL
  standard tap *
  page84_i142
#ISCELL
  logical_power universal_gnd *
  page84_i143
#CELL
  pure_quanta q_cap *
  page84_i144
#ISCELL
  logical_power universal_gnd *
  page84_i145
#ISCELL
  standard tap *
  page84_i147
#ISCELL
  standard tap *
  page84_i148
#ISCELL
  standard tap *
  page84_i149
#ISCELL
  standard offpage *
  page84_i15
#ISCELL
  standard tap *
  page84_i150
#ISCELL
  standard tap *
  page84_i151
#ISCELL
  standard tap *
  page84_i152
#ISCELL
  standard tap *
  page84_i153
#ISCELL
  standard tap *
  page84_i154
#ISCELL
  standard tap *
  page84_i155
#ISCELL
  standard tap *
  page84_i156
#ISCELL
  standard tap *
  page84_i157
#ISCELL
  standard tap *
  page84_i158
#ISCELL
  standard tap *
  page84_i159
#ISCELL
  standard offpage *
  page84_i16
#ISCELL
  standard tap *
  page84_i160
#ISCELL
  standard tap *
  page84_i161
#ISCELL
  standard tap *
  page84_i162
#ISCELL
  standard tap *
  page84_i163
#ISCELL
  standard tap *
  page84_i164
#ISCELL
  standard offpage *
  page84_i165
#ISCELL
  standard offpage *
  page84_i166
#ISCELL
  standard offpage *
  page84_i167
#ISCELL
  standard tap *
  page84_i168
#ISCELL
  standard tap *
  page84_i169
#ISCELL
  standard offpage *
  page84_i17
#ISCELL
  standard tap *
  page84_i170
#ISCELL
  standard tap *
  page84_i171
#ISCELL
  standard tap *
  page84_i172
#ISCELL
  standard offpage *
  page84_i173
#ISCELL
  standard offpage *
  page84_i174
#ISCELL
  logical_power vcc_core *
  page84_i175
#ISCELL
  logical_power universal_gnd *
  page84_i176
#ISCELL
  standard offpage *
  page84_i177
#CELL
  pure_quanta sconn288_adr50017p130cc *
  page84_i178
#CELL
  pure_quanta sconn288_adr50017p130cc *
  page84_i179
#ISCELL
  standard offpage *
  page84_i18
#CELL
  pure_quanta sconn288_adr50017p130cc *
  page84_i180
#CELL
  pure_quanta q_res *
  page84_i182
#ISCELL
  standard offpage *
  page84_i183
#ISCELL
  standard offpage *
  page84_i19
#ISCELL
  standard offpage *
  page84_i2
#ISCELL
  standard offpage *
  page84_i20
#ISCELL
  standard offpage *
  page84_i21
#ISCELL
  standard offpage *
  page84_i22
#ISCELL
  standard offpage *
  page84_i23
#ISCELL
  standard tap *
  page84_i24
#ISCELL
  standard tap *
  page84_i25
#ISCELL
  standard tap *
  page84_i26
#ISCELL
  standard tap *
  page84_i27
#ISCELL
  standard tap *
  page84_i28
#ISCELL
  standard tap *
  page84_i29
#ISCELL
  standard offpage *
  page84_i3
#ISCELL
  standard tap *
  page84_i30
#ISCELL
  standard tap *
  page84_i31
#ISCELL
  standard tap *
  page84_i32
#ISCELL
  standard tap *
  page84_i33
#ISCELL
  standard tap *
  page84_i34
#ISCELL
  standard tap *
  page84_i35
#ISCELL
  standard tap *
  page84_i36
#ISCELL
  standard tap *
  page84_i37
#ISCELL
  standard tap *
  page84_i38
#ISCELL
  standard tap *
  page84_i39
#ISCELL
  standard offpage *
  page84_i4
#ISCELL
  standard tap *
  page84_i40
#ISCELL
  standard tap *
  page84_i41
#ISCELL
  standard tap *
  page84_i42
#ISCELL
  standard tap *
  page84_i43
#ISCELL
  standard tap *
  page84_i44
#ISCELL
  standard tap *
  page84_i45
#ISCELL
  standard tap *
  page84_i46
#ISCELL
  standard tap *
  page84_i47
#ISCELL
  standard tap *
  page84_i48
#ISCELL
  standard tap *
  page84_i49
#ISCELL
  standard tap *
  page84_i50
#ISCELL
  standard tap *
  page84_i51
#ISCELL
  standard tap *
  page84_i52
#ISCELL
  standard tap *
  page84_i53
#ISCELL
  standard tap *
  page84_i54
#ISCELL
  standard tap *
  page84_i55
#ISCELL
  standard tap *
  page84_i56
#ISCELL
  standard tap *
  page84_i57
#ISCELL
  standard tap *
  page84_i58
#ISCELL
  standard tap *
  page84_i59
#ISCELL
  standard offpage *
  page84_i6
#ISCELL
  standard tap *
  page84_i60
#ISCELL
  standard tap *
  page84_i61
#ISCELL
  standard tap *
  page84_i62
#ISCELL
  standard tap *
  page84_i63
#ISCELL
  standard tap *
  page84_i64
#ISCELL
  standard tap *
  page84_i65
#ISCELL
  standard tap *
  page84_i66
#ISCELL
  standard tap *
  page84_i67
#ISCELL
  standard tap *
  page84_i68
#ISCELL
  standard tap *
  page84_i69
#ISCELL
  standard offpage *
  page84_i7
#ISCELL
  standard tap *
  page84_i70
#ISCELL
  standard tap *
  page84_i71
#ISCELL
  standard tap *
  page84_i72
#ISCELL
  standard tap *
  page84_i73
#ISCELL
  standard tap *
  page84_i74
#ISCELL
  standard tap *
  page84_i75
#ISCELL
  standard tap *
  page84_i76
#ISCELL
  standard tap *
  page84_i77
#ISCELL
  standard tap *
  page84_i78
#ISCELL
  standard tap *
  page84_i79
#ISCELL
  standard offpage *
  page84_i8
#ISCELL
  standard tap *
  page84_i80
#ISCELL
  standard tap *
  page84_i81
#ISCELL
  standard tap *
  page84_i82
#ISCELL
  standard tap *
  page84_i83
#ISCELL
  standard tap *
  page84_i84
#ISCELL
  standard tap *
  page84_i85
#ISCELL
  standard tap *
  page84_i86
#ISCELL
  standard tap *
  page84_i87
#ISCELL
  standard tap *
  page84_i88
#ISCELL
  standard tap *
  page84_i89
#ISCELL
  standard offpage *
  page84_i9
#ISCELL
  standard tap *
  page84_i90
#ISCELL
  standard tap *
  page84_i91
#ISCELL
  standard tap *
  page84_i92
#ISCELL
  standard tap *
  page84_i93
#ISCELL
  standard tap *
  page84_i94
#ISCELL
  standard tap *
  page84_i95
#ISCELL
  standard tap *
  page84_i96
#ISCELL
  standard tap *
  page84_i97
#ISCELL
  standard tap *
  page84_i98
#ISCELL
  standard tap *
  page84_i99
#ISCELL
  logical_power cad_note *
  *
#ISCELL
  pure_quanta quanta_title_block_c *
  *
#CELL
  pure_quanta q_res *
  page85_i1
#ISCELL
  standard offpage *
  page85_i10
#ISCELL
  standard tap *
  page85_i100
#ISCELL
  standard tap *
  page85_i101
#ISCELL
  standard tap *
  page85_i102
#ISCELL
  standard tap *
  page85_i103
#ISCELL
  standard tap *
  page85_i104
#ISCELL
  standard tap *
  page85_i105
#ISCELL
  standard tap *
  page85_i106
#ISCELL
  standard tap *
  page85_i107
#ISCELL
  standard tap *
  page85_i108
#ISCELL
  standard tap *
  page85_i109
#ISCELL
  logical_power vcc_core *
  page85_i11
#ISCELL
  standard tap *
  page85_i110
#ISCELL
  standard tap *
  page85_i111
#ISCELL
  standard offpage *
  page85_i112
#ISCELL
  standard tap *
  page85_i113
#ISCELL
  standard tap *
  page85_i114
#ISCELL
  standard tap *
  page85_i115
#ISCELL
  standard tap *
  page85_i116
#ISCELL
  standard tap *
  page85_i117
#ISCELL
  standard tap *
  page85_i118
#ISCELL
  logical_power universal_gnd *
  page85_i119
#ISCELL
  standard offpage *
  page85_i12
#ISCELL
  logical_power universal_gnd *
  page85_i120
#CELL
  pure_quanta q_cap *
  page85_i121
#ISCELL
  logical_power vcc_core *
  page85_i122
#ISCELL
  standard offpage *
  page85_i123
#CELL
  pure_quanta q_cap *
  page85_i125
#ISCELL
  logical_power vcc_core *
  page85_i126
#CELL
  pure_quanta q_cap *
  page85_i127
#ISCELL
  standard tap *
  page85_i128
#ISCELL
  standard tap *
  page85_i129
#ISCELL
  standard offpage *
  page85_i13
#ISCELL
  standard tap *
  page85_i130
#ISCELL
  standard tap *
  page85_i131
#ISCELL
  standard tap *
  page85_i132
#ISCELL
  standard tap *
  page85_i133
#ISCELL
  standard tap *
  page85_i134
#ISCELL
  standard tap *
  page85_i135
#ISCELL
  standard tap *
  page85_i136
#ISCELL
  standard tap *
  page85_i137
#ISCELL
  standard tap *
  page85_i138
#ISCELL
  standard tap *
  page85_i139
#ISCELL
  standard offpage *
  page85_i14
#ISCELL
  standard tap *
  page85_i140
#ISCELL
  standard tap *
  page85_i141
#ISCELL
  standard tap *
  page85_i142
#ISCELL
  standard tap *
  page85_i143
#ISCELL
  standard tap *
  page85_i144
#ISCELL
  standard tap *
  page85_i145
#ISCELL
  standard tap *
  page85_i146
#ISCELL
  standard tap *
  page85_i147
#ISCELL
  standard tap *
  page85_i148
#ISCELL
  standard tap *
  page85_i149
#ISCELL
  standard offpage *
  page85_i15
#ISCELL
  standard tap *
  page85_i150
#ISCELL
  standard tap *
  page85_i151
#ISCELL
  standard tap *
  page85_i152
#ISCELL
  standard tap *
  page85_i153
#ISCELL
  standard tap *
  page85_i154
#ISCELL
  standard tap *
  page85_i155
#ISCELL
  standard tap *
  page85_i156
#ISCELL
  standard tap *
  page85_i157
#ISCELL
  standard tap *
  page85_i158
#ISCELL
  standard tap *
  page85_i159
#ISCELL
  standard offpage *
  page85_i16
#ISCELL
  standard tap *
  page85_i160
#ISCELL
  standard tap *
  page85_i161
#ISCELL
  standard tap *
  page85_i162
#ISCELL
  standard tap *
  page85_i163
#ISCELL
  standard tap *
  page85_i164
#ISCELL
  standard offpage *
  page85_i165
#ISCELL
  standard offpage *
  page85_i166
#ISCELL
  standard offpage *
  page85_i167
#ISCELL
  standard tap *
  page85_i168
#ISCELL
  standard tap *
  page85_i169
#ISCELL
  standard offpage *
  page85_i17
#ISCELL
  standard tap *
  page85_i170
#ISCELL
  standard offpage *
  page85_i171
#ISCELL
  standard offpage *
  page85_i172
#ISCELL
  logical_power universal_gnd *
  page85_i173
#CELL
  pure_quanta sconn288_adr50017p087cc *
  page85_i174
#ISCELL
  logical_power universal_gnd *
  page85_i175
#ISCELL
  logical_power vcc_core *
  page85_i176
#ISCELL
  standard offpage *
  page85_i177
#CELL
  pure_quanta sconn288_adr50017p087cc *
  page85_i178
#ISCELL
  standard offpage *
  page85_i179
#ISCELL
  standard offpage *
  page85_i18
#CELL
  pure_quanta q_res *
  page85_i180
#ISCELL
  standard offpage *
  page85_i19
#ISCELL
  logical_power universal_gnd *
  page85_i2
#ISCELL
  standard offpage *
  page85_i20
#ISCELL
  standard offpage *
  page85_i21
#ISCELL
  standard offpage *
  page85_i22
#CELL
  pure_quanta sconn288_adr50017p087cc *
  page85_i23
#ISCELL
  standard tap *
  page85_i24
#ISCELL
  standard tap *
  page85_i25
#ISCELL
  standard tap *
  page85_i26
#ISCELL
  standard tap *
  page85_i27
#ISCELL
  standard tap *
  page85_i28
#ISCELL
  standard tap *
  page85_i29
#ISCELL
  standard offpage *
  page85_i3
#ISCELL
  standard tap *
  page85_i30
#ISCELL
  standard tap *
  page85_i31
#ISCELL
  standard tap *
  page85_i32
#ISCELL
  standard tap *
  page85_i33
#ISCELL
  standard tap *
  page85_i34
#ISCELL
  standard tap *
  page85_i35
#ISCELL
  standard tap *
  page85_i36
#ISCELL
  standard tap *
  page85_i37
#ISCELL
  standard tap *
  page85_i38
#ISCELL
  standard tap *
  page85_i39
#ISCELL
  standard offpage *
  page85_i4
#ISCELL
  standard tap *
  page85_i40
#ISCELL
  standard tap *
  page85_i41
#ISCELL
  standard tap *
  page85_i42
#ISCELL
  standard tap *
  page85_i43
#ISCELL
  standard tap *
  page85_i44
#ISCELL
  standard tap *
  page85_i45
#ISCELL
  standard tap *
  page85_i46
#ISCELL
  standard tap *
  page85_i47
#ISCELL
  standard tap *
  page85_i48
#ISCELL
  standard tap *
  page85_i49
#ISCELL
  standard offpage *
  page85_i5
#ISCELL
  standard tap *
  page85_i50
#ISCELL
  standard tap *
  page85_i51
#ISCELL
  standard tap *
  page85_i52
#ISCELL
  standard tap *
  page85_i53
#ISCELL
  standard tap *
  page85_i54
#ISCELL
  standard tap *
  page85_i55
#ISCELL
  standard tap *
  page85_i56
#ISCELL
  standard tap *
  page85_i57
#ISCELL
  standard tap *
  page85_i58
#ISCELL
  standard tap *
  page85_i59
#ISCELL
  standard tap *
  page85_i60
#ISCELL
  standard tap *
  page85_i61
#ISCELL
  standard tap *
  page85_i62
#ISCELL
  standard tap *
  page85_i63
#ISCELL
  standard tap *
  page85_i64
#ISCELL
  standard tap *
  page85_i65
#ISCELL
  standard tap *
  page85_i66
#ISCELL
  standard tap *
  page85_i67
#ISCELL
  standard tap *
  page85_i68
#ISCELL
  standard tap *
  page85_i69
#ISCELL
  standard offpage *
  page85_i7
#ISCELL
  standard tap *
  page85_i70
#ISCELL
  standard tap *
  page85_i71
#ISCELL
  standard tap *
  page85_i72
#ISCELL
  standard tap *
  page85_i73
#ISCELL
  standard tap *
  page85_i74
#ISCELL
  standard tap *
  page85_i75
#ISCELL
  standard tap *
  page85_i76
#ISCELL
  standard tap *
  page85_i77
#ISCELL
  standard tap *
  page85_i78
#ISCELL
  standard tap *
  page85_i79
#ISCELL
  standard offpage *
  page85_i8
#ISCELL
  standard tap *
  page85_i80
#ISCELL
  standard tap *
  page85_i81
#ISCELL
  standard tap *
  page85_i82
#ISCELL
  standard tap *
  page85_i83
#ISCELL
  standard tap *
  page85_i84
#ISCELL
  standard tap *
  page85_i85
#ISCELL
  standard tap *
  page85_i86
#ISCELL
  standard tap *
  page85_i87
#ISCELL
  standard tap *
  page85_i88
#ISCELL
  standard tap *
  page85_i89
#ISCELL
  standard offpage *
  page85_i9
#ISCELL
  standard tap *
  page85_i90
#ISCELL
  standard tap *
  page85_i91
#ISCELL
  standard tap *
  page85_i92
#ISCELL
  standard tap *
  page85_i93
#ISCELL
  standard tap *
  page85_i94
#ISCELL
  standard tap *
  page85_i95
#ISCELL
  standard tap *
  page85_i96
#ISCELL
  standard tap *
  page85_i97
#ISCELL
  standard tap *
  page85_i98
#ISCELL
  standard tap *
  page85_i99
#ISCELL
  logical_power cad_note *
  *
#ISCELL
  pure_quanta quanta_title_block_c *
  *
#ISCELL
  standard offpage *
  page86_i1
#ISCELL
  standard offpage *
  page86_i10
#ISCELL
  standard tap *
  page86_i100
#ISCELL
  standard tap *
  page86_i101
#ISCELL
  standard tap *
  page86_i102
#ISCELL
  standard tap *
  page86_i103
#ISCELL
  standard tap *
  page86_i104
#ISCELL
  standard tap *
  page86_i105
#ISCELL
  standard tap *
  page86_i106
#ISCELL
  standard tap *
  page86_i107
#ISCELL
  standard tap *
  page86_i108
#ISCELL
  standard tap *
  page86_i109
#ISCELL
  standard offpage *
  page86_i11
#ISCELL
  standard tap *
  page86_i110
#ISCELL
  standard tap *
  page86_i111
#ISCELL
  standard tap *
  page86_i112
#ISCELL
  standard tap *
  page86_i113
#ISCELL
  standard tap *
  page86_i114
#ISCELL
  standard tap *
  page86_i115
#ISCELL
  standard tap *
  page86_i116
#ISCELL
  standard tap *
  page86_i117
#ISCELL
  standard tap *
  page86_i118
#ISCELL
  logical_power universal_gnd *
  page86_i119
#ISCELL
  logical_power vcc_core *
  page86_i12
#CELL
  pure_quanta q_cap *
  page86_i120
#CELL
  pure_quanta q_cap *
  page86_i121
#ISCELL
  logical_power universal_gnd *
  page86_i122
#CELL
  pure_quanta q_cap *
  page86_i123
#ISCELL
  logical_power vcc_core *
  page86_i124
#ISCELL
  standard offpage *
  page86_i126
#ISCELL
  standard offpage *
  page86_i127
#ISCELL
  logical_power vcc_core *
  page86_i128
#ISCELL
  standard tap *
  page86_i129
#ISCELL
  standard offpage *
  page86_i13
#ISCELL
  standard tap *
  page86_i130
#ISCELL
  standard tap *
  page86_i131
#ISCELL
  standard tap *
  page86_i132
#ISCELL
  standard tap *
  page86_i133
#ISCELL
  standard tap *
  page86_i134
#ISCELL
  standard tap *
  page86_i135
#ISCELL
  standard tap *
  page86_i136
#ISCELL
  standard tap *
  page86_i137
#ISCELL
  standard tap *
  page86_i138
#ISCELL
  standard tap *
  page86_i139
#ISCELL
  standard offpage *
  page86_i14
#ISCELL
  standard tap *
  page86_i140
#ISCELL
  standard tap *
  page86_i141
#ISCELL
  standard tap *
  page86_i142
#ISCELL
  standard tap *
  page86_i143
#ISCELL
  standard tap *
  page86_i144
#ISCELL
  standard tap *
  page86_i145
#ISCELL
  standard tap *
  page86_i146
#ISCELL
  standard tap *
  page86_i147
#ISCELL
  standard tap *
  page86_i148
#ISCELL
  standard tap *
  page86_i149
#ISCELL
  standard offpage *
  page86_i15
#ISCELL
  standard tap *
  page86_i150
#ISCELL
  standard tap *
  page86_i151
#ISCELL
  standard tap *
  page86_i152
#ISCELL
  standard tap *
  page86_i153
#ISCELL
  standard tap *
  page86_i154
#ISCELL
  standard tap *
  page86_i155
#ISCELL
  standard tap *
  page86_i156
#ISCELL
  standard tap *
  page86_i157
#ISCELL
  standard tap *
  page86_i158
#ISCELL
  standard tap *
  page86_i159
#ISCELL
  standard offpage *
  page86_i16
#ISCELL
  standard tap *
  page86_i160
#ISCELL
  standard tap *
  page86_i161
#ISCELL
  standard tap *
  page86_i162
#ISCELL
  standard tap *
  page86_i163
#ISCELL
  standard tap *
  page86_i164
#ISCELL
  standard tap *
  page86_i165
#ISCELL
  standard tap *
  page86_i166
#ISCELL
  standard tap *
  page86_i167
#ISCELL
  standard tap *
  page86_i168
#ISCELL
  standard offpage *
  page86_i169
#ISCELL
  standard offpage *
  page86_i17
#ISCELL
  standard offpage *
  page86_i170
#ISCELL
  standard offpage *
  page86_i171
#ISCELL
  standard offpage *
  page86_i172
#ISCELL
  logical_power universal_gnd *
  page86_i173
#CELL
  pure_quanta sconn288_adr50017p130cc *
  page86_i174
#ISCELL
  logical_power universal_gnd *
  page86_i175
#ISCELL
  logical_power vcc_core *
  page86_i176
#ISCELL
  standard offpage *
  page86_i177
#CELL
  pure_quanta sconn288_adr50017p130cc *
  page86_i178
#ISCELL
  standard offpage *
  page86_i179
#ISCELL
  standard offpage *
  page86_i18
#CELL
  pure_quanta q_res *
  page86_i180
#ISCELL
  standard offpage *
  page86_i19
#ISCELL
  logical_power universal_gnd *
  page86_i2
#ISCELL
  standard offpage *
  page86_i20
#ISCELL
  standard offpage *
  page86_i21
#ISCELL
  standard offpage *
  page86_i22
#ISCELL
  standard offpage *
  page86_i23
#CELL
  pure_quanta sconn288_adr50017p130cc *
  page86_i24
#ISCELL
  standard tap *
  page86_i25
#ISCELL
  standard tap *
  page86_i26
#ISCELL
  standard tap *
  page86_i27
#ISCELL
  standard tap *
  page86_i28
#ISCELL
  standard tap *
  page86_i29
#CELL
  pure_quanta q_res *
  page86_i3
#ISCELL
  standard tap *
  page86_i30
#ISCELL
  standard tap *
  page86_i31
#ISCELL
  standard tap *
  page86_i32
#ISCELL
  standard tap *
  page86_i33
#ISCELL
  standard tap *
  page86_i34
#ISCELL
  standard tap *
  page86_i35
#ISCELL
  standard tap *
  page86_i36
#ISCELL
  standard tap *
  page86_i37
#ISCELL
  standard tap *
  page86_i38
#ISCELL
  standard tap *
  page86_i39
#ISCELL
  standard offpage *
  page86_i4
#ISCELL
  standard tap *
  page86_i40
#ISCELL
  standard tap *
  page86_i41
#ISCELL
  standard tap *
  page86_i42
#ISCELL
  standard tap *
  page86_i43
#ISCELL
  standard tap *
  page86_i44
#ISCELL
  standard tap *
  page86_i45
#ISCELL
  standard tap *
  page86_i46
#ISCELL
  standard tap *
  page86_i47
#ISCELL
  standard tap *
  page86_i48
#ISCELL
  standard tap *
  page86_i49
#ISCELL
  standard offpage *
  page86_i5
#ISCELL
  standard tap *
  page86_i50
#ISCELL
  standard tap *
  page86_i51
#ISCELL
  standard tap *
  page86_i52
#ISCELL
  standard tap *
  page86_i53
#ISCELL
  standard tap *
  page86_i54
#ISCELL
  standard tap *
  page86_i55
#ISCELL
  standard tap *
  page86_i56
#ISCELL
  standard tap *
  page86_i57
#ISCELL
  standard tap *
  page86_i58
#ISCELL
  standard tap *
  page86_i59
#ISCELL
  standard tap *
  page86_i60
#ISCELL
  standard tap *
  page86_i61
#ISCELL
  standard tap *
  page86_i62
#ISCELL
  standard tap *
  page86_i63
#ISCELL
  standard tap *
  page86_i64
#ISCELL
  standard tap *
  page86_i65
#ISCELL
  standard tap *
  page86_i66
#ISCELL
  standard tap *
  page86_i67
#ISCELL
  standard tap *
  page86_i68
#ISCELL
  standard tap *
  page86_i69
#ISCELL
  standard offpage *
  page86_i7
#ISCELL
  standard tap *
  page86_i70
#ISCELL
  standard tap *
  page86_i71
#ISCELL
  standard tap *
  page86_i72
#ISCELL
  standard tap *
  page86_i73
#ISCELL
  standard tap *
  page86_i74
#ISCELL
  standard tap *
  page86_i75
#ISCELL
  standard tap *
  page86_i76
#ISCELL
  standard tap *
  page86_i77
#ISCELL
  standard tap *
  page86_i78
#ISCELL
  standard tap *
  page86_i79
#ISCELL
  standard offpage *
  page86_i8
#ISCELL
  standard tap *
  page86_i80
#ISCELL
  standard tap *
  page86_i81
#ISCELL
  standard tap *
  page86_i82
#ISCELL
  standard tap *
  page86_i83
#ISCELL
  standard tap *
  page86_i84
#ISCELL
  standard tap *
  page86_i85
#ISCELL
  standard tap *
  page86_i86
#ISCELL
  standard tap *
  page86_i87
#ISCELL
  standard tap *
  page86_i88
#ISCELL
  standard tap *
  page86_i89
#ISCELL
  standard offpage *
  page86_i9
#ISCELL
  standard tap *
  page86_i90
#ISCELL
  standard tap *
  page86_i91
#ISCELL
  standard tap *
  page86_i92
#ISCELL
  standard tap *
  page86_i93
#ISCELL
  standard tap *
  page86_i94
#ISCELL
  standard tap *
  page86_i95
#ISCELL
  standard tap *
  page86_i96
#ISCELL
  standard tap *
  page86_i97
#ISCELL
  standard tap *
  page86_i98
#ISCELL
  standard tap *
  page86_i99
#ISCELL
  logical_power cad_note *
  *
#ISCELL
  pure_quanta quanta_title_block_c *
  *
#ISCELL
  standard offpage *
  page87_i1
#ISCELL
  standard offpage *
  page87_i10
#ISCELL
  standard tap *
  page87_i100
#ISCELL
  standard tap *
  page87_i101
#ISCELL
  standard tap *
  page87_i102
#ISCELL
  standard tap *
  page87_i103
#ISCELL
  standard offpage *
  page87_i104
#ISCELL
  standard tap *
  page87_i105
#ISCELL
  standard tap *
  page87_i106
#ISCELL
  standard tap *
  page87_i107
#ISCELL
  standard tap *
  page87_i108
#ISCELL
  standard tap *
  page87_i109
#ISCELL
  standard offpage *
  page87_i11
#ISCELL
  standard tap *
  page87_i110
#ISCELL
  standard tap *
  page87_i111
#ISCELL
  standard tap *
  page87_i112
#ISCELL
  standard tap *
  page87_i113
#ISCELL
  standard tap *
  page87_i114
#ISCELL
  standard tap *
  page87_i115
#ISCELL
  standard tap *
  page87_i116
#ISCELL
  standard tap *
  page87_i117
#ISCELL
  standard tap *
  page87_i118
#ISCELL
  logical_power universal_gnd *
  page87_i119
#ISCELL
  standard offpage *
  page87_i12
#CELL
  pure_quanta q_cap *
  page87_i120
#ISCELL
  logical_power vcc_core *
  page87_i121
#ISCELL
  standard offpage *
  page87_i122
#CELL
  pure_quanta q_cap *
  page87_i124
#ISCELL
  logical_power vcc_core *
  page87_i125
#ISCELL
  logical_power universal_gnd *
  page87_i126
#CELL
  pure_quanta q_cap *
  page87_i127
#ISCELL
  logical_power universal_gnd *
  page87_i128
#ISCELL
  standard tap *
  page87_i129
#ISCELL
  standard offpage *
  page87_i13
#ISCELL
  standard tap *
  page87_i130
#ISCELL
  standard tap *
  page87_i131
#ISCELL
  standard tap *
  page87_i132
#ISCELL
  standard tap *
  page87_i133
#ISCELL
  standard tap *
  page87_i134
#ISCELL
  standard tap *
  page87_i135
#ISCELL
  standard tap *
  page87_i136
#ISCELL
  standard tap *
  page87_i137
#ISCELL
  standard tap *
  page87_i138
#ISCELL
  standard tap *
  page87_i139
#ISCELL
  standard offpage *
  page87_i14
#ISCELL
  standard tap *
  page87_i140
#ISCELL
  standard tap *
  page87_i141
#ISCELL
  standard tap *
  page87_i142
#ISCELL
  standard tap *
  page87_i143
#ISCELL
  standard tap *
  page87_i144
#ISCELL
  standard tap *
  page87_i145
#ISCELL
  standard tap *
  page87_i146
#ISCELL
  standard tap *
  page87_i147
#ISCELL
  standard tap *
  page87_i148
#ISCELL
  standard tap *
  page87_i149
#ISCELL
  standard offpage *
  page87_i15
#ISCELL
  standard tap *
  page87_i150
#ISCELL
  standard tap *
  page87_i151
#ISCELL
  standard tap *
  page87_i152
#ISCELL
  standard tap *
  page87_i153
#ISCELL
  standard tap *
  page87_i154
#ISCELL
  standard tap *
  page87_i155
#ISCELL
  standard tap *
  page87_i156
#ISCELL
  standard tap *
  page87_i157
#ISCELL
  standard tap *
  page87_i158
#ISCELL
  standard tap *
  page87_i159
#ISCELL
  standard offpage *
  page87_i16
#ISCELL
  standard tap *
  page87_i160
#ISCELL
  standard tap *
  page87_i161
#ISCELL
  standard offpage *
  page87_i162
#ISCELL
  standard offpage *
  page87_i163
#ISCELL
  standard offpage *
  page87_i164
#ISCELL
  standard tap *
  page87_i165
#ISCELL
  standard tap *
  page87_i166
#ISCELL
  standard tap *
  page87_i167
#ISCELL
  standard tap *
  page87_i168
#ISCELL
  standard tap *
  page87_i169
#ISCELL
  standard offpage *
  page87_i17
#ISCELL
  standard tap *
  page87_i170
#ISCELL
  standard tap *
  page87_i171
#ISCELL
  standard offpage *
  page87_i172
#ISCELL
  standard offpage *
  page87_i173
#ISCELL
  logical_power vcc_core *
  page87_i174
#CELL
  pure_quanta sconn288_adr50017p087cc *
  page87_i175
#ISCELL
  logical_power universal_gnd *
  page87_i176
#ISCELL
  standard offpage *
  page87_i177
#CELL
  pure_quanta sconn288_adr50017p087cc *
  page87_i178
#ISCELL
  standard offpage *
  page87_i179
#ISCELL
  standard offpage *
  page87_i18
#CELL
  pure_quanta q_res *
  page87_i180
#ISCELL
  standard offpage *
  page87_i19
#ISCELL
  standard offpage *
  page87_i2
#ISCELL
  logical_power vcc_core *
  page87_i20
#ISCELL
  standard tap *
  page87_i21
#ISCELL
  standard tap *
  page87_i22
#ISCELL
  standard tap *
  page87_i23
#ISCELL
  standard tap *
  page87_i24
#ISCELL
  standard tap *
  page87_i25
#ISCELL
  standard tap *
  page87_i26
#ISCELL
  standard tap *
  page87_i27
#ISCELL
  standard tap *
  page87_i28
#ISCELL
  standard tap *
  page87_i29
#ISCELL
  standard offpage *
  page87_i3
#ISCELL
  standard tap *
  page87_i30
#ISCELL
  standard tap *
  page87_i31
#ISCELL
  standard tap *
  page87_i32
#ISCELL
  standard tap *
  page87_i33
#ISCELL
  standard tap *
  page87_i34
#ISCELL
  standard tap *
  page87_i35
#ISCELL
  standard tap *
  page87_i36
#ISCELL
  standard tap *
  page87_i37
#ISCELL
  standard tap *
  page87_i38
#ISCELL
  standard tap *
  page87_i39
#ISCELL
  standard tap *
  page87_i40
#ISCELL
  standard tap *
  page87_i41
#ISCELL
  standard tap *
  page87_i42
#ISCELL
  standard tap *
  page87_i43
#ISCELL
  logical_power universal_gnd *
  page87_i44
#CELL
  pure_quanta q_res *
  page87_i45
#CELL
  pure_quanta sconn288_adr50017p087cc *
  page87_i46
#ISCELL
  standard tap *
  page87_i47
#ISCELL
  standard tap *
  page87_i48
#ISCELL
  standard tap *
  page87_i49
#ISCELL
  standard offpage *
  page87_i5
#ISCELL
  standard tap *
  page87_i50
#ISCELL
  standard tap *
  page87_i51
#ISCELL
  standard tap *
  page87_i52
#ISCELL
  standard tap *
  page87_i53
#ISCELL
  standard tap *
  page87_i54
#ISCELL
  standard tap *
  page87_i55
#ISCELL
  standard tap *
  page87_i56
#ISCELL
  standard tap *
  page87_i57
#ISCELL
  standard tap *
  page87_i58
#ISCELL
  standard tap *
  page87_i59
#ISCELL
  standard offpage *
  page87_i6
#ISCELL
  standard tap *
  page87_i60
#ISCELL
  standard tap *
  page87_i61
#ISCELL
  standard tap *
  page87_i62
#ISCELL
  standard tap *
  page87_i63
#ISCELL
  standard tap *
  page87_i64
#ISCELL
  standard tap *
  page87_i65
#ISCELL
  standard tap *
  page87_i66
#ISCELL
  standard tap *
  page87_i67
#ISCELL
  standard tap *
  page87_i68
#ISCELL
  standard tap *
  page87_i69
#ISCELL
  standard offpage *
  page87_i7
#ISCELL
  standard tap *
  page87_i70
#ISCELL
  standard tap *
  page87_i71
#ISCELL
  standard tap *
  page87_i72
#ISCELL
  standard tap *
  page87_i73
#ISCELL
  standard tap *
  page87_i74
#ISCELL
  standard tap *
  page87_i75
#ISCELL
  standard tap *
  page87_i76
#ISCELL
  standard tap *
  page87_i77
#ISCELL
  standard tap *
  page87_i78
#ISCELL
  standard tap *
  page87_i79
#ISCELL
  standard offpage *
  page87_i8
#ISCELL
  standard tap *
  page87_i80
#ISCELL
  standard tap *
  page87_i81
#ISCELL
  standard tap *
  page87_i82
#ISCELL
  standard tap *
  page87_i83
#ISCELL
  standard tap *
  page87_i84
#ISCELL
  standard tap *
  page87_i85
#ISCELL
  standard tap *
  page87_i86
#ISCELL
  standard tap *
  page87_i87
#ISCELL
  standard tap *
  page87_i88
#ISCELL
  standard tap *
  page87_i89
#ISCELL
  standard offpage *
  page87_i9
#ISCELL
  standard tap *
  page87_i90
#ISCELL
  standard tap *
  page87_i91
#ISCELL
  standard tap *
  page87_i92
#ISCELL
  standard tap *
  page87_i93
#ISCELL
  standard tap *
  page87_i94
#ISCELL
  standard tap *
  page87_i95
#ISCELL
  standard tap *
  page87_i96
#ISCELL
  standard tap *
  page87_i97
#ISCELL
  standard tap *
  page87_i98
#ISCELL
  standard tap *
  page87_i99
#ISCELL
  logical_power cad_note *
  *
#ISCELL
  pure_quanta quanta_title_block_c *
  *
#ISCELL
  logical_power universal_gnd *
  page88_i1
#ISCELL
  standard offpage *
  page88_i10
#ISCELL
  standard tap *
  page88_i100
#ISCELL
  standard tap *
  page88_i101
#ISCELL
  standard tap *
  page88_i102
#ISCELL
  standard tap *
  page88_i103
#ISCELL
  standard tap *
  page88_i104
#ISCELL
  standard tap *
  page88_i105
#ISCELL
  standard tap *
  page88_i106
#ISCELL
  standard tap *
  page88_i107
#ISCELL
  standard tap *
  page88_i108
#ISCELL
  standard tap *
  page88_i109
#ISCELL
  logical_power vcc_core *
  page88_i11
#ISCELL
  standard tap *
  page88_i110
#ISCELL
  standard tap *
  page88_i111
#ISCELL
  standard tap *
  page88_i112
#ISCELL
  standard tap *
  page88_i113
#ISCELL
  standard offpage *
  page88_i114
#ISCELL
  standard offpage *
  page88_i115
#ISCELL
  standard tap *
  page88_i116
#ISCELL
  standard tap *
  page88_i117
#ISCELL
  standard tap *
  page88_i118
#ISCELL
  standard tap *
  page88_i119
#CELL
  pure_quanta sconn288_adr50017p130cc *
  page88_i12
#ISCELL
  standard offpage *
  page88_i120
#ISCELL
  logical_power universal_gnd *
  page88_i121
#ISCELL
  logical_power universal_gnd *
  page88_i122
#CELL
  pure_quanta q_cap *
  page88_i123
#ISCELL
  logical_power vcc_core *
  page88_i124
#CELL
  pure_quanta q_cap *
  page88_i126
#ISCELL
  logical_power vcc_core *
  page88_i127
#ISCELL
  standard tap *
  page88_i128
#ISCELL
  standard tap *
  page88_i129
#ISCELL
  standard tap *
  page88_i13
#ISCELL
  standard tap *
  page88_i130
#ISCELL
  standard tap *
  page88_i131
#ISCELL
  standard tap *
  page88_i132
#ISCELL
  standard tap *
  page88_i133
#ISCELL
  standard tap *
  page88_i134
#ISCELL
  standard tap *
  page88_i135
#ISCELL
  standard tap *
  page88_i136
#ISCELL
  standard tap *
  page88_i137
#ISCELL
  standard tap *
  page88_i138
#ISCELL
  standard tap *
  page88_i139
#ISCELL
  standard tap *
  page88_i14
#ISCELL
  standard tap *
  page88_i140
#ISCELL
  standard tap *
  page88_i141
#ISCELL
  standard tap *
  page88_i142
#ISCELL
  standard tap *
  page88_i143
#ISCELL
  standard tap *
  page88_i144
#ISCELL
  standard tap *
  page88_i145
#ISCELL
  standard tap *
  page88_i146
#ISCELL
  standard tap *
  page88_i147
#ISCELL
  standard tap *
  page88_i148
#ISCELL
  standard tap *
  page88_i149
#ISCELL
  standard offpage *
  page88_i15
#ISCELL
  standard tap *
  page88_i150
#ISCELL
  standard tap *
  page88_i151
#ISCELL
  standard tap *
  page88_i152
#ISCELL
  standard tap *
  page88_i153
#ISCELL
  standard tap *
  page88_i154
#ISCELL
  standard tap *
  page88_i155
#ISCELL
  standard tap *
  page88_i156
#ISCELL
  standard tap *
  page88_i157
#ISCELL
  standard tap *
  page88_i158
#ISCELL
  standard tap *
  page88_i159
#ISCELL
  standard offpage *
  page88_i16
#ISCELL
  standard tap *
  page88_i160
#ISCELL
  standard tap *
  page88_i161
#ISCELL
  standard tap *
  page88_i162
#ISCELL
  standard tap *
  page88_i163
#ISCELL
  standard tap *
  page88_i164
#ISCELL
  standard tap *
  page88_i165
#CELL
  pure_quanta q_cap *
  page88_i166
#ISCELL
  logical_power universal_gnd *
  page88_i167
#CELL
  pure_quanta sconn288_adr50017p130cc *
  page88_i168
#ISCELL
  standard offpage *
  page88_i169
#ISCELL
  standard offpage *
  page88_i17
#ISCELL
  standard offpage *
  page88_i170
#ISCELL
  standard offpage *
  page88_i171
#ISCELL
  standard tap *
  page88_i172
#ISCELL
  standard tap *
  page88_i173
#ISCELL
  standard offpage *
  page88_i174
#ISCELL
  logical_power vcc_core *
  page88_i175
#ISCELL
  logical_power universal_gnd *
  page88_i176
#ISCELL
  standard offpage *
  page88_i177
#CELL
  pure_quanta sconn288_adr50017p130cc *
  page88_i178
#ISCELL
  standard offpage *
  page88_i179
#ISCELL
  standard offpage *
  page88_i18
#CELL
  pure_quanta q_res *
  page88_i180
#ISCELL
  standard offpage *
  page88_i19
#CELL
  pure_quanta q_res *
  page88_i2
#ISCELL
  standard offpage *
  page88_i20
#ISCELL
  standard offpage *
  page88_i21
#ISCELL
  standard offpage *
  page88_i22
#ISCELL
  standard offpage *
  page88_i23
#ISCELL
  standard offpage *
  page88_i24
#ISCELL
  standard offpage *
  page88_i25
#ISCELL
  standard tap *
  page88_i26
#ISCELL
  standard tap *
  page88_i27
#ISCELL
  standard tap *
  page88_i28
#ISCELL
  standard tap *
  page88_i29
#ISCELL
  standard offpage *
  page88_i3
#ISCELL
  standard tap *
  page88_i30
#ISCELL
  standard tap *
  page88_i31
#ISCELL
  standard tap *
  page88_i32
#ISCELL
  standard tap *
  page88_i33
#ISCELL
  standard tap *
  page88_i34
#ISCELL
  standard tap *
  page88_i35
#ISCELL
  standard tap *
  page88_i36
#ISCELL
  standard tap *
  page88_i37
#ISCELL
  standard tap *
  page88_i38
#ISCELL
  standard tap *
  page88_i39
#ISCELL
  standard offpage *
  page88_i4
#ISCELL
  standard tap *
  page88_i40
#ISCELL
  standard tap *
  page88_i41
#ISCELL
  standard tap *
  page88_i42
#ISCELL
  standard tap *
  page88_i43
#ISCELL
  standard tap *
  page88_i44
#ISCELL
  standard tap *
  page88_i45
#ISCELL
  standard tap *
  page88_i46
#ISCELL
  standard tap *
  page88_i47
#ISCELL
  standard tap *
  page88_i48
#ISCELL
  standard tap *
  page88_i49
#ISCELL
  standard offpage *
  page88_i5
#ISCELL
  standard tap *
  page88_i50
#ISCELL
  standard tap *
  page88_i51
#ISCELL
  standard tap *
  page88_i52
#ISCELL
  standard tap *
  page88_i53
#ISCELL
  standard tap *
  page88_i54
#ISCELL
  standard tap *
  page88_i55
#ISCELL
  standard tap *
  page88_i56
#ISCELL
  standard tap *
  page88_i57
#ISCELL
  standard tap *
  page88_i58
#ISCELL
  standard tap *
  page88_i59
#ISCELL
  standard tap *
  page88_i60
#ISCELL
  standard tap *
  page88_i61
#ISCELL
  standard tap *
  page88_i62
#ISCELL
  standard tap *
  page88_i63
#ISCELL
  standard tap *
  page88_i64
#ISCELL
  standard tap *
  page88_i65
#ISCELL
  standard tap *
  page88_i66
#ISCELL
  standard tap *
  page88_i67
#ISCELL
  standard tap *
  page88_i68
#ISCELL
  standard tap *
  page88_i69
#ISCELL
  standard offpage *
  page88_i7
#ISCELL
  standard tap *
  page88_i70
#ISCELL
  standard tap *
  page88_i71
#ISCELL
  standard tap *
  page88_i72
#ISCELL
  standard tap *
  page88_i73
#ISCELL
  standard tap *
  page88_i74
#ISCELL
  standard tap *
  page88_i75
#ISCELL
  standard tap *
  page88_i76
#ISCELL
  standard tap *
  page88_i77
#ISCELL
  standard tap *
  page88_i78
#ISCELL
  standard tap *
  page88_i79
#ISCELL
  standard offpage *
  page88_i8
#ISCELL
  standard tap *
  page88_i80
#ISCELL
  standard tap *
  page88_i81
#ISCELL
  standard tap *
  page88_i82
#ISCELL
  standard tap *
  page88_i83
#ISCELL
  standard tap *
  page88_i84
#ISCELL
  standard tap *
  page88_i85
#ISCELL
  standard tap *
  page88_i86
#ISCELL
  standard tap *
  page88_i87
#ISCELL
  standard tap *
  page88_i88
#ISCELL
  standard tap *
  page88_i89
#ISCELL
  standard offpage *
  page88_i9
#ISCELL
  standard tap *
  page88_i90
#ISCELL
  standard tap *
  page88_i91
#ISCELL
  standard tap *
  page88_i92
#ISCELL
  standard tap *
  page88_i93
#ISCELL
  standard tap *
  page88_i94
#ISCELL
  standard tap *
  page88_i95
#ISCELL
  standard tap *
  page88_i96
#ISCELL
  standard tap *
  page88_i97
#ISCELL
  standard tap *
  page88_i98
#ISCELL
  standard tap *
  page88_i99
#ISCELL
  logical_power cad_note *
  *
#ISCELL
  pure_quanta quanta_title_block_c *
  *
#ISCELL
  logical_power universal_gnd *
  page89_i1
#ISCELL
  standard offpage *
  page89_i10
#ISCELL
  standard tap *
  page89_i100
#ISCELL
  standard tap *
  page89_i101
#ISCELL
  standard tap *
  page89_i102
#ISCELL
  standard tap *
  page89_i103
#ISCELL
  standard tap *
  page89_i104
#ISCELL
  standard tap *
  page89_i105
#ISCELL
  standard tap *
  page89_i106
#ISCELL
  standard tap *
  page89_i107
#ISCELL
  standard tap *
  page89_i108
#ISCELL
  standard tap *
  page89_i109
#ISCELL
  logical_power vcc_core *
  page89_i11
#ISCELL
  standard tap *
  page89_i110
#ISCELL
  standard tap *
  page89_i111
#ISCELL
  standard offpage *
  page89_i112
#ISCELL
  standard tap *
  page89_i113
#ISCELL
  standard tap *
  page89_i114
#ISCELL
  standard tap *
  page89_i115
#ISCELL
  standard tap *
  page89_i116
#ISCELL
  standard tap *
  page89_i117
#ISCELL
  standard tap *
  page89_i118
#ISCELL
  logical_power universal_gnd *
  page89_i119
#ISCELL
  standard tap *
  page89_i12
#ISCELL
  logical_power universal_gnd *
  page89_i120
#CELL
  pure_quanta q_cap *
  page89_i121
#ISCELL
  logical_power vcc_core *
  page89_i122
#ISCELL
  standard offpage *
  page89_i123
#CELL
  pure_quanta q_cap *
  page89_i125
#ISCELL
  logical_power vcc_core *
  page89_i126
#CELL
  pure_quanta q_cap *
  page89_i127
#ISCELL
  logical_power universal_gnd *
  page89_i128
#ISCELL
  standard tap *
  page89_i129
#ISCELL
  standard offpage *
  page89_i13
#ISCELL
  standard tap *
  page89_i130
#ISCELL
  standard tap *
  page89_i131
#ISCELL
  standard tap *
  page89_i132
#ISCELL
  standard tap *
  page89_i133
#ISCELL
  standard tap *
  page89_i134
#ISCELL
  standard tap *
  page89_i135
#ISCELL
  standard tap *
  page89_i136
#ISCELL
  standard tap *
  page89_i137
#ISCELL
  standard tap *
  page89_i138
#ISCELL
  standard tap *
  page89_i139
#ISCELL
  standard offpage *
  page89_i14
#ISCELL
  standard tap *
  page89_i140
#ISCELL
  standard tap *
  page89_i141
#ISCELL
  standard tap *
  page89_i142
#ISCELL
  standard tap *
  page89_i143
#ISCELL
  standard tap *
  page89_i144
#ISCELL
  standard tap *
  page89_i145
#ISCELL
  standard tap *
  page89_i146
#ISCELL
  standard tap *
  page89_i147
#ISCELL
  standard tap *
  page89_i148
#ISCELL
  standard tap *
  page89_i149
#ISCELL
  standard offpage *
  page89_i15
#ISCELL
  standard tap *
  page89_i150
#ISCELL
  standard tap *
  page89_i151
#ISCELL
  standard tap *
  page89_i152
#ISCELL
  standard tap *
  page89_i153
#ISCELL
  standard tap *
  page89_i154
#ISCELL
  standard tap *
  page89_i155
#ISCELL
  standard tap *
  page89_i156
#ISCELL
  standard tap *
  page89_i157
#ISCELL
  standard tap *
  page89_i158
#ISCELL
  standard tap *
  page89_i159
#ISCELL
  standard offpage *
  page89_i16
#ISCELL
  standard tap *
  page89_i160
#ISCELL
  standard tap *
  page89_i161
#ISCELL
  standard tap *
  page89_i162
#ISCELL
  standard tap *
  page89_i163
#ISCELL
  standard tap *
  page89_i164
#ISCELL
  standard tap *
  page89_i165
#ISCELL
  standard offpage *
  page89_i166
#ISCELL
  standard offpage *
  page89_i167
#ISCELL
  standard offpage *
  page89_i168
#ISCELL
  standard tap *
  page89_i169
#ISCELL
  standard offpage *
  page89_i17
#ISCELL
  standard tap *
  page89_i170
#ISCELL
  standard tap *
  page89_i171
#ISCELL
  standard offpage *
  page89_i172
#ISCELL
  standard offpage *
  page89_i173
#ISCELL
  logical_power vcc_core *
  page89_i174
#CELL
  pure_quanta sconn288_adr50017p087cc *
  page89_i175
#ISCELL
  logical_power universal_gnd *
  page89_i176
#ISCELL
  standard offpage *
  page89_i177
#CELL
  pure_quanta sconn288_adr50017p087cc *
  page89_i178
#ISCELL
  standard offpage *
  page89_i179
#ISCELL
  standard offpage *
  page89_i18
#CELL
  pure_quanta q_res *
  page89_i180
#ISCELL
  standard offpage *
  page89_i19
#CELL
  pure_quanta q_res *
  page89_i2
#ISCELL
  standard offpage *
  page89_i20
#ISCELL
  standard offpage *
  page89_i21
#ISCELL
  standard offpage *
  page89_i22
#ISCELL
  standard offpage *
  page89_i23
#ISCELL
  standard tap *
  page89_i24
#ISCELL
  standard tap *
  page89_i25
#ISCELL
  standard tap *
  page89_i26
#ISCELL
  standard tap *
  page89_i27
#ISCELL
  standard tap *
  page89_i28
#ISCELL
  standard tap *
  page89_i29
#ISCELL
  standard offpage *
  page89_i3
#ISCELL
  standard tap *
  page89_i30
#ISCELL
  standard tap *
  page89_i31
#ISCELL
  standard tap *
  page89_i32
#ISCELL
  standard tap *
  page89_i33
#ISCELL
  standard tap *
  page89_i34
#ISCELL
  standard tap *
  page89_i35
#ISCELL
  standard tap *
  page89_i36
#ISCELL
  standard tap *
  page89_i37
#ISCELL
  standard tap *
  page89_i38
#ISCELL
  standard tap *
  page89_i39
#ISCELL
  standard offpage *
  page89_i4
#ISCELL
  standard tap *
  page89_i40
#ISCELL
  standard tap *
  page89_i41
#ISCELL
  standard tap *
  page89_i42
#ISCELL
  standard tap *
  page89_i43
#ISCELL
  standard tap *
  page89_i44
#ISCELL
  standard tap *
  page89_i45
#ISCELL
  standard tap *
  page89_i46
#ISCELL
  standard tap *
  page89_i47
#ISCELL
  standard tap *
  page89_i48
#ISCELL
  standard tap *
  page89_i49
#ISCELL
  standard offpage *
  page89_i5
#CELL
  pure_quanta sconn288_adr50017p087cc *
  page89_i50
#ISCELL
  standard tap *
  page89_i51
#ISCELL
  standard tap *
  page89_i52
#ISCELL
  standard tap *
  page89_i53
#ISCELL
  standard tap *
  page89_i54
#ISCELL
  standard tap *
  page89_i55
#ISCELL
  standard tap *
  page89_i56
#ISCELL
  standard tap *
  page89_i57
#ISCELL
  standard tap *
  page89_i58
#ISCELL
  standard tap *
  page89_i59
#ISCELL
  standard tap *
  page89_i60
#ISCELL
  standard tap *
  page89_i61
#ISCELL
  standard tap *
  page89_i62
#ISCELL
  standard tap *
  page89_i63
#ISCELL
  standard tap *
  page89_i64
#ISCELL
  standard tap *
  page89_i65
#ISCELL
  standard tap *
  page89_i66
#ISCELL
  standard tap *
  page89_i67
#ISCELL
  standard tap *
  page89_i68
#ISCELL
  standard tap *
  page89_i69
#ISCELL
  standard offpage *
  page89_i7
#ISCELL
  standard tap *
  page89_i70
#ISCELL
  standard tap *
  page89_i71
#ISCELL
  standard tap *
  page89_i72
#ISCELL
  standard tap *
  page89_i73
#ISCELL
  standard tap *
  page89_i74
#ISCELL
  standard tap *
  page89_i75
#ISCELL
  standard tap *
  page89_i76
#ISCELL
  standard tap *
  page89_i77
#ISCELL
  standard tap *
  page89_i78
#ISCELL
  standard tap *
  page89_i79
#ISCELL
  standard offpage *
  page89_i8
#ISCELL
  standard tap *
  page89_i80
#ISCELL
  standard tap *
  page89_i81
#ISCELL
  standard tap *
  page89_i82
#ISCELL
  standard tap *
  page89_i83
#ISCELL
  standard tap *
  page89_i84
#ISCELL
  standard tap *
  page89_i85
#ISCELL
  standard tap *
  page89_i86
#ISCELL
  standard tap *
  page89_i87
#ISCELL
  standard tap *
  page89_i88
#ISCELL
  standard tap *
  page89_i89
#ISCELL
  standard offpage *
  page89_i9
#ISCELL
  standard tap *
  page89_i90
#ISCELL
  standard tap *
  page89_i91
#ISCELL
  standard tap *
  page89_i92
#ISCELL
  standard tap *
  page89_i93
#ISCELL
  standard tap *
  page89_i94
#ISCELL
  standard tap *
  page89_i95
#ISCELL
  standard tap *
  page89_i96
#ISCELL
  standard tap *
  page89_i97
#ISCELL
  standard tap *
  page89_i98
#ISCELL
  standard tap *
  page89_i99
#ISCELL
  logical_power cad_note *
  *
#ISCELL
  pure_quanta quanta_title_block_c *
  *
#ISCELL
  logical_power universal_gnd *
  page90_i1
#ISCELL
  standard offpage *
  page90_i10
#ISCELL
  standard tap *
  page90_i100
#ISCELL
  standard tap *
  page90_i101
#ISCELL
  standard tap *
  page90_i102
#ISCELL
  standard tap *
  page90_i103
#ISCELL
  standard tap *
  page90_i104
#ISCELL
  standard tap *
  page90_i105
#ISCELL
  standard tap *
  page90_i106
#ISCELL
  standard tap *
  page90_i107
#ISCELL
  standard tap *
  page90_i108
#ISCELL
  standard offpage *
  page90_i109
#CELL
  pure_quanta q_res *
  page90_i11
#ISCELL
  standard tap *
  page90_i110
#ISCELL
  standard tap *
  page90_i111
#ISCELL
  standard tap *
  page90_i112
#ISCELL
  standard tap *
  page90_i113
#ISCELL
  standard tap *
  page90_i114
#ISCELL
  standard tap *
  page90_i115
#ISCELL
  standard tap *
  page90_i116
#ISCELL
  standard tap *
  page90_i117
#ISCELL
  standard tap *
  page90_i118
#ISCELL
  standard tap *
  page90_i119
#CELL
  pure_quanta sconn288_adr50017p130cc *
  page90_i12
#ISCELL
  logical_power vcc_core *
  page90_i120
#ISCELL
  logical_power universal_gnd *
  page90_i121
#CELL
  pure_quanta q_cap *
  page90_i122
#CELL
  pure_quanta q_cap *
  page90_i123
#ISCELL
  logical_power vcc_core *
  page90_i124
#ISCELL
  standard offpage *
  page90_i125
#ISCELL
  standard tap *
  page90_i127
#ISCELL
  standard tap *
  page90_i128
#ISCELL
  standard tap *
  page90_i129
#ISCELL
  standard offpage *
  page90_i13
#ISCELL
  standard tap *
  page90_i130
#ISCELL
  standard tap *
  page90_i131
#ISCELL
  standard tap *
  page90_i132
#ISCELL
  standard tap *
  page90_i133
#ISCELL
  standard tap *
  page90_i134
#ISCELL
  standard tap *
  page90_i135
#ISCELL
  standard tap *
  page90_i136
#ISCELL
  standard tap *
  page90_i137
#ISCELL
  standard tap *
  page90_i138
#ISCELL
  standard tap *
  page90_i139
#ISCELL
  logical_power vcc_core *
  page90_i14
#ISCELL
  standard tap *
  page90_i140
#ISCELL
  standard tap *
  page90_i141
#ISCELL
  standard tap *
  page90_i142
#ISCELL
  standard tap *
  page90_i143
#ISCELL
  logical_power universal_gnd *
  page90_i144
#CELL
  pure_quanta q_cap *
  page90_i145
#ISCELL
  logical_power universal_gnd *
  page90_i146
#CELL
  pure_quanta sconn288_adr50017p130cc *
  page90_i147
#ISCELL
  standard tap *
  page90_i148
#ISCELL
  standard tap *
  page90_i149
#ISCELL
  standard offpage *
  page90_i15
#ISCELL
  standard tap *
  page90_i150
#ISCELL
  standard tap *
  page90_i151
#ISCELL
  standard tap *
  page90_i152
#ISCELL
  standard tap *
  page90_i153
#ISCELL
  standard tap *
  page90_i154
#ISCELL
  standard tap *
  page90_i155
#ISCELL
  standard tap *
  page90_i156
#ISCELL
  standard tap *
  page90_i157
#ISCELL
  standard tap *
  page90_i158
#ISCELL
  standard tap *
  page90_i159
#ISCELL
  standard offpage *
  page90_i16
#ISCELL
  standard tap *
  page90_i160
#ISCELL
  standard tap *
  page90_i161
#ISCELL
  standard tap *
  page90_i162
#ISCELL
  standard tap *
  page90_i163
#ISCELL
  standard tap *
  page90_i164
#ISCELL
  standard tap *
  page90_i165
#ISCELL
  standard offpage *
  page90_i166
#ISCELL
  standard offpage *
  page90_i167
#ISCELL
  standard offpage *
  page90_i168
#ISCELL
  standard tap *
  page90_i169
#ISCELL
  standard offpage *
  page90_i17
#ISCELL
  standard tap *
  page90_i170
#ISCELL
  standard tap *
  page90_i171
#ISCELL
  standard tap *
  page90_i172
#ISCELL
  standard tap *
  page90_i173
#ISCELL
  standard offpage *
  page90_i174
#ISCELL
  standard offpage *
  page90_i175
#ISCELL
  logical_power vcc_core *
  page90_i176
#ISCELL
  logical_power universal_gnd *
  page90_i177
#CELL
  pure_quanta sconn288_adr50017p130cc *
  page90_i178
#CELL
  pure_quanta q_res *
  page90_i179
#ISCELL
  standard offpage *
  page90_i18
#ISCELL
  standard offpage *
  page90_i180
#ISCELL
  standard offpage *
  page90_i19
#ISCELL
  standard offpage *
  page90_i2
#ISCELL
  standard offpage *
  page90_i20
#ISCELL
  standard offpage *
  page90_i21
#ISCELL
  standard offpage *
  page90_i22
#ISCELL
  standard offpage *
  page90_i23
#ISCELL
  standard offpage *
  page90_i24
#ISCELL
  standard tap *
  page90_i25
#ISCELL
  standard tap *
  page90_i26
#ISCELL
  standard tap *
  page90_i27
#ISCELL
  standard tap *
  page90_i28
#ISCELL
  standard tap *
  page90_i29
#ISCELL
  standard offpage *
  page90_i3
#ISCELL
  standard tap *
  page90_i30
#ISCELL
  standard tap *
  page90_i31
#ISCELL
  standard tap *
  page90_i32
#ISCELL
  standard tap *
  page90_i33
#ISCELL
  standard tap *
  page90_i34
#ISCELL
  standard tap *
  page90_i35
#ISCELL
  standard tap *
  page90_i36
#ISCELL
  standard tap *
  page90_i37
#ISCELL
  standard tap *
  page90_i38
#ISCELL
  standard tap *
  page90_i39
#ISCELL
  standard offpage *
  page90_i4
#ISCELL
  standard tap *
  page90_i40
#ISCELL
  standard tap *
  page90_i41
#ISCELL
  standard tap *
  page90_i42
#ISCELL
  standard tap *
  page90_i43
#ISCELL
  standard tap *
  page90_i44
#ISCELL
  standard tap *
  page90_i45
#ISCELL
  standard tap *
  page90_i46
#ISCELL
  standard tap *
  page90_i47
#ISCELL
  standard tap *
  page90_i48
#ISCELL
  standard tap *
  page90_i49
#ISCELL
  standard offpage *
  page90_i5
#ISCELL
  standard tap *
  page90_i50
#ISCELL
  standard tap *
  page90_i51
#ISCELL
  standard tap *
  page90_i52
#ISCELL
  standard tap *
  page90_i53
#ISCELL
  standard tap *
  page90_i54
#ISCELL
  standard tap *
  page90_i55
#ISCELL
  standard tap *
  page90_i56
#ISCELL
  standard tap *
  page90_i57
#ISCELL
  standard tap *
  page90_i58
#ISCELL
  standard tap *
  page90_i59
#ISCELL
  standard tap *
  page90_i60
#ISCELL
  standard tap *
  page90_i61
#ISCELL
  standard tap *
  page90_i62
#ISCELL
  standard tap *
  page90_i63
#ISCELL
  standard tap *
  page90_i64
#ISCELL
  standard tap *
  page90_i65
#ISCELL
  standard tap *
  page90_i66
#ISCELL
  standard tap *
  page90_i67
#ISCELL
  standard tap *
  page90_i68
#ISCELL
  standard tap *
  page90_i69
#ISCELL
  standard offpage *
  page90_i7
#ISCELL
  standard tap *
  page90_i70
#ISCELL
  standard tap *
  page90_i71
#ISCELL
  standard tap *
  page90_i72
#ISCELL
  standard tap *
  page90_i73
#ISCELL
  standard tap *
  page90_i74
#ISCELL
  standard tap *
  page90_i75
#ISCELL
  standard tap *
  page90_i76
#ISCELL
  standard tap *
  page90_i77
#ISCELL
  standard tap *
  page90_i78
#ISCELL
  standard tap *
  page90_i79
#ISCELL
  standard offpage *
  page90_i8
#ISCELL
  standard tap *
  page90_i80
#ISCELL
  standard tap *
  page90_i81
#ISCELL
  standard tap *
  page90_i82
#ISCELL
  standard tap *
  page90_i83
#ISCELL
  standard tap *
  page90_i84
#ISCELL
  standard tap *
  page90_i85
#ISCELL
  standard tap *
  page90_i86
#ISCELL
  standard tap *
  page90_i87
#ISCELL
  standard tap *
  page90_i88
#ISCELL
  standard tap *
  page90_i89
#ISCELL
  standard offpage *
  page90_i9
#ISCELL
  standard tap *
  page90_i90
#ISCELL
  standard tap *
  page90_i91
#ISCELL
  standard tap *
  page90_i92
#ISCELL
  standard tap *
  page90_i93
#ISCELL
  standard tap *
  page90_i94
#ISCELL
  standard tap *
  page90_i95
#ISCELL
  standard tap *
  page90_i96
#ISCELL
  standard tap *
  page90_i97
#ISCELL
  standard tap *
  page90_i98
#ISCELL
  standard tap *
  page90_i99
#ISCELL
  logical_power cad_note *
  *
#ISCELL
  pure_quanta quanta_title_block_c *
  *
#ISCELL
  logical_power universal_gnd *
  page91_i1
#ISCELL
  standard offpage *
  page91_i10
#ISCELL
  standard tap *
  page91_i100
#ISCELL
  standard tap *
  page91_i101
#ISCELL
  standard tap *
  page91_i102
#ISCELL
  standard tap *
  page91_i103
#ISCELL
  standard tap *
  page91_i104
#ISCELL
  standard tap *
  page91_i105
#ISCELL
  standard tap *
  page91_i106
#ISCELL
  standard tap *
  page91_i107
#ISCELL
  standard tap *
  page91_i108
#ISCELL
  standard tap *
  page91_i109
#ISCELL
  standard offpage *
  page91_i11
#ISCELL
  standard tap *
  page91_i110
#ISCELL
  standard tap *
  page91_i111
#ISCELL
  standard tap *
  page91_i112
#ISCELL
  standard offpage *
  page91_i113
#ISCELL
  standard tap *
  page91_i114
#ISCELL
  standard tap *
  page91_i115
#ISCELL
  standard tap *
  page91_i116
#ISCELL
  standard tap *
  page91_i117
#ISCELL
  standard tap *
  page91_i118
#ISCELL
  standard tap *
  page91_i119
#ISCELL
  logical_power vcc_core *
  page91_i12
#ISCELL
  logical_power universal_gnd *
  page91_i120
#ISCELL
  logical_power universal_gnd *
  page91_i121
#ISCELL
  logical_power vcc_core *
  page91_i122
#CELL
  pure_quanta q_cap *
  page91_i123
#CELL
  pure_quanta q_cap *
  page91_i124
#ISCELL
  logical_power vcc_core *
  page91_i125
#ISCELL
  standard offpage *
  page91_i126
#ISCELL
  standard tap *
  page91_i128
#ISCELL
  standard tap *
  page91_i129
#CELL
  pure_quanta sconn288_adr50017p087cc *
  page91_i13
#ISCELL
  standard tap *
  page91_i130
#ISCELL
  standard tap *
  page91_i131
#ISCELL
  standard tap *
  page91_i132
#ISCELL
  standard tap *
  page91_i133
#ISCELL
  standard tap *
  page91_i134
#ISCELL
  standard tap *
  page91_i135
#ISCELL
  standard tap *
  page91_i136
#ISCELL
  standard tap *
  page91_i137
#ISCELL
  standard tap *
  page91_i138
#ISCELL
  standard tap *
  page91_i139
#ISCELL
  standard tap *
  page91_i14
#ISCELL
  standard tap *
  page91_i140
#ISCELL
  standard tap *
  page91_i141
#ISCELL
  standard tap *
  page91_i142
#ISCELL
  standard tap *
  page91_i143
#ISCELL
  standard tap *
  page91_i144
#ISCELL
  standard tap *
  page91_i145
#CELL
  pure_quanta q_cap *
  page91_i146
#ISCELL
  logical_power universal_gnd *
  page91_i147
#CELL
  pure_quanta sconn288_adr50017p087cc *
  page91_i148
#ISCELL
  standard tap *
  page91_i149
#ISCELL
  standard offpage *
  page91_i15
#ISCELL
  standard tap *
  page91_i150
#ISCELL
  standard tap *
  page91_i151
#ISCELL
  standard tap *
  page91_i152
#ISCELL
  standard tap *
  page91_i153
#ISCELL
  standard tap *
  page91_i154
#ISCELL
  standard tap *
  page91_i155
#ISCELL
  standard tap *
  page91_i156
#ISCELL
  standard tap *
  page91_i157
#ISCELL
  standard tap *
  page91_i158
#ISCELL
  standard tap *
  page91_i159
#ISCELL
  standard offpage *
  page91_i16
#ISCELL
  standard tap *
  page91_i160
#ISCELL
  standard tap *
  page91_i161
#ISCELL
  standard tap *
  page91_i162
#ISCELL
  standard tap *
  page91_i163
#ISCELL
  standard tap *
  page91_i164
#ISCELL
  standard tap *
  page91_i165
#ISCELL
  standard tap *
  page91_i166
#ISCELL
  standard tap *
  page91_i167
#ISCELL
  standard offpage *
  page91_i168
#ISCELL
  standard offpage *
  page91_i169
#ISCELL
  standard offpage *
  page91_i17
#ISCELL
  standard offpage *
  page91_i170
#ISCELL
  standard tap *
  page91_i171
#ISCELL
  standard tap *
  page91_i172
#ISCELL
  standard tap *
  page91_i173
#ISCELL
  standard offpage *
  page91_i174
#ISCELL
  standard offpage *
  page91_i175
#ISCELL
  logical_power vcc_core *
  page91_i176
#ISCELL
  logical_power universal_gnd *
  page91_i177
#CELL
  pure_quanta sconn288_adr50017p087cc *
  page91_i178
#CELL
  pure_quanta q_res *
  page91_i179
#ISCELL
  standard offpage *
  page91_i18
#ISCELL
  standard offpage *
  page91_i180
#ISCELL
  standard offpage *
  page91_i19
#CELL
  pure_quanta q_res *
  page91_i2
#ISCELL
  standard offpage *
  page91_i20
#ISCELL
  standard offpage *
  page91_i21
#ISCELL
  standard offpage *
  page91_i22
#ISCELL
  standard offpage *
  page91_i23
#ISCELL
  standard offpage *
  page91_i24
#ISCELL
  standard offpage *
  page91_i25
#ISCELL
  standard tap *
  page91_i26
#ISCELL
  standard tap *
  page91_i27
#ISCELL
  standard tap *
  page91_i28
#ISCELL
  standard tap *
  page91_i29
#ISCELL
  standard offpage *
  page91_i3
#ISCELL
  standard tap *
  page91_i30
#ISCELL
  standard tap *
  page91_i31
#ISCELL
  standard tap *
  page91_i32
#ISCELL
  standard tap *
  page91_i33
#ISCELL
  standard tap *
  page91_i34
#ISCELL
  standard tap *
  page91_i35
#ISCELL
  standard tap *
  page91_i36
#ISCELL
  standard tap *
  page91_i37
#ISCELL
  standard tap *
  page91_i38
#ISCELL
  standard tap *
  page91_i39
#ISCELL
  standard offpage *
  page91_i4
#ISCELL
  standard tap *
  page91_i40
#ISCELL
  standard tap *
  page91_i41
#ISCELL
  standard tap *
  page91_i42
#ISCELL
  standard tap *
  page91_i43
#ISCELL
  standard tap *
  page91_i44
#ISCELL
  standard tap *
  page91_i45
#ISCELL
  standard tap *
  page91_i46
#ISCELL
  standard tap *
  page91_i47
#ISCELL
  standard tap *
  page91_i48
#ISCELL
  standard tap *
  page91_i49
#ISCELL
  standard offpage *
  page91_i5
#ISCELL
  standard tap *
  page91_i50
#ISCELL
  standard tap *
  page91_i51
#ISCELL
  standard tap *
  page91_i52
#ISCELL
  standard tap *
  page91_i53
#ISCELL
  standard tap *
  page91_i54
#ISCELL
  standard tap *
  page91_i55
#ISCELL
  standard tap *
  page91_i56
#ISCELL
  standard tap *
  page91_i57
#ISCELL
  standard tap *
  page91_i58
#ISCELL
  standard tap *
  page91_i59
#ISCELL
  standard offpage *
  page91_i6
#ISCELL
  standard tap *
  page91_i60
#ISCELL
  standard tap *
  page91_i61
#ISCELL
  standard tap *
  page91_i62
#ISCELL
  standard tap *
  page91_i63
#ISCELL
  standard tap *
  page91_i64
#ISCELL
  standard tap *
  page91_i65
#ISCELL
  standard tap *
  page91_i66
#ISCELL
  standard tap *
  page91_i67
#ISCELL
  standard tap *
  page91_i68
#ISCELL
  standard tap *
  page91_i69
#ISCELL
  standard tap *
  page91_i70
#ISCELL
  standard tap *
  page91_i71
#ISCELL
  standard tap *
  page91_i72
#ISCELL
  standard tap *
  page91_i73
#ISCELL
  standard tap *
  page91_i74
#ISCELL
  standard tap *
  page91_i75
#ISCELL
  standard tap *
  page91_i76
#ISCELL
  standard tap *
  page91_i77
#ISCELL
  standard tap *
  page91_i78
#ISCELL
  standard tap *
  page91_i79
#ISCELL
  standard offpage *
  page91_i8
#ISCELL
  standard tap *
  page91_i80
#ISCELL
  standard tap *
  page91_i81
#ISCELL
  standard tap *
  page91_i82
#ISCELL
  standard tap *
  page91_i83
#ISCELL
  standard tap *
  page91_i84
#ISCELL
  standard tap *
  page91_i85
#ISCELL
  standard tap *
  page91_i86
#ISCELL
  standard tap *
  page91_i87
#ISCELL
  standard tap *
  page91_i88
#ISCELL
  standard tap *
  page91_i89
#ISCELL
  standard offpage *
  page91_i9
#ISCELL
  standard tap *
  page91_i90
#ISCELL
  standard tap *
  page91_i91
#ISCELL
  standard tap *
  page91_i92
#ISCELL
  standard tap *
  page91_i93
#ISCELL
  standard tap *
  page91_i94
#ISCELL
  standard tap *
  page91_i95
#ISCELL
  standard tap *
  page91_i96
#ISCELL
  standard tap *
  page91_i97
#ISCELL
  standard tap *
  page91_i98
#ISCELL
  standard tap *
  page91_i99
#ISCELL
  logical_power cad_note *
  *
#ISCELL
  pure_quanta quanta_title_block_c *
  *
#ISCELL
  logical_power universal_gnd *
  page92_i1
#ISCELL
  standard offpage *
  page92_i10
#ISCELL
  standard tap *
  page92_i100
#ISCELL
  standard tap *
  page92_i101
#ISCELL
  standard tap *
  page92_i102
#ISCELL
  standard tap *
  page92_i103
#ISCELL
  standard tap *
  page92_i104
#ISCELL
  standard tap *
  page92_i105
#ISCELL
  standard tap *
  page92_i106
#ISCELL
  standard tap *
  page92_i107
#ISCELL
  standard tap *
  page92_i108
#ISCELL
  standard tap *
  page92_i109
#ISCELL
  standard offpage *
  page92_i11
#ISCELL
  standard tap *
  page92_i110
#ISCELL
  standard tap *
  page92_i111
#ISCELL
  standard tap *
  page92_i112
#ISCELL
  standard tap *
  page92_i113
#ISCELL
  standard tap *
  page92_i114
#ISCELL
  standard tap *
  page92_i115
#ISCELL
  standard tap *
  page92_i116
#ISCELL
  standard tap *
  page92_i117
#ISCELL
  standard tap *
  page92_i118
#ISCELL
  standard tap *
  page92_i119
#ISCELL
  logical_power vcc_core *
  page92_i12
#ISCELL
  logical_power universal_gnd *
  page92_i120
#ISCELL
  logical_power universal_gnd *
  page92_i121
#CELL
  pure_quanta q_cap *
  page92_i122
#ISCELL
  logical_power vcc_core *
  page92_i123
#ISCELL
  standard offpage *
  page92_i124
#ISCELL
  standard offpage *
  page92_i125
#CELL
  pure_quanta q_cap *
  page92_i127
#ISCELL
  logical_power vcc_core *
  page92_i128
#ISCELL
  standard tap *
  page92_i129
#ISCELL
  standard offpage *
  page92_i13
#CELL
  pure_quanta q_cap *
  page92_i130
#ISCELL
  standard tap *
  page92_i131
#ISCELL
  standard tap *
  page92_i132
#ISCELL
  standard tap *
  page92_i133
#ISCELL
  standard tap *
  page92_i134
#ISCELL
  standard tap *
  page92_i135
#ISCELL
  standard tap *
  page92_i136
#ISCELL
  standard tap *
  page92_i137
#ISCELL
  standard tap *
  page92_i138
#ISCELL
  standard tap *
  page92_i139
#ISCELL
  standard offpage *
  page92_i14
#ISCELL
  standard tap *
  page92_i140
#ISCELL
  standard tap *
  page92_i141
#ISCELL
  standard tap *
  page92_i142
#ISCELL
  standard tap *
  page92_i143
#ISCELL
  standard tap *
  page92_i144
#ISCELL
  standard tap *
  page92_i145
#ISCELL
  standard tap *
  page92_i146
#ISCELL
  standard tap *
  page92_i147
#ISCELL
  standard tap *
  page92_i148
#ISCELL
  standard tap *
  page92_i149
#ISCELL
  standard offpage *
  page92_i15
#ISCELL
  standard tap *
  page92_i150
#ISCELL
  standard tap *
  page92_i151
#ISCELL
  standard tap *
  page92_i152
#ISCELL
  standard tap *
  page92_i153
#ISCELL
  standard tap *
  page92_i154
#ISCELL
  standard tap *
  page92_i155
#ISCELL
  standard tap *
  page92_i156
#ISCELL
  standard tap *
  page92_i157
#ISCELL
  standard tap *
  page92_i158
#ISCELL
  standard tap *
  page92_i159
#ISCELL
  standard offpage *
  page92_i16
#ISCELL
  standard tap *
  page92_i160
#ISCELL
  standard tap *
  page92_i161
#ISCELL
  standard tap *
  page92_i162
#ISCELL
  standard tap *
  page92_i163
#ISCELL
  standard tap *
  page92_i164
#ISCELL
  standard tap *
  page92_i165
#ISCELL
  standard tap *
  page92_i166
#ISCELL
  standard tap *
  page92_i167
#ISCELL
  standard tap *
  page92_i168
#ISCELL
  standard tap *
  page92_i169
#ISCELL
  standard offpage *
  page92_i17
#ISCELL
  standard offpage *
  page92_i170
#ISCELL
  standard offpage *
  page92_i171
#ISCELL
  standard offpage *
  page92_i172
#ISCELL
  standard offpage *
  page92_i173
#ISCELL
  logical_power universal_gnd *
  page92_i174
#CELL
  pure_quanta sconn288_adr50017p130cc *
  page92_i175
#ISCELL
  logical_power universal_gnd *
  page92_i176
#ISCELL
  logical_power vcc_core *
  page92_i177
#CELL
  pure_quanta sconn288_adr50017p130cc *
  page92_i178
#CELL
  pure_quanta q_res *
  page92_i179
#ISCELL
  standard offpage *
  page92_i18
#ISCELL
  standard offpage *
  page92_i180
#ISCELL
  standard offpage *
  page92_i19
#CELL
  pure_quanta q_res *
  page92_i2
#ISCELL
  standard offpage *
  page92_i20
#ISCELL
  standard offpage *
  page92_i21
#ISCELL
  standard offpage *
  page92_i22
#ISCELL
  standard offpage *
  page92_i23
#ISCELL
  standard offpage *
  page92_i24
#CELL
  pure_quanta sconn288_adr50017p130cc *
  page92_i25
#ISCELL
  standard tap *
  page92_i26
#ISCELL
  standard tap *
  page92_i27
#ISCELL
  standard tap *
  page92_i28
#ISCELL
  standard tap *
  page92_i29
#ISCELL
  standard offpage *
  page92_i3
#ISCELL
  standard tap *
  page92_i30
#ISCELL
  standard tap *
  page92_i31
#ISCELL
  standard tap *
  page92_i32
#ISCELL
  standard tap *
  page92_i33
#ISCELL
  standard tap *
  page92_i34
#ISCELL
  standard tap *
  page92_i35
#ISCELL
  standard tap *
  page92_i36
#ISCELL
  standard tap *
  page92_i37
#ISCELL
  standard tap *
  page92_i38
#ISCELL
  standard tap *
  page92_i39
#ISCELL
  standard offpage *
  page92_i4
#ISCELL
  standard tap *
  page92_i40
#ISCELL
  standard tap *
  page92_i41
#ISCELL
  standard tap *
  page92_i42
#ISCELL
  standard tap *
  page92_i43
#ISCELL
  standard tap *
  page92_i44
#ISCELL
  standard tap *
  page92_i45
#ISCELL
  standard tap *
  page92_i46
#ISCELL
  standard tap *
  page92_i47
#ISCELL
  standard tap *
  page92_i48
#ISCELL
  standard tap *
  page92_i49
#ISCELL
  standard offpage *
  page92_i5
#ISCELL
  standard tap *
  page92_i50
#ISCELL
  standard tap *
  page92_i51
#ISCELL
  standard tap *
  page92_i52
#ISCELL
  standard tap *
  page92_i53
#ISCELL
  standard tap *
  page92_i54
#ISCELL
  standard tap *
  page92_i55
#ISCELL
  standard tap *
  page92_i56
#ISCELL
  standard tap *
  page92_i57
#ISCELL
  standard tap *
  page92_i58
#ISCELL
  standard tap *
  page92_i59
#ISCELL
  standard offpage *
  page92_i6
#ISCELL
  standard tap *
  page92_i60
#ISCELL
  standard tap *
  page92_i61
#ISCELL
  standard tap *
  page92_i62
#ISCELL
  standard tap *
  page92_i63
#ISCELL
  standard tap *
  page92_i64
#ISCELL
  standard tap *
  page92_i65
#ISCELL
  standard tap *
  page92_i66
#ISCELL
  standard tap *
  page92_i67
#ISCELL
  standard tap *
  page92_i68
#ISCELL
  standard tap *
  page92_i69
#ISCELL
  standard offpage *
  page92_i7
#ISCELL
  standard tap *
  page92_i70
#ISCELL
  standard tap *
  page92_i71
#ISCELL
  standard tap *
  page92_i72
#ISCELL
  standard tap *
  page92_i73
#ISCELL
  standard tap *
  page92_i74
#ISCELL
  standard tap *
  page92_i75
#ISCELL
  standard tap *
  page92_i76
#ISCELL
  standard tap *
  page92_i77
#ISCELL
  standard tap *
  page92_i78
#ISCELL
  standard tap *
  page92_i79
#ISCELL
  standard tap *
  page92_i80
#ISCELL
  standard tap *
  page92_i81
#ISCELL
  standard tap *
  page92_i82
#ISCELL
  standard tap *
  page92_i83
#ISCELL
  standard tap *
  page92_i84
#ISCELL
  standard tap *
  page92_i85
#ISCELL
  standard tap *
  page92_i86
#ISCELL
  standard tap *
  page92_i87
#ISCELL
  standard tap *
  page92_i88
#ISCELL
  standard tap *
  page92_i89
#ISCELL
  standard offpage *
  page92_i9
#ISCELL
  standard tap *
  page92_i90
#ISCELL
  standard tap *
  page92_i91
#ISCELL
  standard tap *
  page92_i92
#ISCELL
  standard tap *
  page92_i93
#ISCELL
  standard tap *
  page92_i94
#ISCELL
  standard tap *
  page92_i95
#ISCELL
  standard tap *
  page92_i96
#ISCELL
  standard tap *
  page92_i97
#ISCELL
  standard tap *
  page92_i98
#ISCELL
  standard tap *
  page92_i99
#ISCELL
  logical_power cad_note *
  *
#ISCELL
  pure_quanta quanta_title_block_c *
  *
#ISCELL
  logical_power universal_gnd *
  page93_i1
#ISCELL
  standard offpage *
  page93_i10
#ISCELL
  standard tap *
  page93_i100
#ISCELL
  standard tap *
  page93_i101
#ISCELL
  standard tap *
  page93_i102
#ISCELL
  standard tap *
  page93_i103
#ISCELL
  standard tap *
  page93_i104
#ISCELL
  standard tap *
  page93_i105
#ISCELL
  standard tap *
  page93_i106
#ISCELL
  standard tap *
  page93_i107
#ISCELL
  standard tap *
  page93_i108
#ISCELL
  standard tap *
  page93_i109
#ISCELL
  standard offpage *
  page93_i11
#ISCELL
  standard tap *
  page93_i110
#ISCELL
  standard tap *
  page93_i111
#ISCELL
  standard tap *
  page93_i112
#ISCELL
  standard tap *
  page93_i113
#ISCELL
  standard tap *
  page93_i114
#ISCELL
  standard tap *
  page93_i115
#ISCELL
  standard tap *
  page93_i116
#ISCELL
  standard offpage *
  page93_i117
#ISCELL
  standard tap *
  page93_i118
#ISCELL
  standard tap *
  page93_i119
#ISCELL
  logical_power vcc_core *
  page93_i12
#ISCELL
  logical_power universal_gnd *
  page93_i120
#ISCELL
  logical_power universal_gnd *
  page93_i121
#CELL
  pure_quanta q_cap *
  page93_i122
#ISCELL
  logical_power vcc_core *
  page93_i123
#ISCELL
  standard offpage *
  page93_i124
#CELL
  pure_quanta q_cap *
  page93_i126
#ISCELL
  logical_power vcc_core *
  page93_i127
#CELL
  pure_quanta q_cap *
  page93_i128
#ISCELL
  standard tap *
  page93_i129
#ISCELL
  standard offpage *
  page93_i13
#ISCELL
  standard tap *
  page93_i130
#ISCELL
  standard tap *
  page93_i131
#ISCELL
  standard tap *
  page93_i132
#ISCELL
  standard tap *
  page93_i133
#ISCELL
  standard tap *
  page93_i134
#ISCELL
  standard tap *
  page93_i135
#ISCELL
  standard tap *
  page93_i136
#ISCELL
  standard tap *
  page93_i137
#ISCELL
  standard tap *
  page93_i138
#ISCELL
  standard tap *
  page93_i139
#ISCELL
  standard offpage *
  page93_i14
#ISCELL
  standard tap *
  page93_i140
#ISCELL
  standard tap *
  page93_i141
#ISCELL
  standard tap *
  page93_i142
#ISCELL
  standard tap *
  page93_i143
#ISCELL
  standard tap *
  page93_i144
#ISCELL
  standard tap *
  page93_i145
#ISCELL
  standard tap *
  page93_i146
#ISCELL
  standard tap *
  page93_i147
#ISCELL
  standard tap *
  page93_i148
#ISCELL
  standard tap *
  page93_i149
#ISCELL
  standard offpage *
  page93_i15
#ISCELL
  standard tap *
  page93_i150
#ISCELL
  standard tap *
  page93_i151
#ISCELL
  standard tap *
  page93_i152
#ISCELL
  standard tap *
  page93_i153
#ISCELL
  standard tap *
  page93_i154
#ISCELL
  standard tap *
  page93_i155
#ISCELL
  standard tap *
  page93_i156
#ISCELL
  standard tap *
  page93_i157
#ISCELL
  standard tap *
  page93_i158
#ISCELL
  standard tap *
  page93_i159
#ISCELL
  standard offpage *
  page93_i16
#ISCELL
  standard tap *
  page93_i160
#ISCELL
  standard tap *
  page93_i161
#ISCELL
  standard tap *
  page93_i162
#ISCELL
  standard tap *
  page93_i163
#ISCELL
  standard tap *
  page93_i164
#ISCELL
  standard tap *
  page93_i165
#ISCELL
  standard tap *
  page93_i166
#ISCELL
  standard tap *
  page93_i167
#ISCELL
  standard offpage *
  page93_i168
#ISCELL
  standard offpage *
  page93_i169
#ISCELL
  standard offpage *
  page93_i17
#ISCELL
  standard offpage *
  page93_i170
#ISCELL
  standard offpage *
  page93_i171
#ISCELL
  standard tap *
  page93_i172
#ISCELL
  standard offpage *
  page93_i173
#ISCELL
  logical_power universal_gnd *
  page93_i174
#CELL
  pure_quanta sconn288_adr50017p087cc *
  page93_i175
#ISCELL
  logical_power universal_gnd *
  page93_i176
#ISCELL
  logical_power vcc_core *
  page93_i177
#CELL
  pure_quanta sconn288_adr50017p087cc *
  page93_i178
#CELL
  pure_quanta q_res *
  page93_i179
#ISCELL
  standard offpage *
  page93_i18
#ISCELL
  standard offpage *
  page93_i180
#ISCELL
  standard offpage *
  page93_i19
#CELL
  pure_quanta q_res *
  page93_i2
#ISCELL
  standard offpage *
  page93_i20
#ISCELL
  standard offpage *
  page93_i21
#ISCELL
  standard offpage *
  page93_i22
#ISCELL
  standard offpage *
  page93_i23
#CELL
  pure_quanta sconn288_adr50017p087cc *
  page93_i24
#ISCELL
  standard tap *
  page93_i25
#ISCELL
  standard tap *
  page93_i26
#ISCELL
  standard tap *
  page93_i27
#ISCELL
  standard tap *
  page93_i28
#ISCELL
  standard tap *
  page93_i29
#ISCELL
  standard offpage *
  page93_i3
#ISCELL
  standard tap *
  page93_i30
#ISCELL
  standard tap *
  page93_i31
#ISCELL
  standard tap *
  page93_i32
#ISCELL
  standard tap *
  page93_i33
#ISCELL
  standard tap *
  page93_i34
#ISCELL
  standard tap *
  page93_i35
#ISCELL
  standard tap *
  page93_i36
#ISCELL
  standard tap *
  page93_i37
#ISCELL
  standard tap *
  page93_i38
#ISCELL
  standard tap *
  page93_i39
#ISCELL
  standard offpage *
  page93_i4
#ISCELL
  standard tap *
  page93_i40
#ISCELL
  standard tap *
  page93_i41
#ISCELL
  standard tap *
  page93_i42
#ISCELL
  standard tap *
  page93_i43
#ISCELL
  standard tap *
  page93_i44
#ISCELL
  standard tap *
  page93_i45
#ISCELL
  standard tap *
  page93_i46
#ISCELL
  standard tap *
  page93_i47
#ISCELL
  standard tap *
  page93_i48
#ISCELL
  standard tap *
  page93_i49
#ISCELL
  standard offpage *
  page93_i5
#ISCELL
  standard tap *
  page93_i50
#ISCELL
  standard tap *
  page93_i51
#ISCELL
  standard tap *
  page93_i52
#ISCELL
  standard tap *
  page93_i53
#ISCELL
  standard tap *
  page93_i54
#ISCELL
  standard tap *
  page93_i55
#ISCELL
  standard tap *
  page93_i56
#ISCELL
  standard tap *
  page93_i57
#ISCELL
  standard tap *
  page93_i58
#ISCELL
  standard tap *
  page93_i59
#ISCELL
  standard offpage *
  page93_i6
#ISCELL
  standard tap *
  page93_i60
#ISCELL
  standard tap *
  page93_i61
#ISCELL
  standard tap *
  page93_i62
#ISCELL
  standard tap *
  page93_i63
#ISCELL
  standard tap *
  page93_i64
#ISCELL
  standard tap *
  page93_i65
#ISCELL
  standard tap *
  page93_i66
#ISCELL
  standard tap *
  page93_i67
#ISCELL
  standard tap *
  page93_i68
#ISCELL
  standard tap *
  page93_i69
#ISCELL
  standard tap *
  page93_i70
#ISCELL
  standard tap *
  page93_i71
#ISCELL
  standard tap *
  page93_i72
#ISCELL
  standard tap *
  page93_i73
#ISCELL
  standard tap *
  page93_i74
#ISCELL
  standard tap *
  page93_i75
#ISCELL
  standard tap *
  page93_i76
#ISCELL
  standard tap *
  page93_i77
#ISCELL
  standard tap *
  page93_i78
#ISCELL
  standard tap *
  page93_i79
#ISCELL
  standard offpage *
  page93_i8
#ISCELL
  standard tap *
  page93_i80
#ISCELL
  standard tap *
  page93_i81
#ISCELL
  standard tap *
  page93_i82
#ISCELL
  standard tap *
  page93_i83
#ISCELL
  standard tap *
  page93_i84
#ISCELL
  standard tap *
  page93_i85
#ISCELL
  standard tap *
  page93_i86
#ISCELL
  standard tap *
  page93_i87
#ISCELL
  standard tap *
  page93_i88
#ISCELL
  standard tap *
  page93_i89
#ISCELL
  standard offpage *
  page93_i9
#ISCELL
  standard tap *
  page93_i90
#ISCELL
  standard tap *
  page93_i91
#ISCELL
  standard tap *
  page93_i92
#ISCELL
  standard tap *
  page93_i93
#ISCELL
  standard tap *
  page93_i94
#ISCELL
  standard tap *
  page93_i95
#ISCELL
  standard tap *
  page93_i96
#ISCELL
  standard tap *
  page93_i97
#ISCELL
  standard tap *
  page93_i98
#ISCELL
  standard tap *
  page93_i99
#ISCELL
  logical_power cad_note *
  *
#ISCELL
  pure_quanta quanta_title_block_c *
  *
#ISCELL
  standard offpage *
  page94_i1
#CELL
  pure_quanta q_res *
  page94_i10
#ISCELL
  standard tap *
  page94_i100
#ISCELL
  standard tap *
  page94_i101
#ISCELL
  standard tap *
  page94_i102
#ISCELL
  standard tap *
  page94_i103
#ISCELL
  standard tap *
  page94_i104
#ISCELL
  standard offpage *
  page94_i105
#ISCELL
  standard offpage *
  page94_i106
#ISCELL
  standard tap *
  page94_i107
#ISCELL
  standard tap *
  page94_i108
#ISCELL
  standard tap *
  page94_i109
#CELL
  pure_quanta sconn288_adr50017p130cc *
  page94_i11
#ISCELL
  standard tap *
  page94_i110
#ISCELL
  standard tap *
  page94_i111
#ISCELL
  standard tap *
  page94_i112
#ISCELL
  standard tap *
  page94_i113
#ISCELL
  standard tap *
  page94_i114
#ISCELL
  standard tap *
  page94_i115
#ISCELL
  standard tap *
  page94_i116
#ISCELL
  standard tap *
  page94_i117
#ISCELL
  standard tap *
  page94_i118
#ISCELL
  standard tap *
  page94_i119
#ISCELL
  standard offpage *
  page94_i12
#ISCELL
  standard tap *
  page94_i120
#ISCELL
  standard offpage *
  page94_i121
#ISCELL
  logical_power universal_gnd *
  page94_i122
#CELL
  pure_quanta q_cap *
  page94_i123
#ISCELL
  logical_power vcc_core *
  page94_i124
#CELL
  pure_quanta q_cap *
  page94_i125
#ISCELL
  logical_power vcc_core *
  page94_i126
#ISCELL
  standard tap *
  page94_i128
#ISCELL
  standard tap *
  page94_i129
#ISCELL
  standard offpage *
  page94_i13
#ISCELL
  standard tap *
  page94_i130
#ISCELL
  standard tap *
  page94_i131
#ISCELL
  standard tap *
  page94_i132
#ISCELL
  standard tap *
  page94_i133
#ISCELL
  standard tap *
  page94_i134
#ISCELL
  standard tap *
  page94_i135
#ISCELL
  standard tap *
  page94_i136
#ISCELL
  standard tap *
  page94_i137
#ISCELL
  standard tap *
  page94_i138
#ISCELL
  standard tap *
  page94_i139
#ISCELL
  standard offpage *
  page94_i14
#ISCELL
  standard tap *
  page94_i140
#ISCELL
  standard tap *
  page94_i141
#ISCELL
  standard tap *
  page94_i142
#ISCELL
  standard tap *
  page94_i143
#ISCELL
  standard tap *
  page94_i144
#ISCELL
  standard tap *
  page94_i145
#ISCELL
  standard tap *
  page94_i146
#ISCELL
  standard tap *
  page94_i147
#ISCELL
  standard tap *
  page94_i148
#ISCELL
  standard tap *
  page94_i149
#ISCELL
  standard offpage *
  page94_i15
#ISCELL
  standard tap *
  page94_i150
#ISCELL
  standard tap *
  page94_i151
#ISCELL
  standard tap *
  page94_i152
#ISCELL
  standard tap *
  page94_i153
#ISCELL
  standard tap *
  page94_i154
#ISCELL
  standard tap *
  page94_i155
#ISCELL
  standard tap *
  page94_i156
#ISCELL
  standard tap *
  page94_i157
#ISCELL
  standard tap *
  page94_i158
#ISCELL
  standard tap *
  page94_i159
#ISCELL
  logical_power vcc_core *
  page94_i16
#ISCELL
  standard tap *
  page94_i160
#ISCELL
  logical_power universal_gnd *
  page94_i161
#CELL
  pure_quanta q_cap *
  page94_i162
#ISCELL
  logical_power universal_gnd *
  page94_i163
#CELL
  pure_quanta sconn288_adr50017p130cc *
  page94_i164
#ISCELL
  standard offpage *
  page94_i165
#ISCELL
  standard offpage *
  page94_i166
#ISCELL
  standard tap *
  page94_i167
#ISCELL
  standard tap *
  page94_i168
#ISCELL
  standard tap *
  page94_i169
#ISCELL
  standard offpage *
  page94_i17
#ISCELL
  standard tap *
  page94_i170
#ISCELL
  standard tap *
  page94_i171
#ISCELL
  standard tap *
  page94_i172
#ISCELL
  standard tap *
  page94_i173
#ISCELL
  standard offpage *
  page94_i174
#ISCELL
  standard offpage *
  page94_i175
#ISCELL
  logical_power vcc_core *
  page94_i176
#ISCELL
  logical_power universal_gnd *
  page94_i177
#CELL
  pure_quanta sconn288_adr50017p130cc *
  page94_i178
#CELL
  pure_quanta q_res *
  page94_i179
#ISCELL
  standard offpage *
  page94_i18
#ISCELL
  standard offpage *
  page94_i180
#ISCELL
  standard offpage *
  page94_i19
#ISCELL
  standard offpage *
  page94_i2
#ISCELL
  standard offpage *
  page94_i20
#ISCELL
  standard offpage *
  page94_i21
#ISCELL
  standard offpage *
  page94_i22
#ISCELL
  standard offpage *
  page94_i23
#ISCELL
  standard offpage *
  page94_i24
#ISCELL
  standard tap *
  page94_i25
#ISCELL
  standard tap *
  page94_i26
#ISCELL
  standard tap *
  page94_i27
#ISCELL
  standard tap *
  page94_i28
#ISCELL
  standard tap *
  page94_i29
#ISCELL
  standard offpage *
  page94_i3
#ISCELL
  standard tap *
  page94_i30
#ISCELL
  standard tap *
  page94_i31
#ISCELL
  standard tap *
  page94_i32
#ISCELL
  standard tap *
  page94_i33
#ISCELL
  standard tap *
  page94_i34
#ISCELL
  standard tap *
  page94_i35
#ISCELL
  standard tap *
  page94_i36
#ISCELL
  standard tap *
  page94_i37
#ISCELL
  standard tap *
  page94_i38
#ISCELL
  standard tap *
  page94_i39
#ISCELL
  standard offpage *
  page94_i4
#ISCELL
  standard tap *
  page94_i40
#ISCELL
  standard tap *
  page94_i41
#ISCELL
  standard tap *
  page94_i42
#ISCELL
  standard tap *
  page94_i43
#ISCELL
  standard tap *
  page94_i44
#ISCELL
  standard tap *
  page94_i45
#ISCELL
  standard tap *
  page94_i46
#ISCELL
  standard tap *
  page94_i47
#ISCELL
  standard tap *
  page94_i48
#ISCELL
  standard tap *
  page94_i49
#ISCELL
  standard tap *
  page94_i50
#ISCELL
  standard tap *
  page94_i51
#ISCELL
  standard tap *
  page94_i52
#ISCELL
  standard tap *
  page94_i53
#ISCELL
  standard tap *
  page94_i54
#ISCELL
  standard tap *
  page94_i55
#ISCELL
  standard tap *
  page94_i56
#ISCELL
  standard tap *
  page94_i57
#ISCELL
  standard tap *
  page94_i58
#ISCELL
  standard tap *
  page94_i59
#ISCELL
  standard offpage *
  page94_i6
#ISCELL
  standard tap *
  page94_i60
#ISCELL
  standard tap *
  page94_i61
#ISCELL
  standard tap *
  page94_i62
#ISCELL
  standard tap *
  page94_i63
#ISCELL
  standard tap *
  page94_i64
#ISCELL
  standard tap *
  page94_i65
#ISCELL
  standard tap *
  page94_i66
#ISCELL
  standard tap *
  page94_i67
#ISCELL
  standard tap *
  page94_i68
#ISCELL
  standard tap *
  page94_i69
#ISCELL
  standard offpage *
  page94_i7
#ISCELL
  standard tap *
  page94_i70
#ISCELL
  standard tap *
  page94_i71
#ISCELL
  standard tap *
  page94_i72
#ISCELL
  standard tap *
  page94_i73
#ISCELL
  standard tap *
  page94_i74
#ISCELL
  standard tap *
  page94_i75
#ISCELL
  standard tap *
  page94_i76
#ISCELL
  standard tap *
  page94_i77
#ISCELL
  standard tap *
  page94_i78
#ISCELL
  standard tap *
  page94_i79
#ISCELL
  standard offpage *
  page94_i8
#ISCELL
  standard tap *
  page94_i80
#ISCELL
  standard tap *
  page94_i81
#ISCELL
  standard tap *
  page94_i82
#ISCELL
  standard tap *
  page94_i83
#ISCELL
  standard tap *
  page94_i84
#ISCELL
  standard tap *
  page94_i85
#ISCELL
  standard tap *
  page94_i86
#ISCELL
  standard tap *
  page94_i87
#ISCELL
  standard tap *
  page94_i88
#ISCELL
  standard tap *
  page94_i89
#ISCELL
  logical_power universal_gnd *
  page94_i9
#ISCELL
  standard tap *
  page94_i90
#ISCELL
  standard tap *
  page94_i91
#ISCELL
  standard tap *
  page94_i92
#ISCELL
  standard tap *
  page94_i93
#ISCELL
  standard tap *
  page94_i94
#ISCELL
  standard tap *
  page94_i95
#ISCELL
  standard tap *
  page94_i96
#ISCELL
  standard tap *
  page94_i97
#ISCELL
  standard tap *
  page94_i98
#ISCELL
  standard tap *
  page94_i99
#ISCELL
  logical_power cad_note *
  *
#ISCELL
  pure_quanta quanta_title_block_c *
  *
#ISCELL
  standard offpage *
  page95_i1
#ISCELL
  standard offpage *
  page95_i10
#ISCELL
  standard tap *
  page95_i100
#ISCELL
  standard tap *
  page95_i101
#ISCELL
  standard tap *
  page95_i102
#ISCELL
  standard tap *
  page95_i103
#ISCELL
  standard tap *
  page95_i104
#ISCELL
  standard offpage *
  page95_i105
#ISCELL
  standard tap *
  page95_i106
#ISCELL
  standard tap *
  page95_i107
#ISCELL
  standard tap *
  page95_i108
#ISCELL
  standard tap *
  page95_i109
#ISCELL
  standard offpage *
  page95_i11
#ISCELL
  standard tap *
  page95_i110
#ISCELL
  standard tap *
  page95_i111
#ISCELL
  standard tap *
  page95_i112
#ISCELL
  standard tap *
  page95_i113
#ISCELL
  standard tap *
  page95_i114
#ISCELL
  standard tap *
  page95_i115
#ISCELL
  standard tap *
  page95_i116
#ISCELL
  standard tap *
  page95_i117
#ISCELL
  standard tap *
  page95_i118
#ISCELL
  standard tap *
  page95_i119
#ISCELL
  standard offpage *
  page95_i12
#ISCELL
  logical_power universal_gnd *
  page95_i120
#CELL
  pure_quanta q_cap *
  page95_i121
#ISCELL
  logical_power vcc_core *
  page95_i122
#ISCELL
  standard offpage *
  page95_i123
#CELL
  pure_quanta q_cap *
  page95_i125
#ISCELL
  logical_power vcc_core *
  page95_i126
#ISCELL
  logical_power universal_gnd *
  page95_i127
#CELL
  pure_quanta q_cap *
  page95_i128
#ISCELL
  logical_power universal_gnd *
  page95_i129
#ISCELL
  standard offpage *
  page95_i13
#ISCELL
  standard tap *
  page95_i130
#ISCELL
  standard tap *
  page95_i131
#ISCELL
  standard tap *
  page95_i132
#ISCELL
  standard tap *
  page95_i133
#ISCELL
  standard tap *
  page95_i134
#ISCELL
  standard tap *
  page95_i135
#ISCELL
  standard tap *
  page95_i136
#ISCELL
  standard tap *
  page95_i137
#ISCELL
  standard tap *
  page95_i138
#ISCELL
  standard tap *
  page95_i139
#ISCELL
  standard offpage *
  page95_i14
#ISCELL
  standard tap *
  page95_i140
#ISCELL
  standard tap *
  page95_i141
#ISCELL
  standard tap *
  page95_i142
#ISCELL
  standard tap *
  page95_i143
#ISCELL
  standard tap *
  page95_i144
#ISCELL
  standard tap *
  page95_i145
#ISCELL
  standard tap *
  page95_i146
#ISCELL
  standard tap *
  page95_i147
#ISCELL
  standard tap *
  page95_i148
#ISCELL
  standard tap *
  page95_i149
#ISCELL
  standard offpage *
  page95_i15
#ISCELL
  standard tap *
  page95_i150
#ISCELL
  standard tap *
  page95_i151
#ISCELL
  standard tap *
  page95_i152
#ISCELL
  standard tap *
  page95_i153
#ISCELL
  standard tap *
  page95_i154
#ISCELL
  standard tap *
  page95_i155
#ISCELL
  standard tap *
  page95_i156
#ISCELL
  standard tap *
  page95_i157
#ISCELL
  standard tap *
  page95_i158
#ISCELL
  standard tap *
  page95_i159
#ISCELL
  standard offpage *
  page95_i16
#ISCELL
  standard tap *
  page95_i160
#ISCELL
  standard tap *
  page95_i161
#ISCELL
  standard tap *
  page95_i162
#ISCELL
  standard offpage *
  page95_i163
#ISCELL
  standard offpage *
  page95_i164
#ISCELL
  standard offpage *
  page95_i165
#ISCELL
  standard tap *
  page95_i166
#ISCELL
  standard tap *
  page95_i167
#ISCELL
  standard tap *
  page95_i168
#ISCELL
  standard tap *
  page95_i169
#ISCELL
  standard offpage *
  page95_i17
#ISCELL
  standard tap *
  page95_i170
#ISCELL
  standard tap *
  page95_i171
#ISCELL
  standard tap *
  page95_i172
#ISCELL
  standard offpage *
  page95_i173
#ISCELL
  standard offpage *
  page95_i174
#ISCELL
  logical_power vcc_core *
  page95_i175
#CELL
  pure_quanta sconn288_adr50017p087cc *
  page95_i176
#ISCELL
  logical_power universal_gnd *
  page95_i177
#CELL
  pure_quanta sconn288_adr50017p087cc *
  page95_i178
#CELL
  pure_quanta q_res *
  page95_i179
#ISCELL
  standard offpage *
  page95_i18
#ISCELL
  standard offpage *
  page95_i180
#ISCELL
  standard offpage *
  page95_i19
#ISCELL
  standard offpage *
  page95_i2
#ISCELL
  standard offpage *
  page95_i20
#ISCELL
  logical_power vcc_core *
  page95_i21
#ISCELL
  standard tap *
  page95_i22
#ISCELL
  standard tap *
  page95_i23
#ISCELL
  standard tap *
  page95_i24
#ISCELL
  standard tap *
  page95_i25
#ISCELL
  standard tap *
  page95_i26
#ISCELL
  standard tap *
  page95_i27
#ISCELL
  standard tap *
  page95_i28
#ISCELL
  standard tap *
  page95_i29
#ISCELL
  standard offpage *
  page95_i3
#ISCELL
  standard tap *
  page95_i30
#ISCELL
  standard tap *
  page95_i31
#ISCELL
  standard tap *
  page95_i32
#ISCELL
  standard tap *
  page95_i33
#ISCELL
  standard tap *
  page95_i34
#ISCELL
  standard tap *
  page95_i35
#ISCELL
  standard tap *
  page95_i36
#ISCELL
  standard tap *
  page95_i37
#ISCELL
  standard tap *
  page95_i38
#ISCELL
  standard tap *
  page95_i39
#ISCELL
  standard offpage *
  page95_i4
#ISCELL
  standard tap *
  page95_i40
#ISCELL
  standard tap *
  page95_i41
#ISCELL
  standard tap *
  page95_i42
#ISCELL
  standard tap *
  page95_i43
#ISCELL
  standard tap *
  page95_i44
#ISCELL
  logical_power universal_gnd *
  page95_i45
#CELL
  pure_quanta q_res *
  page95_i46
#CELL
  pure_quanta sconn288_adr50017p087cc *
  page95_i47
#ISCELL
  standard tap *
  page95_i48
#ISCELL
  standard tap *
  page95_i49
#ISCELL
  standard tap *
  page95_i50
#ISCELL
  standard tap *
  page95_i51
#ISCELL
  standard tap *
  page95_i52
#ISCELL
  standard tap *
  page95_i53
#ISCELL
  standard tap *
  page95_i54
#ISCELL
  standard tap *
  page95_i55
#ISCELL
  standard tap *
  page95_i56
#ISCELL
  standard tap *
  page95_i57
#ISCELL
  standard tap *
  page95_i58
#ISCELL
  standard tap *
  page95_i59
#ISCELL
  standard offpage *
  page95_i6
#ISCELL
  standard tap *
  page95_i60
#ISCELL
  standard tap *
  page95_i61
#ISCELL
  standard tap *
  page95_i62
#ISCELL
  standard tap *
  page95_i63
#ISCELL
  standard tap *
  page95_i64
#ISCELL
  standard tap *
  page95_i65
#ISCELL
  standard tap *
  page95_i66
#ISCELL
  standard tap *
  page95_i67
#ISCELL
  standard tap *
  page95_i68
#ISCELL
  standard tap *
  page95_i69
#ISCELL
  standard offpage *
  page95_i7
#ISCELL
  standard tap *
  page95_i70
#ISCELL
  standard tap *
  page95_i71
#ISCELL
  standard tap *
  page95_i72
#ISCELL
  standard tap *
  page95_i73
#ISCELL
  standard tap *
  page95_i74
#ISCELL
  standard tap *
  page95_i75
#ISCELL
  standard tap *
  page95_i76
#ISCELL
  standard tap *
  page95_i77
#ISCELL
  standard tap *
  page95_i78
#ISCELL
  standard tap *
  page95_i79
#ISCELL
  standard offpage *
  page95_i8
#ISCELL
  standard tap *
  page95_i80
#ISCELL
  standard tap *
  page95_i81
#ISCELL
  standard tap *
  page95_i82
#ISCELL
  standard tap *
  page95_i83
#ISCELL
  standard tap *
  page95_i84
#ISCELL
  standard tap *
  page95_i85
#ISCELL
  standard tap *
  page95_i86
#ISCELL
  standard tap *
  page95_i87
#ISCELL
  standard tap *
  page95_i88
#ISCELL
  standard tap *
  page95_i89
#ISCELL
  standard offpage *
  page95_i9
#ISCELL
  standard tap *
  page95_i90
#ISCELL
  standard tap *
  page95_i91
#ISCELL
  standard tap *
  page95_i92
#ISCELL
  standard tap *
  page95_i93
#ISCELL
  standard tap *
  page95_i94
#ISCELL
  standard tap *
  page95_i95
#ISCELL
  standard tap *
  page95_i96
#ISCELL
  standard tap *
  page95_i97
#ISCELL
  standard tap *
  page95_i98
#ISCELL
  standard tap *
  page95_i99
#ISCELL
  logical_power cad_note *
  *
#ISCELL
  pure_quanta quanta_title_block_c *
  *
#ISCELL
  logical_power universal_gnd *
  page96_i1
#ISCELL
  standard offpage *
  page96_i10
#ISCELL
  standard tap *
  page96_i100
#ISCELL
  standard tap *
  page96_i101
#ISCELL
  standard tap *
  page96_i102
#ISCELL
  standard tap *
  page96_i103
#ISCELL
  standard tap *
  page96_i104
#ISCELL
  standard tap *
  page96_i105
#ISCELL
  standard tap *
  page96_i106
#ISCELL
  standard offpage *
  page96_i107
#ISCELL
  standard tap *
  page96_i108
#ISCELL
  standard tap *
  page96_i109
#ISCELL
  standard offpage *
  page96_i11
#ISCELL
  standard tap *
  page96_i110
#ISCELL
  standard tap *
  page96_i111
#ISCELL
  standard tap *
  page96_i112
#ISCELL
  standard tap *
  page96_i113
#ISCELL
  standard tap *
  page96_i114
#ISCELL
  standard tap *
  page96_i115
#ISCELL
  standard tap *
  page96_i116
#ISCELL
  standard tap *
  page96_i117
#ISCELL
  standard tap *
  page96_i118
#ISCELL
  standard tap *
  page96_i119
#ISCELL
  standard offpage *
  page96_i12
#ISCELL
  logical_power universal_gnd *
  page96_i120
#CELL
  pure_quanta q_cap *
  page96_i121
#ISCELL
  logical_power vcc_core *
  page96_i122
#ISCELL
  standard offpage *
  page96_i123
#CELL
  pure_quanta q_cap *
  page96_i125
#ISCELL
  logical_power vcc_core *
  page96_i126
#CELL
  pure_quanta q_cap *
  page96_i127
#ISCELL
  logical_power universal_gnd *
  page96_i128
#ISCELL
  logical_power universal_gnd *
  page96_i129
#ISCELL
  standard offpage *
  page96_i13
#ISCELL
  standard tap *
  page96_i130
#ISCELL
  standard tap *
  page96_i131
#ISCELL
  standard tap *
  page96_i132
#ISCELL
  standard tap *
  page96_i133
#ISCELL
  standard tap *
  page96_i134
#ISCELL
  standard tap *
  page96_i135
#ISCELL
  standard tap *
  page96_i136
#ISCELL
  standard tap *
  page96_i137
#ISCELL
  standard tap *
  page96_i138
#ISCELL
  standard tap *
  page96_i139
#ISCELL
  standard offpage *
  page96_i14
#ISCELL
  standard tap *
  page96_i140
#ISCELL
  standard tap *
  page96_i141
#ISCELL
  standard tap *
  page96_i142
#ISCELL
  standard tap *
  page96_i143
#ISCELL
  standard tap *
  page96_i144
#ISCELL
  standard tap *
  page96_i145
#ISCELL
  standard tap *
  page96_i146
#ISCELL
  standard tap *
  page96_i147
#ISCELL
  standard tap *
  page96_i148
#ISCELL
  standard tap *
  page96_i149
#ISCELL
  standard offpage *
  page96_i15
#ISCELL
  standard tap *
  page96_i150
#ISCELL
  standard tap *
  page96_i151
#ISCELL
  standard tap *
  page96_i152
#ISCELL
  standard tap *
  page96_i153
#ISCELL
  standard tap *
  page96_i154
#ISCELL
  standard tap *
  page96_i155
#ISCELL
  standard tap *
  page96_i156
#ISCELL
  standard tap *
  page96_i157
#ISCELL
  standard tap *
  page96_i158
#ISCELL
  standard tap *
  page96_i159
#ISCELL
  standard offpage *
  page96_i16
#ISCELL
  standard tap *
  page96_i160
#ISCELL
  standard tap *
  page96_i161
#ISCELL
  standard tap *
  page96_i162
#ISCELL
  standard tap *
  page96_i163
#ISCELL
  standard offpage *
  page96_i164
#ISCELL
  standard offpage *
  page96_i165
#ISCELL
  standard offpage *
  page96_i166
#ISCELL
  standard tap *
  page96_i167
#ISCELL
  standard tap *
  page96_i168
#ISCELL
  standard tap *
  page96_i169
#ISCELL
  standard offpage *
  page96_i17
#ISCELL
  standard tap *
  page96_i170
#ISCELL
  standard tap *
  page96_i171
#ISCELL
  standard tap *
  page96_i172
#ISCELL
  standard offpage *
  page96_i173
#ISCELL
  standard offpage *
  page96_i174
#ISCELL
  logical_power vcc_core *
  page96_i175
#CELL
  pure_quanta sconn288_adr50017p130cc *
  page96_i176
#ISCELL
  logical_power universal_gnd *
  page96_i177
#CELL
  pure_quanta sconn288_adr50017p130cc *
  page96_i178
#CELL
  pure_quanta q_res *
  page96_i179
#ISCELL
  standard offpage *
  page96_i18
#ISCELL
  standard offpage *
  page96_i180
#ISCELL
  standard offpage *
  page96_i19
#ISCELL
  standard offpage *
  page96_i2
#ISCELL
  standard offpage *
  page96_i20
#ISCELL
  standard offpage *
  page96_i21
#ISCELL
  logical_power vcc_core *
  page96_i22
#ISCELL
  standard tap *
  page96_i23
#ISCELL
  standard tap *
  page96_i24
#ISCELL
  standard tap *
  page96_i25
#ISCELL
  standard tap *
  page96_i26
#ISCELL
  standard tap *
  page96_i27
#ISCELL
  standard tap *
  page96_i28
#ISCELL
  standard tap *
  page96_i29
#ISCELL
  standard offpage *
  page96_i3
#ISCELL
  standard tap *
  page96_i30
#ISCELL
  standard tap *
  page96_i31
#ISCELL
  standard tap *
  page96_i32
#ISCELL
  standard tap *
  page96_i33
#ISCELL
  standard tap *
  page96_i34
#ISCELL
  standard tap *
  page96_i35
#ISCELL
  standard tap *
  page96_i36
#ISCELL
  standard tap *
  page96_i37
#ISCELL
  standard tap *
  page96_i38
#ISCELL
  standard tap *
  page96_i39
#ISCELL
  standard offpage *
  page96_i4
#ISCELL
  standard tap *
  page96_i40
#ISCELL
  standard tap *
  page96_i41
#ISCELL
  standard tap *
  page96_i42
#ISCELL
  standard tap *
  page96_i43
#ISCELL
  standard tap *
  page96_i44
#ISCELL
  standard tap *
  page96_i45
#ISCELL
  standard tap *
  page96_i46
#CELL
  pure_quanta q_res *
  page96_i47
#CELL
  pure_quanta sconn288_adr50017p130cc *
  page96_i48
#ISCELL
  standard tap *
  page96_i49
#ISCELL
  standard offpage *
  page96_i5
#ISCELL
  standard tap *
  page96_i50
#ISCELL
  standard tap *
  page96_i51
#ISCELL
  standard tap *
  page96_i52
#ISCELL
  standard tap *
  page96_i53
#ISCELL
  standard tap *
  page96_i54
#ISCELL
  standard tap *
  page96_i55
#ISCELL
  standard tap *
  page96_i56
#ISCELL
  standard tap *
  page96_i57
#ISCELL
  standard tap *
  page96_i58
#ISCELL
  standard tap *
  page96_i59
#ISCELL
  standard tap *
  page96_i60
#ISCELL
  standard tap *
  page96_i61
#ISCELL
  standard tap *
  page96_i62
#ISCELL
  standard tap *
  page96_i63
#ISCELL
  standard tap *
  page96_i64
#ISCELL
  standard tap *
  page96_i65
#ISCELL
  standard tap *
  page96_i66
#ISCELL
  standard tap *
  page96_i67
#ISCELL
  standard tap *
  page96_i68
#ISCELL
  standard tap *
  page96_i69
#ISCELL
  standard offpage *
  page96_i7
#ISCELL
  standard tap *
  page96_i70
#ISCELL
  standard tap *
  page96_i71
#ISCELL
  standard tap *
  page96_i72
#ISCELL
  standard tap *
  page96_i73
#ISCELL
  standard tap *
  page96_i74
#ISCELL
  standard tap *
  page96_i75
#ISCELL
  standard tap *
  page96_i76
#ISCELL
  standard tap *
  page96_i77
#ISCELL
  standard tap *
  page96_i78
#ISCELL
  standard tap *
  page96_i79
#ISCELL
  standard offpage *
  page96_i8
#ISCELL
  standard tap *
  page96_i80
#ISCELL
  standard tap *
  page96_i81
#ISCELL
  standard tap *
  page96_i82
#ISCELL
  standard tap *
  page96_i83
#ISCELL
  standard tap *
  page96_i84
#ISCELL
  standard tap *
  page96_i85
#ISCELL
  standard tap *
  page96_i86
#ISCELL
  standard tap *
  page96_i87
#ISCELL
  standard tap *
  page96_i88
#ISCELL
  standard tap *
  page96_i89
#ISCELL
  standard offpage *
  page96_i9
#ISCELL
  standard tap *
  page96_i90
#ISCELL
  standard tap *
  page96_i91
#ISCELL
  standard tap *
  page96_i92
#ISCELL
  standard tap *
  page96_i93
#ISCELL
  standard tap *
  page96_i94
#ISCELL
  standard tap *
  page96_i95
#ISCELL
  standard tap *
  page96_i96
#ISCELL
  standard tap *
  page96_i97
#ISCELL
  standard tap *
  page96_i98
#ISCELL
  standard tap *
  page96_i99
#ISCELL
  logical_power cad_note *
  *
#ISCELL
  pure_quanta quanta_title_block_c *
  *
#ISCELL
  standard offpage *
  page97_i1
#ISCELL
  standard tap *
  page97_i100
#ISCELL
  standard tap *
  page97_i101
#ISCELL
  standard tap *
  page97_i102
#ISCELL
  standard tap *
  page97_i103
#ISCELL
  standard offpage *
  page97_i104
#ISCELL
  standard tap *
  page97_i105
#ISCELL
  standard tap *
  page97_i106
#ISCELL
  standard tap *
  page97_i107
#ISCELL
  standard tap *
  page97_i108
#ISCELL
  standard tap *
  page97_i109
#ISCELL
  standard offpage *
  page97_i11
#ISCELL
  standard tap *
  page97_i110
#ISCELL
  standard tap *
  page97_i111
#ISCELL
  standard tap *
  page97_i112
#ISCELL
  standard tap *
  page97_i113
#ISCELL
  standard tap *
  page97_i114
#ISCELL
  standard tap *
  page97_i115
#ISCELL
  standard tap *
  page97_i116
#ISCELL
  standard tap *
  page97_i117
#ISCELL
  standard tap *
  page97_i118
#ISCELL
  standard tap *
  page97_i119
#ISCELL
  standard offpage *
  page97_i12
#ISCELL
  standard tap *
  page97_i120
#ISCELL
  standard tap *
  page97_i121
#ISCELL
  standard tap *
  page97_i122
#ISCELL
  standard tap *
  page97_i123
#ISCELL
  standard tap *
  page97_i124
#ISCELL
  standard tap *
  page97_i125
#ISCELL
  standard tap *
  page97_i126
#ISCELL
  standard tap *
  page97_i127
#ISCELL
  standard tap *
  page97_i128
#ISCELL
  standard tap *
  page97_i129
#ISCELL
  standard offpage *
  page97_i13
#ISCELL
  standard tap *
  page97_i130
#ISCELL
  standard offpage *
  page97_i131
#ISCELL
  standard tap *
  page97_i133
#ISCELL
  standard tap *
  page97_i134
#ISCELL
  standard tap *
  page97_i135
#ISCELL
  standard tap *
  page97_i136
#ISCELL
  standard tap *
  page97_i137
#ISCELL
  standard tap *
  page97_i138
#ISCELL
  standard tap *
  page97_i139
#ISCELL
  standard offpage *
  page97_i14
#ISCELL
  standard tap *
  page97_i140
#ISCELL
  standard tap *
  page97_i141
#ISCELL
  standard tap *
  page97_i142
#ISCELL
  standard tap *
  page97_i143
#ISCELL
  standard tap *
  page97_i144
#ISCELL
  standard tap *
  page97_i145
#ISCELL
  standard tap *
  page97_i146
#ISCELL
  standard tap *
  page97_i147
#ISCELL
  standard tap *
  page97_i148
#ISCELL
  standard tap *
  page97_i149
#ISCELL
  standard offpage *
  page97_i15
#ISCELL
  standard tap *
  page97_i150
#ISCELL
  standard tap *
  page97_i151
#ISCELL
  standard tap *
  page97_i152
#ISCELL
  standard tap *
  page97_i153
#ISCELL
  standard tap *
  page97_i154
#ISCELL
  standard tap *
  page97_i155
#ISCELL
  standard tap *
  page97_i156
#ISCELL
  standard tap *
  page97_i157
#ISCELL
  standard tap *
  page97_i158
#ISCELL
  standard tap *
  page97_i159
#ISCELL
  standard offpage *
  page97_i16
#ISCELL
  standard tap *
  page97_i160
#ISCELL
  standard tap *
  page97_i161
#ISCELL
  standard tap *
  page97_i162
#ISCELL
  standard tap *
  page97_i163
#ISCELL
  standard tap *
  page97_i164
#ISCELL
  standard tap *
  page97_i165
#ISCELL
  standard tap *
  page97_i166
#ISCELL
  standard tap *
  page97_i167
#ISCELL
  standard tap *
  page97_i168
#ISCELL
  standard tap *
  page97_i169
#ISCELL
  standard offpage *
  page97_i17
#ISCELL
  standard tap *
  page97_i170
#ISCELL
  standard tap *
  page97_i171
#ISCELL
  standard tap *
  page97_i172
#ISCELL
  standard offpage *
  page97_i173
#ISCELL
  standard offpage *
  page97_i174
#ISCELL
  standard offpage *
  page97_i175
#ISCELL
  standard offpage *
  page97_i176
#ISCELL
  logical_power vcc_core *
  page97_i177
#CELL
  pure_quanta sconn288_adr50017p087cc *
  page97_i178
#CELL
  pure_quanta q_res *
  page97_i179
#ISCELL
  standard offpage *
  page97_i18
#ISCELL
  standard offpage *
  page97_i180
#ISCELL
  standard offpage *
  page97_i19
#ISCELL
  standard offpage *
  page97_i2
#ISCELL
  standard offpage *
  page97_i20
#ISCELL
  standard offpage *
  page97_i21
#ISCELL
  standard offpage *
  page97_i22
#ISCELL
  standard offpage *
  page97_i23
#ISCELL
  standard offpage *
  page97_i24
#ISCELL
  logical_power vcc_core *
  page97_i25
#ISCELL
  standard tap *
  page97_i26
#ISCELL
  standard tap *
  page97_i27
#ISCELL
  standard tap *
  page97_i28
#ISCELL
  standard tap *
  page97_i29
#ISCELL
  standard offpage *
  page97_i3
#ISCELL
  standard tap *
  page97_i30
#ISCELL
  standard tap *
  page97_i31
#ISCELL
  standard tap *
  page97_i32
#ISCELL
  standard tap *
  page97_i33
#ISCELL
  standard tap *
  page97_i34
#ISCELL
  standard tap *
  page97_i35
#ISCELL
  standard tap *
  page97_i36
#ISCELL
  standard tap *
  page97_i37
#ISCELL
  standard tap *
  page97_i38
#ISCELL
  standard tap *
  page97_i39
#ISCELL
  logical_power universal_gnd *
  page97_i4
#ISCELL
  standard tap *
  page97_i40
#ISCELL
  standard tap *
  page97_i41
#ISCELL
  standard tap *
  page97_i42
#ISCELL
  standard tap *
  page97_i43
#ISCELL
  standard tap *
  page97_i44
#ISCELL
  standard tap *
  page97_i45
#ISCELL
  standard tap *
  page97_i46
#ISCELL
  standard tap *
  page97_i47
#ISCELL
  standard tap *
  page97_i48
#ISCELL
  standard tap *
  page97_i49
#CELL
  pure_quanta q_res *
  page97_i5
#ISCELL
  standard tap *
  page97_i50
#ISCELL
  standard tap *
  page97_i51
#ISCELL
  standard tap *
  page97_i52
#ISCELL
  standard tap *
  page97_i53
#ISCELL
  standard tap *
  page97_i54
#ISCELL
  standard tap *
  page97_i55
#CELL
  pure_quanta q_cap *
  page97_i56
#ISCELL
  logical_power universal_gnd *
  page97_i57
#ISCELL
  logical_power vcc_core *
  page97_i58
#CELL
  pure_quanta q_cap *
  page97_i59
#CELL
  pure_quanta sconn288_adr50017p087cc *
  page97_i6
#ISCELL
  logical_power vcc_core *
  page97_i60
#ISCELL
  logical_power universal_gnd *
  page97_i61
#CELL
  pure_quanta q_cap *
  page97_i62
#ISCELL
  logical_power universal_gnd *
  page97_i63
#CELL
  pure_quanta sconn288_adr50017p087cc *
  page97_i64
#ISCELL
  logical_power universal_gnd *
  page97_i65
#ISCELL
  standard tap *
  page97_i66
#ISCELL
  standard tap *
  page97_i67
#ISCELL
  standard tap *
  page97_i68
#ISCELL
  standard tap *
  page97_i69
#ISCELL
  standard offpage *
  page97_i7
#ISCELL
  standard tap *
  page97_i70
#ISCELL
  standard tap *
  page97_i71
#ISCELL
  standard tap *
  page97_i72
#ISCELL
  standard tap *
  page97_i73
#ISCELL
  standard tap *
  page97_i74
#ISCELL
  standard tap *
  page97_i75
#ISCELL
  standard tap *
  page97_i76
#ISCELL
  standard tap *
  page97_i77
#ISCELL
  standard tap *
  page97_i78
#ISCELL
  standard tap *
  page97_i79
#ISCELL
  standard offpage *
  page97_i8
#ISCELL
  standard tap *
  page97_i80
#ISCELL
  standard tap *
  page97_i81
#ISCELL
  standard tap *
  page97_i82
#ISCELL
  standard tap *
  page97_i83
#ISCELL
  standard tap *
  page97_i84
#ISCELL
  standard tap *
  page97_i85
#ISCELL
  standard tap *
  page97_i86
#ISCELL
  standard tap *
  page97_i87
#ISCELL
  standard tap *
  page97_i88
#ISCELL
  standard tap *
  page97_i89
#ISCELL
  standard offpage *
  page97_i9
#ISCELL
  standard tap *
  page97_i90
#ISCELL
  standard tap *
  page97_i91
#ISCELL
  standard tap *
  page97_i92
#ISCELL
  standard tap *
  page97_i93
#ISCELL
  standard tap *
  page97_i94
#ISCELL
  standard tap *
  page97_i95
#ISCELL
  standard tap *
  page97_i96
#ISCELL
  standard tap *
  page97_i97
#ISCELL
  standard tap *
  page97_i98
#ISCELL
  standard tap *
  page97_i99
#ISCELL
  logical_power cad_note *
  *
#ISCELL
  pure_quanta quanta_title_block_c *
  *
#ISCELL
  logical_power universal_gnd *
  page98_i1
#ISCELL
  standard offpage *
  page98_i10
#ISCELL
  standard tap *
  page98_i100
#ISCELL
  standard tap *
  page98_i101
#ISCELL
  standard tap *
  page98_i102
#ISCELL
  standard tap *
  page98_i103
#ISCELL
  standard tap *
  page98_i104
#ISCELL
  standard tap *
  page98_i105
#ISCELL
  standard tap *
  page98_i106
#ISCELL
  standard tap *
  page98_i107
#ISCELL
  standard tap *
  page98_i108
#ISCELL
  standard offpage *
  page98_i109
#CELL
  pure_quanta q_res *
  page98_i11
#ISCELL
  standard tap *
  page98_i110
#ISCELL
  standard tap *
  page98_i111
#ISCELL
  standard tap *
  page98_i112
#ISCELL
  standard tap *
  page98_i113
#ISCELL
  standard tap *
  page98_i114
#ISCELL
  standard tap *
  page98_i115
#ISCELL
  standard tap *
  page98_i116
#ISCELL
  standard tap *
  page98_i117
#ISCELL
  standard tap *
  page98_i118
#ISCELL
  standard tap *
  page98_i119
#CELL
  pure_quanta sconn288_adr50017p130cc *
  page98_i12
#ISCELL
  logical_power vcc_core *
  page98_i120
#ISCELL
  logical_power universal_gnd *
  page98_i121
#CELL
  pure_quanta q_cap *
  page98_i122
#CELL
  pure_quanta q_cap *
  page98_i123
#ISCELL
  logical_power vcc_core *
  page98_i124
#ISCELL
  standard offpage *
  page98_i125
#ISCELL
  standard tap *
  page98_i127
#ISCELL
  standard tap *
  page98_i128
#ISCELL
  standard tap *
  page98_i129
#ISCELL
  standard offpage *
  page98_i13
#ISCELL
  standard tap *
  page98_i130
#ISCELL
  standard tap *
  page98_i131
#ISCELL
  standard tap *
  page98_i132
#ISCELL
  standard tap *
  page98_i133
#ISCELL
  standard tap *
  page98_i134
#ISCELL
  standard tap *
  page98_i135
#ISCELL
  standard tap *
  page98_i136
#ISCELL
  standard tap *
  page98_i137
#ISCELL
  standard tap *
  page98_i138
#ISCELL
  standard tap *
  page98_i139
#ISCELL
  logical_power vcc_core *
  page98_i14
#ISCELL
  standard tap *
  page98_i140
#ISCELL
  standard tap *
  page98_i141
#ISCELL
  standard tap *
  page98_i142
#ISCELL
  standard tap *
  page98_i143
#ISCELL
  logical_power universal_gnd *
  page98_i144
#CELL
  pure_quanta q_cap *
  page98_i145
#ISCELL
  logical_power universal_gnd *
  page98_i146
#CELL
  pure_quanta sconn288_adr50017p130cc *
  page98_i147
#ISCELL
  standard tap *
  page98_i148
#ISCELL
  standard tap *
  page98_i149
#ISCELL
  standard offpage *
  page98_i15
#ISCELL
  standard tap *
  page98_i150
#ISCELL
  standard tap *
  page98_i151
#ISCELL
  standard tap *
  page98_i152
#ISCELL
  standard tap *
  page98_i153
#ISCELL
  standard tap *
  page98_i154
#ISCELL
  standard tap *
  page98_i155
#ISCELL
  standard tap *
  page98_i156
#ISCELL
  standard tap *
  page98_i157
#ISCELL
  standard tap *
  page98_i158
#ISCELL
  standard tap *
  page98_i159
#ISCELL
  standard offpage *
  page98_i16
#ISCELL
  standard tap *
  page98_i160
#ISCELL
  standard tap *
  page98_i161
#ISCELL
  standard tap *
  page98_i162
#ISCELL
  standard tap *
  page98_i163
#ISCELL
  standard tap *
  page98_i164
#ISCELL
  standard tap *
  page98_i165
#ISCELL
  standard offpage *
  page98_i166
#ISCELL
  standard offpage *
  page98_i167
#ISCELL
  standard offpage *
  page98_i168
#ISCELL
  standard tap *
  page98_i169
#ISCELL
  standard offpage *
  page98_i17
#ISCELL
  standard tap *
  page98_i170
#ISCELL
  standard tap *
  page98_i171
#ISCELL
  standard tap *
  page98_i172
#ISCELL
  standard tap *
  page98_i173
#ISCELL
  standard offpage *
  page98_i174
#ISCELL
  standard offpage *
  page98_i175
#ISCELL
  logical_power vcc_core *
  page98_i176
#ISCELL
  logical_power universal_gnd *
  page98_i177
#CELL
  pure_quanta sconn288_adr50017p130cc *
  page98_i178
#CELL
  pure_quanta q_res *
  page98_i179
#ISCELL
  standard offpage *
  page98_i18
#ISCELL
  standard offpage *
  page98_i180
#ISCELL
  standard offpage *
  page98_i19
#ISCELL
  standard offpage *
  page98_i2
#ISCELL
  standard offpage *
  page98_i20
#ISCELL
  standard offpage *
  page98_i21
#ISCELL
  standard offpage *
  page98_i22
#ISCELL
  standard offpage *
  page98_i23
#ISCELL
  standard offpage *
  page98_i24
#ISCELL
  standard tap *
  page98_i25
#ISCELL
  standard tap *
  page98_i26
#ISCELL
  standard tap *
  page98_i27
#ISCELL
  standard tap *
  page98_i28
#ISCELL
  standard tap *
  page98_i29
#ISCELL
  standard offpage *
  page98_i3
#ISCELL
  standard tap *
  page98_i30
#ISCELL
  standard tap *
  page98_i31
#ISCELL
  standard tap *
  page98_i32
#ISCELL
  standard tap *
  page98_i33
#ISCELL
  standard tap *
  page98_i34
#ISCELL
  standard tap *
  page98_i35
#ISCELL
  standard tap *
  page98_i36
#ISCELL
  standard tap *
  page98_i37
#ISCELL
  standard tap *
  page98_i38
#ISCELL
  standard tap *
  page98_i39
#ISCELL
  standard offpage *
  page98_i4
#ISCELL
  standard tap *
  page98_i40
#ISCELL
  standard tap *
  page98_i41
#ISCELL
  standard tap *
  page98_i42
#ISCELL
  standard tap *
  page98_i43
#ISCELL
  standard tap *
  page98_i44
#ISCELL
  standard tap *
  page98_i45
#ISCELL
  standard tap *
  page98_i46
#ISCELL
  standard tap *
  page98_i47
#ISCELL
  standard tap *
  page98_i48
#ISCELL
  standard tap *
  page98_i49
#ISCELL
  standard offpage *
  page98_i5
#ISCELL
  standard tap *
  page98_i50
#ISCELL
  standard tap *
  page98_i51
#ISCELL
  standard tap *
  page98_i52
#ISCELL
  standard tap *
  page98_i53
#ISCELL
  standard tap *
  page98_i54
#ISCELL
  standard tap *
  page98_i55
#ISCELL
  standard tap *
  page98_i56
#ISCELL
  standard tap *
  page98_i57
#ISCELL
  standard tap *
  page98_i58
#ISCELL
  standard tap *
  page98_i59
#ISCELL
  standard tap *
  page98_i60
#ISCELL
  standard tap *
  page98_i61
#ISCELL
  standard tap *
  page98_i62
#ISCELL
  standard tap *
  page98_i63
#ISCELL
  standard tap *
  page98_i64
#ISCELL
  standard tap *
  page98_i65
#ISCELL
  standard tap *
  page98_i66
#ISCELL
  standard tap *
  page98_i67
#ISCELL
  standard tap *
  page98_i68
#ISCELL
  standard tap *
  page98_i69
#ISCELL
  standard offpage *
  page98_i7
#ISCELL
  standard tap *
  page98_i70
#ISCELL
  standard tap *
  page98_i71
#ISCELL
  standard tap *
  page98_i72
#ISCELL
  standard tap *
  page98_i73
#ISCELL
  standard tap *
  page98_i74
#ISCELL
  standard tap *
  page98_i75
#ISCELL
  standard tap *
  page98_i76
#ISCELL
  standard tap *
  page98_i77
#ISCELL
  standard tap *
  page98_i78
#ISCELL
  standard tap *
  page98_i79
#ISCELL
  standard offpage *
  page98_i8
#ISCELL
  standard tap *
  page98_i80
#ISCELL
  standard tap *
  page98_i81
#ISCELL
  standard tap *
  page98_i82
#ISCELL
  standard tap *
  page98_i83
#ISCELL
  standard tap *
  page98_i84
#ISCELL
  standard tap *
  page98_i85
#ISCELL
  standard tap *
  page98_i86
#ISCELL
  standard tap *
  page98_i87
#ISCELL
  standard tap *
  page98_i88
#ISCELL
  standard tap *
  page98_i89
#ISCELL
  standard offpage *
  page98_i9
#ISCELL
  standard tap *
  page98_i90
#ISCELL
  standard tap *
  page98_i91
#ISCELL
  standard tap *
  page98_i92
#ISCELL
  standard tap *
  page98_i93
#ISCELL
  standard tap *
  page98_i94
#ISCELL
  standard tap *
  page98_i95
#ISCELL
  standard tap *
  page98_i96
#ISCELL
  standard tap *
  page98_i97
#ISCELL
  standard tap *
  page98_i98
#ISCELL
  standard tap *
  page98_i99
#ISCELL
  logical_power cad_note *
  *
#ISCELL
  pure_quanta quanta_title_block_c *
  *
#ISCELL
  logical_power universal_gnd *
  page99_i1
#ISCELL
  standard offpage *
  page99_i10
#ISCELL
  standard tap *
  page99_i100
#ISCELL
  standard tap *
  page99_i101
#ISCELL
  standard tap *
  page99_i102
#ISCELL
  standard tap *
  page99_i103
#ISCELL
  standard tap *
  page99_i104
#ISCELL
  standard tap *
  page99_i105
#ISCELL
  standard tap *
  page99_i106
#ISCELL
  standard tap *
  page99_i107
#ISCELL
  standard tap *
  page99_i108
#ISCELL
  standard tap *
  page99_i109
#ISCELL
  standard offpage *
  page99_i11
#ISCELL
  standard tap *
  page99_i110
#ISCELL
  standard tap *
  page99_i111
#ISCELL
  standard tap *
  page99_i112
#ISCELL
  standard offpage *
  page99_i113
#ISCELL
  standard tap *
  page99_i114
#ISCELL
  standard tap *
  page99_i115
#ISCELL
  standard tap *
  page99_i116
#ISCELL
  standard tap *
  page99_i117
#ISCELL
  standard tap *
  page99_i118
#ISCELL
  standard tap *
  page99_i119
#ISCELL
  logical_power vcc_core *
  page99_i12
#ISCELL
  logical_power universal_gnd *
  page99_i120
#ISCELL
  logical_power universal_gnd *
  page99_i121
#CELL
  pure_quanta q_cap *
  page99_i122
#ISCELL
  logical_power vcc_core *
  page99_i123
#ISCELL
  standard offpage *
  page99_i124
#CELL
  pure_quanta q_cap *
  page99_i126
#ISCELL
  logical_power vcc_core *
  page99_i127
#CELL
  pure_quanta q_cap *
  page99_i128
#ISCELL
  standard tap *
  page99_i129
#ISCELL
  standard offpage *
  page99_i13
#ISCELL
  standard tap *
  page99_i130
#ISCELL
  standard tap *
  page99_i131
#ISCELL
  standard tap *
  page99_i132
#ISCELL
  standard tap *
  page99_i133
#ISCELL
  standard tap *
  page99_i134
#ISCELL
  standard tap *
  page99_i135
#ISCELL
  standard tap *
  page99_i136
#ISCELL
  standard tap *
  page99_i137
#ISCELL
  standard tap *
  page99_i138
#ISCELL
  standard tap *
  page99_i139
#ISCELL
  standard offpage *
  page99_i14
#ISCELL
  standard tap *
  page99_i140
#ISCELL
  standard tap *
  page99_i141
#ISCELL
  standard tap *
  page99_i142
#ISCELL
  standard tap *
  page99_i143
#ISCELL
  standard tap *
  page99_i144
#ISCELL
  standard tap *
  page99_i145
#ISCELL
  standard tap *
  page99_i146
#ISCELL
  standard tap *
  page99_i147
#ISCELL
  standard tap *
  page99_i148
#ISCELL
  standard tap *
  page99_i149
#ISCELL
  standard offpage *
  page99_i15
#ISCELL
  standard tap *
  page99_i150
#ISCELL
  standard tap *
  page99_i151
#ISCELL
  standard tap *
  page99_i152
#ISCELL
  standard tap *
  page99_i153
#ISCELL
  standard tap *
  page99_i154
#ISCELL
  standard tap *
  page99_i155
#ISCELL
  standard tap *
  page99_i156
#ISCELL
  standard tap *
  page99_i157
#ISCELL
  standard tap *
  page99_i158
#ISCELL
  standard tap *
  page99_i159
#ISCELL
  standard offpage *
  page99_i16
#ISCELL
  standard tap *
  page99_i160
#ISCELL
  standard tap *
  page99_i161
#ISCELL
  standard tap *
  page99_i162
#ISCELL
  standard tap *
  page99_i163
#ISCELL
  standard tap *
  page99_i164
#ISCELL
  standard tap *
  page99_i165
#ISCELL
  standard offpage *
  page99_i166
#ISCELL
  standard offpage *
  page99_i167
#ISCELL
  standard offpage *
  page99_i168
#ISCELL
  standard tap *
  page99_i169
#ISCELL
  standard offpage *
  page99_i17
#ISCELL
  standard tap *
  page99_i170
#ISCELL
  standard tap *
  page99_i171
#ISCELL
  standard offpage *
  page99_i172
#ISCELL
  standard offpage *
  page99_i173
#ISCELL
  logical_power universal_gnd *
  page99_i174
#CELL
  pure_quanta sconn288_adr50017p087cc *
  page99_i175
#ISCELL
  logical_power universal_gnd *
  page99_i176
#ISCELL
  logical_power vcc_core *
  page99_i177
#CELL
  pure_quanta sconn288_adr50017p087cc *
  page99_i178
#ISCELL
  standard offpage *
  page99_i179
#ISCELL
  standard offpage *
  page99_i18
#CELL
  pure_quanta q_res *
  page99_i180
#ISCELL
  standard offpage *
  page99_i19
#CELL
  pure_quanta q_res *
  page99_i2
#ISCELL
  standard offpage *
  page99_i20
#ISCELL
  standard offpage *
  page99_i21
#ISCELL
  standard offpage *
  page99_i22
#ISCELL
  standard offpage *
  page99_i23
#CELL
  pure_quanta sconn288_adr50017p087cc *
  page99_i24
#ISCELL
  standard tap *
  page99_i25
#ISCELL
  standard tap *
  page99_i26
#ISCELL
  standard tap *
  page99_i27
#ISCELL
  standard tap *
  page99_i28
#ISCELL
  standard tap *
  page99_i29
#ISCELL
  standard offpage *
  page99_i3
#ISCELL
  standard tap *
  page99_i30
#ISCELL
  standard tap *
  page99_i31
#ISCELL
  standard tap *
  page99_i32
#ISCELL
  standard tap *
  page99_i33
#ISCELL
  standard tap *
  page99_i34
#ISCELL
  standard tap *
  page99_i35
#ISCELL
  standard tap *
  page99_i36
#ISCELL
  standard tap *
  page99_i37
#ISCELL
  standard tap *
  page99_i38
#ISCELL
  standard tap *
  page99_i39
#ISCELL
  standard offpage *
  page99_i4
#ISCELL
  standard tap *
  page99_i40
#ISCELL
  standard tap *
  page99_i41
#ISCELL
  standard tap *
  page99_i42
#ISCELL
  standard tap *
  page99_i43
#ISCELL
  standard tap *
  page99_i44
#ISCELL
  standard tap *
  page99_i45
#ISCELL
  standard tap *
  page99_i46
#ISCELL
  standard tap *
  page99_i47
#ISCELL
  standard tap *
  page99_i48
#ISCELL
  standard tap *
  page99_i49
#ISCELL
  standard offpage *
  page99_i5
#ISCELL
  standard tap *
  page99_i50
#ISCELL
  standard tap *
  page99_i51
#ISCELL
  standard tap *
  page99_i52
#ISCELL
  standard tap *
  page99_i53
#ISCELL
  standard tap *
  page99_i54
#ISCELL
  standard tap *
  page99_i55
#ISCELL
  standard tap *
  page99_i56
#ISCELL
  standard tap *
  page99_i57
#ISCELL
  standard tap *
  page99_i58
#ISCELL
  standard tap *
  page99_i59
#ISCELL
  standard offpage *
  page99_i6
#ISCELL
  standard tap *
  page99_i60
#ISCELL
  standard tap *
  page99_i61
#ISCELL
  standard tap *
  page99_i62
#ISCELL
  standard tap *
  page99_i63
#ISCELL
  standard tap *
  page99_i64
#ISCELL
  standard tap *
  page99_i65
#ISCELL
  standard tap *
  page99_i66
#ISCELL
  standard tap *
  page99_i67
#ISCELL
  standard tap *
  page99_i68
#ISCELL
  standard tap *
  page99_i69
#ISCELL
  standard offpage *
  page99_i7
#ISCELL
  standard tap *
  page99_i70
#ISCELL
  standard tap *
  page99_i71
#ISCELL
  standard tap *
  page99_i72
#ISCELL
  standard tap *
  page99_i73
#ISCELL
  standard tap *
  page99_i74
#ISCELL
  standard tap *
  page99_i75
#ISCELL
  standard tap *
  page99_i76
#ISCELL
  standard tap *
  page99_i77
#ISCELL
  standard tap *
  page99_i78
#ISCELL
  standard tap *
  page99_i79
#ISCELL
  standard offpage *
  page99_i8
#ISCELL
  standard tap *
  page99_i80
#ISCELL
  standard tap *
  page99_i81
#ISCELL
  standard tap *
  page99_i82
#ISCELL
  standard tap *
  page99_i83
#ISCELL
  standard tap *
  page99_i84
#ISCELL
  standard tap *
  page99_i85
#ISCELL
  standard tap *
  page99_i86
#ISCELL
  standard tap *
  page99_i87
#ISCELL
  standard tap *
  page99_i88
#ISCELL
  standard tap *
  page99_i89
#ISCELL
  standard tap *
  page99_i90
#ISCELL
  standard tap *
  page99_i91
#ISCELL
  standard tap *
  page99_i92
#ISCELL
  standard tap *
  page99_i93
#ISCELL
  standard tap *
  page99_i94
#ISCELL
  standard tap *
  page99_i95
#ISCELL
  standard tap *
  page99_i96
#ISCELL
  standard tap *
  page99_i97
#ISCELL
  standard tap *
  page99_i98
#ISCELL
  standard tap *
  page99_i99
#ISCELL
  logical_power cad_note *
  *
#ISCELL
  pure_quanta quanta_title_block_c *
  *
#ISCELL
  standard offpage *
  page100_i1
#ISCELL
  standard offpage *
  page100_i10
#ISCELL
  standard tap *
  page100_i100
#ISCELL
  standard tap *
  page100_i101
#ISCELL
  standard tap *
  page100_i102
#ISCELL
  standard tap *
  page100_i103
#ISCELL
  standard tap *
  page100_i104
#ISCELL
  standard tap *
  page100_i105
#ISCELL
  standard tap *
  page100_i106
#ISCELL
  standard tap *
  page100_i107
#ISCELL
  standard tap *
  page100_i108
#ISCELL
  standard tap *
  page100_i109
#ISCELL
  standard offpage *
  page100_i11
#ISCELL
  standard tap *
  page100_i110
#ISCELL
  standard tap *
  page100_i111
#ISCELL
  standard tap *
  page100_i112
#ISCELL
  standard tap *
  page100_i113
#ISCELL
  standard tap *
  page100_i114
#ISCELL
  standard tap *
  page100_i115
#ISCELL
  standard tap *
  page100_i116
#ISCELL
  standard tap *
  page100_i117
#ISCELL
  standard tap *
  page100_i118
#ISCELL
  standard tap *
  page100_i119
#ISCELL
  standard offpage *
  page100_i12
#ISCELL
  logical_power universal_gnd *
  page100_i120
#CELL
  pure_quanta q_cap *
  page100_i121
#CELL
  pure_quanta q_cap *
  page100_i122
#ISCELL
  logical_power universal_gnd *
  page100_i123
#CELL
  pure_quanta q_cap *
  page100_i124
#ISCELL
  logical_power vcc_core *
  page100_i125
#ISCELL
  standard offpage *
  page100_i127
#ISCELL
  standard offpage *
  page100_i128
#ISCELL
  logical_power vcc_core *
  page100_i129
#ISCELL
  logical_power vcc_core *
  page100_i13
#ISCELL
  standard tap *
  page100_i130
#ISCELL
  standard tap *
  page100_i131
#ISCELL
  standard tap *
  page100_i132
#ISCELL
  standard tap *
  page100_i133
#ISCELL
  standard tap *
  page100_i134
#ISCELL
  standard tap *
  page100_i135
#ISCELL
  standard tap *
  page100_i136
#ISCELL
  standard tap *
  page100_i137
#ISCELL
  standard tap *
  page100_i138
#ISCELL
  standard tap *
  page100_i139
#ISCELL
  standard offpage *
  page100_i14
#ISCELL
  standard tap *
  page100_i140
#ISCELL
  standard tap *
  page100_i141
#ISCELL
  standard tap *
  page100_i142
#ISCELL
  standard tap *
  page100_i143
#ISCELL
  standard tap *
  page100_i144
#ISCELL
  standard tap *
  page100_i145
#ISCELL
  standard tap *
  page100_i146
#ISCELL
  standard tap *
  page100_i147
#ISCELL
  standard tap *
  page100_i148
#ISCELL
  standard tap *
  page100_i149
#ISCELL
  standard offpage *
  page100_i15
#ISCELL
  standard tap *
  page100_i150
#ISCELL
  standard tap *
  page100_i151
#ISCELL
  standard tap *
  page100_i152
#ISCELL
  standard tap *
  page100_i153
#ISCELL
  standard tap *
  page100_i154
#ISCELL
  standard tap *
  page100_i155
#ISCELL
  standard tap *
  page100_i156
#ISCELL
  standard tap *
  page100_i157
#ISCELL
  standard tap *
  page100_i158
#ISCELL
  standard tap *
  page100_i159
#ISCELL
  standard offpage *
  page100_i16
#ISCELL
  standard tap *
  page100_i160
#ISCELL
  standard tap *
  page100_i161
#ISCELL
  standard tap *
  page100_i162
#ISCELL
  standard tap *
  page100_i163
#ISCELL
  standard tap *
  page100_i164
#ISCELL
  standard tap *
  page100_i165
#ISCELL
  standard tap *
  page100_i166
#ISCELL
  standard tap *
  page100_i167
#ISCELL
  standard tap *
  page100_i168
#ISCELL
  standard tap *
  page100_i169
#ISCELL
  standard offpage *
  page100_i17
#ISCELL
  standard offpage *
  page100_i170
#ISCELL
  standard offpage *
  page100_i171
#ISCELL
  standard offpage *
  page100_i172
#ISCELL
  standard offpage *
  page100_i173
#ISCELL
  logical_power universal_gnd *
  page100_i174
#CELL
  pure_quanta sconn288_adr50017p130cc *
  page100_i175
#ISCELL
  logical_power universal_gnd *
  page100_i176
#ISCELL
  logical_power vcc_core *
  page100_i177
#CELL
  pure_quanta sconn288_adr50017p130cc *
  page100_i178
#ISCELL
  standard offpage *
  page100_i179
#ISCELL
  standard offpage *
  page100_i18
#CELL
  pure_quanta q_res *
  page100_i180
#ISCELL
  standard offpage *
  page100_i19
#ISCELL
  logical_power universal_gnd *
  page100_i2
#ISCELL
  standard offpage *
  page100_i20
#ISCELL
  standard offpage *
  page100_i21
#ISCELL
  standard offpage *
  page100_i22
#ISCELL
  standard offpage *
  page100_i23
#ISCELL
  standard offpage *
  page100_i24
#CELL
  pure_quanta sconn288_adr50017p130cc *
  page100_i25
#ISCELL
  standard tap *
  page100_i26
#ISCELL
  standard tap *
  page100_i27
#ISCELL
  standard tap *
  page100_i28
#ISCELL
  standard tap *
  page100_i29
#CELL
  pure_quanta q_res *
  page100_i3
#ISCELL
  standard tap *
  page100_i30
#ISCELL
  standard tap *
  page100_i31
#ISCELL
  standard tap *
  page100_i32
#ISCELL
  standard tap *
  page100_i33
#ISCELL
  standard tap *
  page100_i34
#ISCELL
  standard tap *
  page100_i35
#ISCELL
  standard tap *
  page100_i36
#ISCELL
  standard tap *
  page100_i37
#ISCELL
  standard tap *
  page100_i38
#ISCELL
  standard tap *
  page100_i39
#ISCELL
  standard offpage *
  page100_i4
#ISCELL
  standard tap *
  page100_i40
#ISCELL
  standard tap *
  page100_i41
#ISCELL
  standard tap *
  page100_i42
#ISCELL
  standard tap *
  page100_i43
#ISCELL
  standard tap *
  page100_i44
#ISCELL
  standard tap *
  page100_i45
#ISCELL
  standard tap *
  page100_i46
#ISCELL
  standard tap *
  page100_i47
#ISCELL
  standard tap *
  page100_i48
#ISCELL
  standard tap *
  page100_i49
#ISCELL
  standard offpage *
  page100_i5
#ISCELL
  standard tap *
  page100_i50
#ISCELL
  standard tap *
  page100_i51
#ISCELL
  standard tap *
  page100_i52
#ISCELL
  standard tap *
  page100_i53
#ISCELL
  standard tap *
  page100_i54
#ISCELL
  standard tap *
  page100_i55
#ISCELL
  standard tap *
  page100_i56
#ISCELL
  standard tap *
  page100_i57
#ISCELL
  standard tap *
  page100_i58
#ISCELL
  standard tap *
  page100_i59
#ISCELL
  standard offpage *
  page100_i6
#ISCELL
  standard tap *
  page100_i60
#ISCELL
  standard tap *
  page100_i61
#ISCELL
  standard tap *
  page100_i62
#ISCELL
  standard tap *
  page100_i63
#ISCELL
  standard tap *
  page100_i64
#ISCELL
  standard tap *
  page100_i65
#ISCELL
  standard tap *
  page100_i66
#ISCELL
  standard tap *
  page100_i67
#ISCELL
  standard tap *
  page100_i68
#ISCELL
  standard tap *
  page100_i69
#ISCELL
  standard tap *
  page100_i70
#ISCELL
  standard tap *
  page100_i71
#ISCELL
  standard tap *
  page100_i72
#ISCELL
  standard tap *
  page100_i73
#ISCELL
  standard tap *
  page100_i74
#ISCELL
  standard tap *
  page100_i75
#ISCELL
  standard tap *
  page100_i76
#ISCELL
  standard tap *
  page100_i77
#ISCELL
  standard tap *
  page100_i78
#ISCELL
  standard tap *
  page100_i79
#ISCELL
  standard offpage *
  page100_i8
#ISCELL
  standard tap *
  page100_i80
#ISCELL
  standard tap *
  page100_i81
#ISCELL
  standard tap *
  page100_i82
#ISCELL
  standard tap *
  page100_i83
#ISCELL
  standard tap *
  page100_i84
#ISCELL
  standard tap *
  page100_i85
#ISCELL
  standard tap *
  page100_i86
#ISCELL
  standard tap *
  page100_i87
#ISCELL
  standard tap *
  page100_i88
#ISCELL
  standard tap *
  page100_i89
#ISCELL
  standard offpage *
  page100_i9
#ISCELL
  standard tap *
  page100_i90
#ISCELL
  standard tap *
  page100_i91
#ISCELL
  standard tap *
  page100_i92
#ISCELL
  standard tap *
  page100_i93
#ISCELL
  standard tap *
  page100_i94
#ISCELL
  standard tap *
  page100_i95
#ISCELL
  standard tap *
  page100_i96
#ISCELL
  standard tap *
  page100_i97
#ISCELL
  standard tap *
  page100_i98
#ISCELL
  standard tap *
  page100_i99
#ISCELL
  logical_power cad_note *
  *
#ISCELL
  pure_quanta quanta_title_block_c *
  *
#ISCELL
  standard offpage *
  page101_i1
#ISCELL
  standard offpage *
  page101_i10
#ISCELL
  standard tap *
  page101_i100
#ISCELL
  standard tap *
  page101_i101
#ISCELL
  standard tap *
  page101_i102
#ISCELL
  standard tap *
  page101_i103
#ISCELL
  standard tap *
  page101_i104
#ISCELL
  standard offpage *
  page101_i105
#ISCELL
  standard tap *
  page101_i106
#ISCELL
  standard tap *
  page101_i107
#ISCELL
  standard tap *
  page101_i108
#ISCELL
  standard tap *
  page101_i109
#ISCELL
  standard offpage *
  page101_i11
#ISCELL
  standard tap *
  page101_i110
#ISCELL
  standard tap *
  page101_i111
#ISCELL
  standard tap *
  page101_i112
#ISCELL
  standard tap *
  page101_i113
#ISCELL
  standard tap *
  page101_i114
#ISCELL
  standard tap *
  page101_i115
#ISCELL
  standard tap *
  page101_i116
#ISCELL
  standard tap *
  page101_i117
#ISCELL
  standard tap *
  page101_i118
#ISCELL
  standard tap *
  page101_i119
#ISCELL
  standard offpage *
  page101_i12
#ISCELL
  logical_power universal_gnd *
  page101_i120
#CELL
  pure_quanta q_cap *
  page101_i121
#ISCELL
  logical_power vcc_core *
  page101_i122
#ISCELL
  standard offpage *
  page101_i123
#CELL
  pure_quanta q_cap *
  page101_i125
#ISCELL
  logical_power vcc_core *
  page101_i126
#CELL
  pure_quanta q_cap *
  page101_i127
#ISCELL
  logical_power universal_gnd *
  page101_i128
#ISCELL
  logical_power universal_gnd *
  page101_i129
#ISCELL
  standard offpage *
  page101_i13
#ISCELL
  standard tap *
  page101_i130
#ISCELL
  standard tap *
  page101_i131
#ISCELL
  standard tap *
  page101_i132
#ISCELL
  standard tap *
  page101_i133
#ISCELL
  standard tap *
  page101_i134
#ISCELL
  standard tap *
  page101_i135
#ISCELL
  standard tap *
  page101_i136
#ISCELL
  standard tap *
  page101_i137
#ISCELL
  standard tap *
  page101_i138
#ISCELL
  standard tap *
  page101_i139
#ISCELL
  standard offpage *
  page101_i14
#ISCELL
  standard tap *
  page101_i140
#ISCELL
  standard tap *
  page101_i141
#ISCELL
  standard tap *
  page101_i142
#ISCELL
  standard tap *
  page101_i143
#ISCELL
  standard tap *
  page101_i144
#ISCELL
  standard tap *
  page101_i145
#ISCELL
  standard tap *
  page101_i146
#ISCELL
  standard tap *
  page101_i147
#ISCELL
  standard tap *
  page101_i148
#ISCELL
  standard tap *
  page101_i149
#ISCELL
  standard offpage *
  page101_i15
#ISCELL
  standard tap *
  page101_i150
#ISCELL
  standard tap *
  page101_i151
#ISCELL
  standard tap *
  page101_i152
#ISCELL
  standard tap *
  page101_i153
#ISCELL
  standard tap *
  page101_i154
#ISCELL
  standard tap *
  page101_i155
#ISCELL
  standard tap *
  page101_i156
#ISCELL
  standard tap *
  page101_i157
#ISCELL
  standard tap *
  page101_i158
#ISCELL
  standard tap *
  page101_i159
#ISCELL
  standard offpage *
  page101_i16
#ISCELL
  standard tap *
  page101_i160
#ISCELL
  standard tap *
  page101_i161
#ISCELL
  standard tap *
  page101_i162
#ISCELL
  standard offpage *
  page101_i163
#ISCELL
  standard offpage *
  page101_i164
#ISCELL
  standard offpage *
  page101_i165
#ISCELL
  standard tap *
  page101_i166
#ISCELL
  standard tap *
  page101_i167
#ISCELL
  standard tap *
  page101_i168
#ISCELL
  standard tap *
  page101_i169
#ISCELL
  standard offpage *
  page101_i17
#ISCELL
  standard tap *
  page101_i170
#ISCELL
  standard tap *
  page101_i171
#ISCELL
  standard tap *
  page101_i172
#ISCELL
  standard offpage *
  page101_i173
#ISCELL
  standard offpage *
  page101_i174
#ISCELL
  logical_power vcc_core *
  page101_i175
#CELL
  pure_quanta sconn288_adr50017p087cc *
  page101_i176
#ISCELL
  logical_power universal_gnd *
  page101_i177
#CELL
  pure_quanta sconn288_adr50017p087cc *
  page101_i178
#ISCELL
  standard offpage *
  page101_i179
#ISCELL
  standard offpage *
  page101_i18
#CELL
  pure_quanta q_res *
  page101_i180
#ISCELL
  standard offpage *
  page101_i19
#ISCELL
  standard offpage *
  page101_i2
#ISCELL
  standard offpage *
  page101_i20
#ISCELL
  logical_power vcc_core *
  page101_i21
#ISCELL
  standard tap *
  page101_i22
#ISCELL
  standard tap *
  page101_i23
#ISCELL
  standard tap *
  page101_i24
#ISCELL
  standard tap *
  page101_i25
#ISCELL
  standard tap *
  page101_i26
#ISCELL
  standard tap *
  page101_i27
#ISCELL
  standard tap *
  page101_i28
#ISCELL
  standard tap *
  page101_i29
#ISCELL
  standard offpage *
  page101_i3
#ISCELL
  standard tap *
  page101_i30
#ISCELL
  standard tap *
  page101_i31
#ISCELL
  standard tap *
  page101_i32
#ISCELL
  standard tap *
  page101_i33
#ISCELL
  standard tap *
  page101_i34
#ISCELL
  standard tap *
  page101_i35
#ISCELL
  standard tap *
  page101_i36
#ISCELL
  standard tap *
  page101_i37
#ISCELL
  standard tap *
  page101_i38
#ISCELL
  standard tap *
  page101_i39
#ISCELL
  standard offpage *
  page101_i4
#ISCELL
  standard tap *
  page101_i40
#ISCELL
  standard tap *
  page101_i41
#ISCELL
  standard tap *
  page101_i42
#ISCELL
  standard tap *
  page101_i43
#ISCELL
  standard tap *
  page101_i44
#ISCELL
  logical_power universal_gnd *
  page101_i45
#CELL
  pure_quanta q_res *
  page101_i46
#CELL
  pure_quanta sconn288_adr50017p087cc *
  page101_i47
#ISCELL
  standard tap *
  page101_i48
#ISCELL
  standard tap *
  page101_i49
#ISCELL
  standard tap *
  page101_i50
#ISCELL
  standard tap *
  page101_i51
#ISCELL
  standard tap *
  page101_i52
#ISCELL
  standard tap *
  page101_i53
#ISCELL
  standard tap *
  page101_i54
#ISCELL
  standard tap *
  page101_i55
#ISCELL
  standard tap *
  page101_i56
#ISCELL
  standard tap *
  page101_i57
#ISCELL
  standard tap *
  page101_i58
#ISCELL
  standard tap *
  page101_i59
#ISCELL
  standard offpage *
  page101_i6
#ISCELL
  standard tap *
  page101_i60
#ISCELL
  standard tap *
  page101_i61
#ISCELL
  standard tap *
  page101_i62
#ISCELL
  standard tap *
  page101_i63
#ISCELL
  standard tap *
  page101_i64
#ISCELL
  standard tap *
  page101_i65
#ISCELL
  standard tap *
  page101_i66
#ISCELL
  standard tap *
  page101_i67
#ISCELL
  standard tap *
  page101_i68
#ISCELL
  standard tap *
  page101_i69
#ISCELL
  standard offpage *
  page101_i7
#ISCELL
  standard tap *
  page101_i70
#ISCELL
  standard tap *
  page101_i71
#ISCELL
  standard tap *
  page101_i72
#ISCELL
  standard tap *
  page101_i73
#ISCELL
  standard tap *
  page101_i74
#ISCELL
  standard tap *
  page101_i75
#ISCELL
  standard tap *
  page101_i76
#ISCELL
  standard tap *
  page101_i77
#ISCELL
  standard tap *
  page101_i78
#ISCELL
  standard tap *
  page101_i79
#ISCELL
  standard offpage *
  page101_i8
#ISCELL
  standard tap *
  page101_i80
#ISCELL
  standard tap *
  page101_i81
#ISCELL
  standard tap *
  page101_i82
#ISCELL
  standard tap *
  page101_i83
#ISCELL
  standard tap *
  page101_i84
#ISCELL
  standard tap *
  page101_i85
#ISCELL
  standard tap *
  page101_i86
#ISCELL
  standard tap *
  page101_i87
#ISCELL
  standard tap *
  page101_i88
#ISCELL
  standard tap *
  page101_i89
#ISCELL
  standard offpage *
  page101_i9
#ISCELL
  standard tap *
  page101_i90
#ISCELL
  standard tap *
  page101_i91
#ISCELL
  standard tap *
  page101_i92
#ISCELL
  standard tap *
  page101_i93
#ISCELL
  standard tap *
  page101_i94
#ISCELL
  standard tap *
  page101_i95
#ISCELL
  standard tap *
  page101_i96
#ISCELL
  standard tap *
  page101_i97
#ISCELL
  standard tap *
  page101_i98
#ISCELL
  standard tap *
  page101_i99
#ISCELL
  logical_power cad_note *
  *
#ISCELL
  pure_quanta quanta_title_block_c *
  *
#ISCELL
  logical_power universal_gnd *
  page102_i1
#ISCELL
  standard offpage *
  page102_i10
#ISCELL
  standard tap *
  page102_i100
#ISCELL
  standard tap *
  page102_i101
#ISCELL
  standard tap *
  page102_i102
#ISCELL
  standard tap *
  page102_i103
#ISCELL
  standard tap *
  page102_i104
#ISCELL
  standard tap *
  page102_i105
#ISCELL
  standard tap *
  page102_i106
#ISCELL
  standard tap *
  page102_i107
#ISCELL
  standard tap *
  page102_i108
#ISCELL
  standard tap *
  page102_i109
#ISCELL
  standard offpage *
  page102_i11
#ISCELL
  standard tap *
  page102_i110
#ISCELL
  standard tap *
  page102_i111
#ISCELL
  standard tap *
  page102_i112
#ISCELL
  standard tap *
  page102_i113
#ISCELL
  standard tap *
  page102_i114
#ISCELL
  standard offpage *
  page102_i115
#ISCELL
  standard offpage *
  page102_i116
#ISCELL
  standard tap *
  page102_i117
#ISCELL
  standard tap *
  page102_i118
#ISCELL
  standard tap *
  page102_i119
#ISCELL
  logical_power vcc_core *
  page102_i12
#ISCELL
  standard tap *
  page102_i120
#ISCELL
  standard offpage *
  page102_i121
#ISCELL
  logical_power universal_gnd *
  page102_i122
#ISCELL
  logical_power universal_gnd *
  page102_i123
#CELL
  pure_quanta q_cap *
  page102_i124
#ISCELL
  logical_power vcc_core *
  page102_i125
#CELL
  pure_quanta q_cap *
  page102_i127
#ISCELL
  logical_power vcc_core *
  page102_i128
#ISCELL
  standard tap *
  page102_i129
#CELL
  pure_quanta sconn288_adr50017p130cc *
  page102_i13
#ISCELL
  standard tap *
  page102_i130
#ISCELL
  standard tap *
  page102_i131
#ISCELL
  standard tap *
  page102_i132
#ISCELL
  standard tap *
  page102_i133
#ISCELL
  standard tap *
  page102_i134
#ISCELL
  standard tap *
  page102_i135
#ISCELL
  standard tap *
  page102_i136
#ISCELL
  standard tap *
  page102_i137
#ISCELL
  standard tap *
  page102_i138
#ISCELL
  standard tap *
  page102_i139
#ISCELL
  standard tap *
  page102_i14
#ISCELL
  standard tap *
  page102_i140
#ISCELL
  standard tap *
  page102_i141
#ISCELL
  standard tap *
  page102_i142
#ISCELL
  standard tap *
  page102_i143
#ISCELL
  standard tap *
  page102_i144
#ISCELL
  standard tap *
  page102_i145
#ISCELL
  standard tap *
  page102_i146
#ISCELL
  standard tap *
  page102_i147
#ISCELL
  standard tap *
  page102_i148
#ISCELL
  standard tap *
  page102_i149
#ISCELL
  standard tap *
  page102_i15
#ISCELL
  standard tap *
  page102_i150
#ISCELL
  standard tap *
  page102_i151
#ISCELL
  standard tap *
  page102_i152
#ISCELL
  standard tap *
  page102_i153
#ISCELL
  standard tap *
  page102_i154
#ISCELL
  standard tap *
  page102_i155
#ISCELL
  standard tap *
  page102_i156
#ISCELL
  standard tap *
  page102_i157
#ISCELL
  standard tap *
  page102_i158
#ISCELL
  standard tap *
  page102_i159
#ISCELL
  standard offpage *
  page102_i16
#ISCELL
  standard tap *
  page102_i160
#ISCELL
  standard tap *
  page102_i161
#ISCELL
  standard tap *
  page102_i162
#ISCELL
  standard tap *
  page102_i163
#ISCELL
  standard tap *
  page102_i164
#ISCELL
  standard tap *
  page102_i165
#ISCELL
  standard tap *
  page102_i166
#CELL
  pure_quanta q_cap *
  page102_i167
#ISCELL
  logical_power universal_gnd *
  page102_i168
#CELL
  pure_quanta sconn288_adr50017p130cc *
  page102_i169
#ISCELL
  standard offpage *
  page102_i17
#ISCELL
  standard offpage *
  page102_i170
#ISCELL
  standard offpage *
  page102_i171
#ISCELL
  standard offpage *
  page102_i172
#ISCELL
  standard tap *
  page102_i173
#ISCELL
  standard tap *
  page102_i174
#ISCELL
  standard offpage *
  page102_i175
#ISCELL
  logical_power vcc_core *
  page102_i176
#ISCELL
  logical_power universal_gnd *
  page102_i177
#CELL
  pure_quanta sconn288_adr50017p130cc *
  page102_i178
#ISCELL
  standard offpage *
  page102_i179
#ISCELL
  standard offpage *
  page102_i18
#CELL
  pure_quanta q_res *
  page102_i180
#ISCELL
  standard offpage *
  page102_i19
#CELL
  pure_quanta q_res *
  page102_i2
#ISCELL
  standard offpage *
  page102_i20
#ISCELL
  standard offpage *
  page102_i21
#ISCELL
  standard offpage *
  page102_i22
#ISCELL
  standard offpage *
  page102_i23
#ISCELL
  standard offpage *
  page102_i24
#ISCELL
  standard offpage *
  page102_i25
#ISCELL
  standard offpage *
  page102_i26
#ISCELL
  standard tap *
  page102_i27
#ISCELL
  standard tap *
  page102_i28
#ISCELL
  standard tap *
  page102_i29
#ISCELL
  standard offpage *
  page102_i3
#ISCELL
  standard tap *
  page102_i30
#ISCELL
  standard tap *
  page102_i31
#ISCELL
  standard tap *
  page102_i32
#ISCELL
  standard tap *
  page102_i33
#ISCELL
  standard tap *
  page102_i34
#ISCELL
  standard tap *
  page102_i35
#ISCELL
  standard tap *
  page102_i36
#ISCELL
  standard tap *
  page102_i37
#ISCELL
  standard tap *
  page102_i38
#ISCELL
  standard tap *
  page102_i39
#ISCELL
  standard offpage *
  page102_i4
#ISCELL
  standard tap *
  page102_i40
#ISCELL
  standard tap *
  page102_i41
#ISCELL
  standard tap *
  page102_i42
#ISCELL
  standard tap *
  page102_i43
#ISCELL
  standard tap *
  page102_i44
#ISCELL
  standard tap *
  page102_i45
#ISCELL
  standard tap *
  page102_i46
#ISCELL
  standard tap *
  page102_i47
#ISCELL
  standard tap *
  page102_i48
#ISCELL
  standard tap *
  page102_i49
#ISCELL
  standard offpage *
  page102_i5
#ISCELL
  standard tap *
  page102_i50
#ISCELL
  standard tap *
  page102_i51
#ISCELL
  standard tap *
  page102_i52
#ISCELL
  standard tap *
  page102_i53
#ISCELL
  standard tap *
  page102_i54
#ISCELL
  standard tap *
  page102_i55
#ISCELL
  standard tap *
  page102_i56
#ISCELL
  standard tap *
  page102_i57
#ISCELL
  standard tap *
  page102_i58
#ISCELL
  standard tap *
  page102_i59
#ISCELL
  standard offpage *
  page102_i6
#ISCELL
  standard tap *
  page102_i60
#ISCELL
  standard tap *
  page102_i61
#ISCELL
  standard tap *
  page102_i62
#ISCELL
  standard tap *
  page102_i63
#ISCELL
  standard tap *
  page102_i64
#ISCELL
  standard tap *
  page102_i65
#ISCELL
  standard tap *
  page102_i66
#ISCELL
  standard tap *
  page102_i67
#ISCELL
  standard tap *
  page102_i68
#ISCELL
  standard tap *
  page102_i69
#ISCELL
  standard tap *
  page102_i70
#ISCELL
  standard tap *
  page102_i71
#ISCELL
  standard tap *
  page102_i72
#ISCELL
  standard tap *
  page102_i73
#ISCELL
  standard tap *
  page102_i74
#ISCELL
  standard tap *
  page102_i75
#ISCELL
  standard tap *
  page102_i76
#ISCELL
  standard tap *
  page102_i77
#ISCELL
  standard tap *
  page102_i78
#ISCELL
  standard tap *
  page102_i79
#ISCELL
  standard offpage *
  page102_i8
#ISCELL
  standard tap *
  page102_i80
#ISCELL
  standard tap *
  page102_i81
#ISCELL
  standard tap *
  page102_i82
#ISCELL
  standard tap *
  page102_i83
#ISCELL
  standard tap *
  page102_i84
#ISCELL
  standard tap *
  page102_i85
#ISCELL
  standard tap *
  page102_i86
#ISCELL
  standard tap *
  page102_i87
#ISCELL
  standard tap *
  page102_i88
#ISCELL
  standard tap *
  page102_i89
#ISCELL
  standard offpage *
  page102_i9
#ISCELL
  standard tap *
  page102_i90
#ISCELL
  standard tap *
  page102_i91
#ISCELL
  standard tap *
  page102_i92
#ISCELL
  standard tap *
  page102_i93
#ISCELL
  standard tap *
  page102_i94
#ISCELL
  standard tap *
  page102_i95
#ISCELL
  standard tap *
  page102_i96
#ISCELL
  standard tap *
  page102_i97
#ISCELL
  standard tap *
  page102_i98
#ISCELL
  standard tap *
  page102_i99
#ISCELL
  logical_power cad_note *
  *
#ISCELL
  pure_quanta quanta_title_block_c *
  *
#ISCELL
  logical_power universal_gnd *
  page103_i1
#ISCELL
  standard offpage *
  page103_i10
#ISCELL
  standard tap *
  page103_i100
#ISCELL
  standard tap *
  page103_i101
#ISCELL
  standard tap *
  page103_i102
#ISCELL
  standard tap *
  page103_i103
#ISCELL
  standard tap *
  page103_i104
#ISCELL
  standard tap *
  page103_i105
#ISCELL
  standard tap *
  page103_i106
#ISCELL
  standard tap *
  page103_i107
#ISCELL
  standard tap *
  page103_i108
#ISCELL
  standard tap *
  page103_i109
#ISCELL
  standard offpage *
  page103_i11
#ISCELL
  standard tap *
  page103_i110
#ISCELL
  standard tap *
  page103_i111
#ISCELL
  standard tap *
  page103_i112
#ISCELL
  standard offpage *
  page103_i113
#ISCELL
  standard tap *
  page103_i114
#ISCELL
  standard tap *
  page103_i115
#ISCELL
  standard tap *
  page103_i116
#ISCELL
  standard tap *
  page103_i117
#ISCELL
  standard tap *
  page103_i118
#ISCELL
  standard tap *
  page103_i119
#ISCELL
  logical_power vcc_core *
  page103_i12
#ISCELL
  logical_power universal_gnd *
  page103_i120
#ISCELL
  logical_power universal_gnd *
  page103_i121
#CELL
  pure_quanta q_cap *
  page103_i122
#ISCELL
  logical_power vcc_core *
  page103_i123
#ISCELL
  standard offpage *
  page103_i124
#CELL
  pure_quanta q_cap *
  page103_i126
#ISCELL
  logical_power vcc_core *
  page103_i127
#CELL
  pure_quanta q_cap *
  page103_i128
#ISCELL
  logical_power universal_gnd *
  page103_i129
#ISCELL
  standard tap *
  page103_i13
#ISCELL
  standard tap *
  page103_i130
#ISCELL
  standard tap *
  page103_i131
#ISCELL
  standard tap *
  page103_i132
#ISCELL
  standard tap *
  page103_i133
#ISCELL
  standard tap *
  page103_i134
#ISCELL
  standard tap *
  page103_i135
#ISCELL
  standard tap *
  page103_i136
#ISCELL
  standard tap *
  page103_i137
#ISCELL
  standard tap *
  page103_i138
#ISCELL
  standard tap *
  page103_i139
#ISCELL
  standard offpage *
  page103_i14
#ISCELL
  standard tap *
  page103_i140
#ISCELL
  standard tap *
  page103_i141
#ISCELL
  standard tap *
  page103_i142
#ISCELL
  standard tap *
  page103_i143
#ISCELL
  standard tap *
  page103_i144
#ISCELL
  standard tap *
  page103_i145
#ISCELL
  standard tap *
  page103_i146
#ISCELL
  standard tap *
  page103_i147
#ISCELL
  standard tap *
  page103_i148
#ISCELL
  standard tap *
  page103_i149
#ISCELL
  standard offpage *
  page103_i15
#ISCELL
  standard tap *
  page103_i150
#ISCELL
  standard tap *
  page103_i151
#ISCELL
  standard tap *
  page103_i152
#ISCELL
  standard tap *
  page103_i153
#ISCELL
  standard tap *
  page103_i154
#ISCELL
  standard tap *
  page103_i155
#ISCELL
  standard tap *
  page103_i156
#ISCELL
  standard tap *
  page103_i157
#ISCELL
  standard tap *
  page103_i158
#ISCELL
  standard tap *
  page103_i159
#ISCELL
  standard offpage *
  page103_i16
#ISCELL
  standard tap *
  page103_i160
#ISCELL
  standard tap *
  page103_i161
#ISCELL
  standard tap *
  page103_i162
#ISCELL
  standard tap *
  page103_i163
#ISCELL
  standard tap *
  page103_i164
#ISCELL
  standard tap *
  page103_i165
#ISCELL
  standard tap *
  page103_i166
#ISCELL
  standard offpage *
  page103_i167
#ISCELL
  standard offpage *
  page103_i168
#ISCELL
  standard offpage *
  page103_i169
#ISCELL
  standard offpage *
  page103_i17
#ISCELL
  standard tap *
  page103_i170
#ISCELL
  standard tap *
  page103_i171
#ISCELL
  standard tap *
  page103_i172
#ISCELL
  standard offpage *
  page103_i173
#ISCELL
  standard offpage *
  page103_i174
#ISCELL
  logical_power vcc_core *
  page103_i175
#CELL
  pure_quanta sconn288_adr50017p087cc *
  page103_i176
#ISCELL
  logical_power universal_gnd *
  page103_i177
#CELL
  pure_quanta sconn288_adr50017p087cc *
  page103_i178
#ISCELL
  standard offpage *
  page103_i179
#ISCELL
  standard offpage *
  page103_i18
#CELL
  pure_quanta q_res *
  page103_i180
#ISCELL
  standard offpage *
  page103_i19
#CELL
  pure_quanta q_res *
  page103_i2
#ISCELL
  standard offpage *
  page103_i20
#ISCELL
  standard offpage *
  page103_i21
#ISCELL
  standard offpage *
  page103_i22
#ISCELL
  standard offpage *
  page103_i23
#ISCELL
  standard offpage *
  page103_i24
#ISCELL
  standard tap *
  page103_i25
#ISCELL
  standard tap *
  page103_i26
#ISCELL
  standard tap *
  page103_i27
#ISCELL
  standard tap *
  page103_i28
#ISCELL
  standard tap *
  page103_i29
#ISCELL
  standard offpage *
  page103_i3
#ISCELL
  standard tap *
  page103_i30
#ISCELL
  standard tap *
  page103_i31
#ISCELL
  standard tap *
  page103_i32
#ISCELL
  standard tap *
  page103_i33
#ISCELL
  standard tap *
  page103_i34
#ISCELL
  standard tap *
  page103_i35
#ISCELL
  standard tap *
  page103_i36
#ISCELL
  standard tap *
  page103_i37
#ISCELL
  standard tap *
  page103_i38
#ISCELL
  standard tap *
  page103_i39
#ISCELL
  standard offpage *
  page103_i4
#ISCELL
  standard tap *
  page103_i40
#ISCELL
  standard tap *
  page103_i41
#ISCELL
  standard tap *
  page103_i42
#ISCELL
  standard tap *
  page103_i43
#ISCELL
  standard tap *
  page103_i44
#ISCELL
  standard tap *
  page103_i45
#ISCELL
  standard tap *
  page103_i46
#ISCELL
  standard tap *
  page103_i47
#ISCELL
  standard tap *
  page103_i48
#ISCELL
  standard tap *
  page103_i49
#ISCELL
  standard offpage *
  page103_i5
#ISCELL
  standard tap *
  page103_i50
#CELL
  pure_quanta sconn288_adr50017p087cc *
  page103_i51
#ISCELL
  standard tap *
  page103_i52
#ISCELL
  standard tap *
  page103_i53
#ISCELL
  standard tap *
  page103_i54
#ISCELL
  standard tap *
  page103_i55
#ISCELL
  standard tap *
  page103_i56
#ISCELL
  standard tap *
  page103_i57
#ISCELL
  standard tap *
  page103_i58
#ISCELL
  standard tap *
  page103_i59
#ISCELL
  standard offpage *
  page103_i6
#ISCELL
  standard tap *
  page103_i60
#ISCELL
  standard tap *
  page103_i61
#ISCELL
  standard tap *
  page103_i62
#ISCELL
  standard tap *
  page103_i63
#ISCELL
  standard tap *
  page103_i64
#ISCELL
  standard tap *
  page103_i65
#ISCELL
  standard tap *
  page103_i66
#ISCELL
  standard tap *
  page103_i67
#ISCELL
  standard tap *
  page103_i68
#ISCELL
  standard tap *
  page103_i69
#ISCELL
  standard tap *
  page103_i70
#ISCELL
  standard tap *
  page103_i71
#ISCELL
  standard tap *
  page103_i72
#ISCELL
  standard tap *
  page103_i73
#ISCELL
  standard tap *
  page103_i74
#ISCELL
  standard tap *
  page103_i75
#ISCELL
  standard tap *
  page103_i76
#ISCELL
  standard tap *
  page103_i77
#ISCELL
  standard tap *
  page103_i78
#ISCELL
  standard tap *
  page103_i79
#ISCELL
  standard offpage *
  page103_i8
#ISCELL
  standard tap *
  page103_i80
#ISCELL
  standard tap *
  page103_i81
#ISCELL
  standard tap *
  page103_i82
#ISCELL
  standard tap *
  page103_i83
#ISCELL
  standard tap *
  page103_i84
#ISCELL
  standard tap *
  page103_i85
#ISCELL
  standard tap *
  page103_i86
#ISCELL
  standard tap *
  page103_i87
#ISCELL
  standard tap *
  page103_i88
#ISCELL
  standard tap *
  page103_i89
#ISCELL
  standard offpage *
  page103_i9
#ISCELL
  standard tap *
  page103_i90
#ISCELL
  standard tap *
  page103_i91
#ISCELL
  standard tap *
  page103_i92
#ISCELL
  standard tap *
  page103_i93
#ISCELL
  standard tap *
  page103_i94
#ISCELL
  standard tap *
  page103_i95
#ISCELL
  standard tap *
  page103_i96
#ISCELL
  standard tap *
  page103_i97
#ISCELL
  standard tap *
  page103_i98
#ISCELL
  standard tap *
  page103_i99
#ISCELL
  logical_power cad_note *
  *
#ISCELL
  pure_quanta quanta_title_block_c *
  *
#ISCELL
  logical_power universal_gnd *
  page104_i1
#ISCELL
  standard offpage *
  page104_i10
#ISCELL
  standard tap *
  page104_i100
#ISCELL
  standard tap *
  page104_i101
#ISCELL
  standard tap *
  page104_i102
#ISCELL
  standard tap *
  page104_i103
#ISCELL
  standard tap *
  page104_i104
#ISCELL
  standard tap *
  page104_i105
#ISCELL
  standard tap *
  page104_i106
#ISCELL
  standard tap *
  page104_i107
#ISCELL
  standard tap *
  page104_i108
#ISCELL
  standard tap *
  page104_i109
#ISCELL
  standard offpage *
  page104_i11
#ISCELL
  standard tap *
  page104_i110
#ISCELL
  standard tap *
  page104_i111
#ISCELL
  standard tap *
  page104_i112
#ISCELL
  standard tap *
  page104_i113
#ISCELL
  standard tap *
  page104_i114
#ISCELL
  standard tap *
  page104_i115
#ISCELL
  standard tap *
  page104_i116
#ISCELL
  standard tap *
  page104_i117
#ISCELL
  standard tap *
  page104_i118
#ISCELL
  standard tap *
  page104_i119
#ISCELL
  logical_power vcc_core *
  page104_i12
#ISCELL
  logical_power universal_gnd *
  page104_i120
#ISCELL
  logical_power universal_gnd *
  page104_i121
#CELL
  pure_quanta q_cap *
  page104_i122
#ISCELL
  logical_power vcc_core *
  page104_i123
#ISCELL
  standard offpage *
  page104_i124
#ISCELL
  standard offpage *
  page104_i125
#CELL
  pure_quanta q_cap *
  page104_i127
#ISCELL
  logical_power vcc_core *
  page104_i128
#CELL
  pure_quanta q_cap *
  page104_i129
#ISCELL
  standard offpage *
  page104_i13
#ISCELL
  standard tap *
  page104_i130
#ISCELL
  standard tap *
  page104_i131
#ISCELL
  standard tap *
  page104_i132
#ISCELL
  standard tap *
  page104_i133
#ISCELL
  standard tap *
  page104_i134
#ISCELL
  standard tap *
  page104_i135
#ISCELL
  standard tap *
  page104_i136
#ISCELL
  standard tap *
  page104_i137
#ISCELL
  standard tap *
  page104_i138
#ISCELL
  standard tap *
  page104_i139
#ISCELL
  standard offpage *
  page104_i14
#ISCELL
  standard tap *
  page104_i140
#ISCELL
  standard tap *
  page104_i141
#ISCELL
  standard tap *
  page104_i142
#ISCELL
  standard tap *
  page104_i143
#ISCELL
  standard tap *
  page104_i144
#ISCELL
  standard tap *
  page104_i145
#ISCELL
  standard tap *
  page104_i146
#ISCELL
  standard tap *
  page104_i147
#ISCELL
  standard tap *
  page104_i148
#ISCELL
  standard tap *
  page104_i149
#ISCELL
  standard offpage *
  page104_i15
#ISCELL
  standard tap *
  page104_i150
#ISCELL
  standard tap *
  page104_i151
#ISCELL
  standard tap *
  page104_i152
#ISCELL
  standard tap *
  page104_i153
#ISCELL
  standard tap *
  page104_i154
#ISCELL
  standard tap *
  page104_i155
#ISCELL
  standard tap *
  page104_i156
#ISCELL
  standard tap *
  page104_i157
#ISCELL
  standard tap *
  page104_i158
#ISCELL
  standard tap *
  page104_i159
#ISCELL
  standard offpage *
  page104_i16
#ISCELL
  standard tap *
  page104_i160
#ISCELL
  standard tap *
  page104_i161
#ISCELL
  standard tap *
  page104_i162
#ISCELL
  standard tap *
  page104_i163
#ISCELL
  standard tap *
  page104_i164
#ISCELL
  standard tap *
  page104_i165
#ISCELL
  standard tap *
  page104_i166
#ISCELL
  standard tap *
  page104_i167
#ISCELL
  standard tap *
  page104_i168
#ISCELL
  standard tap *
  page104_i169
#ISCELL
  standard offpage *
  page104_i17
#ISCELL
  standard offpage *
  page104_i170
#ISCELL
  standard offpage *
  page104_i171
#ISCELL
  standard offpage *
  page104_i172
#ISCELL
  standard offpage *
  page104_i173
#ISCELL
  logical_power universal_gnd *
  page104_i174
#CELL
  pure_quanta sconn288_adr50017p130cc *
  page104_i175
#ISCELL
  logical_power universal_gnd *
  page104_i176
#ISCELL
  logical_power vcc_core *
  page104_i177
#CELL
  pure_quanta sconn288_adr50017p130cc *
  page104_i178
#ISCELL
  standard offpage *
  page104_i179
#ISCELL
  standard offpage *
  page104_i18
#CELL
  pure_quanta q_res *
  page104_i180
#ISCELL
  standard offpage *
  page104_i19
#CELL
  pure_quanta q_res *
  page104_i2
#ISCELL
  standard offpage *
  page104_i20
#ISCELL
  standard offpage *
  page104_i21
#ISCELL
  standard offpage *
  page104_i22
#ISCELL
  standard offpage *
  page104_i23
#ISCELL
  standard offpage *
  page104_i24
#CELL
  pure_quanta sconn288_adr50017p130cc *
  page104_i25
#ISCELL
  standard tap *
  page104_i26
#ISCELL
  standard tap *
  page104_i27
#ISCELL
  standard tap *
  page104_i28
#ISCELL
  standard tap *
  page104_i29
#ISCELL
  standard offpage *
  page104_i3
#ISCELL
  standard tap *
  page104_i30
#ISCELL
  standard tap *
  page104_i31
#ISCELL
  standard tap *
  page104_i32
#ISCELL
  standard tap *
  page104_i33
#ISCELL
  standard tap *
  page104_i34
#ISCELL
  standard tap *
  page104_i35
#ISCELL
  standard tap *
  page104_i36
#ISCELL
  standard tap *
  page104_i37
#ISCELL
  standard tap *
  page104_i38
#ISCELL
  standard tap *
  page104_i39
#ISCELL
  standard offpage *
  page104_i4
#ISCELL
  standard tap *
  page104_i40
#ISCELL
  standard tap *
  page104_i41
#ISCELL
  standard tap *
  page104_i42
#ISCELL
  standard tap *
  page104_i43
#ISCELL
  standard tap *
  page104_i44
#ISCELL
  standard tap *
  page104_i45
#ISCELL
  standard tap *
  page104_i46
#ISCELL
  standard tap *
  page104_i47
#ISCELL
  standard tap *
  page104_i48
#ISCELL
  standard tap *
  page104_i49
#ISCELL
  standard offpage *
  page104_i5
#ISCELL
  standard tap *
  page104_i50
#ISCELL
  standard tap *
  page104_i51
#ISCELL
  standard tap *
  page104_i52
#ISCELL
  standard tap *
  page104_i53
#ISCELL
  standard tap *
  page104_i54
#ISCELL
  standard tap *
  page104_i55
#ISCELL
  standard tap *
  page104_i56
#ISCELL
  standard tap *
  page104_i57
#ISCELL
  standard tap *
  page104_i58
#ISCELL
  standard tap *
  page104_i59
#ISCELL
  standard offpage *
  page104_i6
#ISCELL
  standard tap *
  page104_i60
#ISCELL
  standard tap *
  page104_i61
#ISCELL
  standard tap *
  page104_i62
#ISCELL
  standard tap *
  page104_i63
#ISCELL
  standard tap *
  page104_i64
#ISCELL
  standard tap *
  page104_i65
#ISCELL
  standard tap *
  page104_i66
#ISCELL
  standard tap *
  page104_i67
#ISCELL
  standard tap *
  page104_i68
#ISCELL
  standard tap *
  page104_i69
#ISCELL
  standard offpage *
  page104_i7
#ISCELL
  standard tap *
  page104_i70
#ISCELL
  standard tap *
  page104_i71
#ISCELL
  standard tap *
  page104_i72
#ISCELL
  standard tap *
  page104_i73
#ISCELL
  standard tap *
  page104_i74
#ISCELL
  standard tap *
  page104_i75
#ISCELL
  standard tap *
  page104_i76
#ISCELL
  standard tap *
  page104_i77
#ISCELL
  standard tap *
  page104_i78
#ISCELL
  standard tap *
  page104_i79
#ISCELL
  standard tap *
  page104_i80
#ISCELL
  standard tap *
  page104_i81
#ISCELL
  standard tap *
  page104_i82
#ISCELL
  standard tap *
  page104_i83
#ISCELL
  standard tap *
  page104_i84
#ISCELL
  standard tap *
  page104_i85
#ISCELL
  standard tap *
  page104_i86
#ISCELL
  standard tap *
  page104_i87
#ISCELL
  standard tap *
  page104_i88
#ISCELL
  standard tap *
  page104_i89
#ISCELL
  standard offpage *
  page104_i9
#ISCELL
  standard tap *
  page104_i90
#ISCELL
  standard tap *
  page104_i91
#ISCELL
  standard tap *
  page104_i92
#ISCELL
  standard tap *
  page104_i93
#ISCELL
  standard tap *
  page104_i94
#ISCELL
  standard tap *
  page104_i95
#ISCELL
  standard tap *
  page104_i96
#ISCELL
  standard tap *
  page104_i97
#ISCELL
  standard tap *
  page104_i98
#ISCELL
  standard tap *
  page104_i99
#ISCELL
  logical_power cad_note *
  *
#ISCELL
  pure_quanta quanta_title_block_c *
  *
#ISCELL
  logical_power universal_gnd *
  page105_i1
#ISCELL
  standard offpage *
  page105_i10
#ISCELL
  standard tap *
  page105_i100
#ISCELL
  standard tap *
  page105_i101
#ISCELL
  standard tap *
  page105_i102
#ISCELL
  standard tap *
  page105_i103
#ISCELL
  standard tap *
  page105_i104
#ISCELL
  standard tap *
  page105_i105
#ISCELL
  standard tap *
  page105_i106
#ISCELL
  standard tap *
  page105_i107
#ISCELL
  standard tap *
  page105_i108
#ISCELL
  standard tap *
  page105_i109
#ISCELL
  standard offpage *
  page105_i11
#ISCELL
  standard tap *
  page105_i110
#ISCELL
  standard tap *
  page105_i111
#ISCELL
  standard tap *
  page105_i112
#ISCELL
  standard offpage *
  page105_i113
#ISCELL
  standard tap *
  page105_i114
#ISCELL
  standard tap *
  page105_i115
#ISCELL
  standard tap *
  page105_i116
#ISCELL
  standard tap *
  page105_i117
#ISCELL
  standard tap *
  page105_i118
#ISCELL
  standard tap *
  page105_i119
#ISCELL
  logical_power vcc_core *
  page105_i12
#ISCELL
  logical_power universal_gnd *
  page105_i120
#ISCELL
  logical_power universal_gnd *
  page105_i121
#ISCELL
  logical_power vcc_core *
  page105_i122
#CELL
  pure_quanta q_cap *
  page105_i123
#CELL
  pure_quanta q_cap *
  page105_i124
#ISCELL
  logical_power vcc_core *
  page105_i125
#ISCELL
  standard offpage *
  page105_i126
#ISCELL
  standard tap *
  page105_i128
#ISCELL
  standard tap *
  page105_i129
#ISCELL
  standard tap *
  page105_i130
#ISCELL
  standard tap *
  page105_i131
#ISCELL
  standard tap *
  page105_i132
#ISCELL
  standard tap *
  page105_i133
#ISCELL
  standard tap *
  page105_i134
#ISCELL
  standard tap *
  page105_i135
#ISCELL
  standard tap *
  page105_i136
#ISCELL
  standard tap *
  page105_i137
#ISCELL
  standard tap *
  page105_i138
#ISCELL
  standard tap *
  page105_i139
#ISCELL
  standard tap *
  page105_i14
#ISCELL
  standard tap *
  page105_i140
#ISCELL
  standard tap *
  page105_i141
#ISCELL
  standard tap *
  page105_i142
#ISCELL
  standard tap *
  page105_i143
#ISCELL
  standard tap *
  page105_i144
#ISCELL
  standard tap *
  page105_i145
#CELL
  pure_quanta q_cap *
  page105_i146
#ISCELL
  logical_power universal_gnd *
  page105_i147
#ISCELL
  standard tap *
  page105_i149
#ISCELL
  standard offpage *
  page105_i15
#ISCELL
  standard tap *
  page105_i150
#ISCELL
  standard tap *
  page105_i151
#ISCELL
  standard tap *
  page105_i152
#ISCELL
  standard tap *
  page105_i153
#ISCELL
  standard tap *
  page105_i154
#ISCELL
  standard tap *
  page105_i155
#ISCELL
  standard tap *
  page105_i156
#ISCELL
  standard tap *
  page105_i157
#ISCELL
  standard tap *
  page105_i158
#ISCELL
  standard tap *
  page105_i159
#ISCELL
  standard offpage *
  page105_i16
#ISCELL
  standard tap *
  page105_i160
#ISCELL
  standard tap *
  page105_i161
#ISCELL
  standard tap *
  page105_i162
#ISCELL
  standard tap *
  page105_i163
#ISCELL
  standard tap *
  page105_i164
#ISCELL
  standard tap *
  page105_i165
#ISCELL
  standard tap *
  page105_i166
#ISCELL
  standard tap *
  page105_i167
#ISCELL
  standard offpage *
  page105_i168
#ISCELL
  standard offpage *
  page105_i169
#ISCELL
  standard offpage *
  page105_i17
#ISCELL
  standard offpage *
  page105_i170
#ISCELL
  standard tap *
  page105_i171
#ISCELL
  standard tap *
  page105_i172
#ISCELL
  standard tap *
  page105_i173
#ISCELL
  standard offpage *
  page105_i174
#ISCELL
  standard offpage *
  page105_i175
#ISCELL
  logical_power vcc_core *
  page105_i176
#ISCELL
  logical_power universal_gnd *
  page105_i177
#CELL
  pure_quanta sconn288_adr50017p087cc *
  page105_i178
#ISCELL
  standard offpage *
  page105_i18
#CELL
  pure_quanta sconn288_adr50017p087cc *
  page105_i180
#CELL
  pure_quanta sconn288_adr50017p087cc *
  page105_i181
#ISCELL
  standard offpage *
  page105_i182
#CELL
  pure_quanta q_res *
  page105_i183
#ISCELL
  standard offpage *
  page105_i19
#CELL
  pure_quanta q_res *
  page105_i2
#ISCELL
  standard offpage *
  page105_i20
#ISCELL
  standard offpage *
  page105_i21
#ISCELL
  standard offpage *
  page105_i22
#ISCELL
  standard offpage *
  page105_i23
#ISCELL
  standard offpage *
  page105_i24
#ISCELL
  standard offpage *
  page105_i25
#ISCELL
  standard tap *
  page105_i26
#ISCELL
  standard tap *
  page105_i27
#ISCELL
  standard tap *
  page105_i28
#ISCELL
  standard tap *
  page105_i29
#ISCELL
  standard offpage *
  page105_i3
#ISCELL
  standard tap *
  page105_i30
#ISCELL
  standard tap *
  page105_i31
#ISCELL
  standard tap *
  page105_i32
#ISCELL
  standard tap *
  page105_i33
#ISCELL
  standard tap *
  page105_i34
#ISCELL
  standard tap *
  page105_i35
#ISCELL
  standard tap *
  page105_i36
#ISCELL
  standard tap *
  page105_i37
#ISCELL
  standard tap *
  page105_i38
#ISCELL
  standard tap *
  page105_i39
#ISCELL
  standard offpage *
  page105_i4
#ISCELL
  standard tap *
  page105_i40
#ISCELL
  standard tap *
  page105_i41
#ISCELL
  standard tap *
  page105_i42
#ISCELL
  standard tap *
  page105_i43
#ISCELL
  standard tap *
  page105_i44
#ISCELL
  standard tap *
  page105_i45
#ISCELL
  standard tap *
  page105_i46
#ISCELL
  standard tap *
  page105_i47
#ISCELL
  standard tap *
  page105_i48
#ISCELL
  standard tap *
  page105_i49
#ISCELL
  standard offpage *
  page105_i5
#ISCELL
  standard tap *
  page105_i50
#ISCELL
  standard tap *
  page105_i51
#ISCELL
  standard tap *
  page105_i52
#ISCELL
  standard tap *
  page105_i53
#ISCELL
  standard tap *
  page105_i54
#ISCELL
  standard tap *
  page105_i55
#ISCELL
  standard tap *
  page105_i56
#ISCELL
  standard tap *
  page105_i57
#ISCELL
  standard tap *
  page105_i58
#ISCELL
  standard tap *
  page105_i59
#ISCELL
  standard offpage *
  page105_i6
#ISCELL
  standard tap *
  page105_i60
#ISCELL
  standard tap *
  page105_i61
#ISCELL
  standard tap *
  page105_i62
#ISCELL
  standard tap *
  page105_i63
#ISCELL
  standard tap *
  page105_i64
#ISCELL
  standard tap *
  page105_i65
#ISCELL
  standard tap *
  page105_i66
#ISCELL
  standard tap *
  page105_i67
#ISCELL
  standard tap *
  page105_i68
#ISCELL
  standard tap *
  page105_i69
#ISCELL
  standard tap *
  page105_i70
#ISCELL
  standard tap *
  page105_i71
#ISCELL
  standard tap *
  page105_i72
#ISCELL
  standard tap *
  page105_i73
#ISCELL
  standard tap *
  page105_i74
#ISCELL
  standard tap *
  page105_i75
#ISCELL
  standard tap *
  page105_i76
#ISCELL
  standard tap *
  page105_i77
#ISCELL
  standard tap *
  page105_i78
#ISCELL
  standard tap *
  page105_i79
#ISCELL
  standard offpage *
  page105_i8
#ISCELL
  standard tap *
  page105_i80
#ISCELL
  standard tap *
  page105_i81
#ISCELL
  standard tap *
  page105_i82
#ISCELL
  standard tap *
  page105_i83
#ISCELL
  standard tap *
  page105_i84
#ISCELL
  standard tap *
  page105_i85
#ISCELL
  standard tap *
  page105_i86
#ISCELL
  standard tap *
  page105_i87
#ISCELL
  standard tap *
  page105_i88
#ISCELL
  standard tap *
  page105_i89
#ISCELL
  standard offpage *
  page105_i9
#ISCELL
  standard tap *
  page105_i90
#ISCELL
  standard tap *
  page105_i91
#ISCELL
  standard tap *
  page105_i92
#ISCELL
  standard tap *
  page105_i93
#ISCELL
  standard tap *
  page105_i94
#ISCELL
  standard tap *
  page105_i95
#ISCELL
  standard tap *
  page105_i96
#ISCELL
  standard tap *
  page105_i97
#ISCELL
  standard tap *
  page105_i98
#ISCELL
  standard tap *
  page105_i99
#ISCELL
  logical_power cad_note *
  *
#ISCELL
  pure_quanta quanta_title_block_c *
  *
#ISCELL
  logical_power universal_gnd *
  page106_i1
#ISCELL
  standard offpage *
  page106_i10
#ISCELL
  standard tap *
  page106_i100
#ISCELL
  standard tap *
  page106_i101
#ISCELL
  standard tap *
  page106_i102
#ISCELL
  standard tap *
  page106_i103
#ISCELL
  standard tap *
  page106_i104
#ISCELL
  standard tap *
  page106_i105
#ISCELL
  standard tap *
  page106_i106
#ISCELL
  standard tap *
  page106_i107
#ISCELL
  standard tap *
  page106_i108
#ISCELL
  standard tap *
  page106_i109
#ISCELL
  standard offpage *
  page106_i11
#ISCELL
  standard tap *
  page106_i110
#ISCELL
  standard tap *
  page106_i111
#ISCELL
  standard tap *
  page106_i112
#ISCELL
  standard tap *
  page106_i113
#ISCELL
  standard tap *
  page106_i114
#ISCELL
  standard tap *
  page106_i115
#ISCELL
  standard tap *
  page106_i116
#ISCELL
  standard tap *
  page106_i117
#ISCELL
  standard tap *
  page106_i118
#ISCELL
  standard tap *
  page106_i119
#ISCELL
  logical_power vcc_core *
  page106_i12
#ISCELL
  logical_power universal_gnd *
  page106_i120
#ISCELL
  logical_power universal_gnd *
  page106_i121
#CELL
  pure_quanta q_cap *
  page106_i122
#ISCELL
  logical_power vcc_core *
  page106_i123
#ISCELL
  standard offpage *
  page106_i124
#ISCELL
  standard offpage *
  page106_i125
#CELL
  pure_quanta q_cap *
  page106_i127
#ISCELL
  logical_power vcc_core *
  page106_i128
#ISCELL
  standard tap *
  page106_i129
#ISCELL
  standard offpage *
  page106_i13
#CELL
  pure_quanta q_cap *
  page106_i130
#ISCELL
  standard tap *
  page106_i131
#ISCELL
  standard tap *
  page106_i132
#ISCELL
  standard tap *
  page106_i133
#ISCELL
  standard tap *
  page106_i134
#ISCELL
  standard tap *
  page106_i135
#ISCELL
  standard tap *
  page106_i136
#ISCELL
  standard tap *
  page106_i137
#ISCELL
  standard tap *
  page106_i138
#ISCELL
  standard tap *
  page106_i139
#ISCELL
  standard offpage *
  page106_i14
#ISCELL
  standard tap *
  page106_i140
#ISCELL
  standard tap *
  page106_i141
#ISCELL
  standard tap *
  page106_i142
#ISCELL
  standard tap *
  page106_i143
#ISCELL
  standard tap *
  page106_i144
#ISCELL
  standard tap *
  page106_i145
#ISCELL
  standard tap *
  page106_i146
#ISCELL
  standard tap *
  page106_i147
#ISCELL
  standard tap *
  page106_i148
#ISCELL
  standard tap *
  page106_i149
#ISCELL
  standard offpage *
  page106_i15
#ISCELL
  standard tap *
  page106_i150
#ISCELL
  standard tap *
  page106_i151
#ISCELL
  standard tap *
  page106_i152
#ISCELL
  standard tap *
  page106_i153
#ISCELL
  standard tap *
  page106_i154
#ISCELL
  standard tap *
  page106_i155
#ISCELL
  standard tap *
  page106_i156
#ISCELL
  standard tap *
  page106_i157
#ISCELL
  standard tap *
  page106_i158
#ISCELL
  standard tap *
  page106_i159
#ISCELL
  standard offpage *
  page106_i16
#ISCELL
  standard tap *
  page106_i160
#ISCELL
  standard tap *
  page106_i161
#ISCELL
  standard tap *
  page106_i162
#ISCELL
  standard tap *
  page106_i163
#ISCELL
  standard tap *
  page106_i164
#ISCELL
  standard tap *
  page106_i165
#ISCELL
  standard tap *
  page106_i166
#ISCELL
  standard tap *
  page106_i167
#ISCELL
  standard tap *
  page106_i168
#ISCELL
  standard tap *
  page106_i169
#ISCELL
  standard offpage *
  page106_i17
#ISCELL
  standard offpage *
  page106_i170
#ISCELL
  standard offpage *
  page106_i171
#ISCELL
  standard offpage *
  page106_i172
#ISCELL
  standard offpage *
  page106_i173
#ISCELL
  logical_power universal_gnd *
  page106_i174
#ISCELL
  logical_power universal_gnd *
  page106_i176
#ISCELL
  logical_power vcc_core *
  page106_i177
#CELL
  pure_quanta sconn288_adr50017p130cc *
  page106_i178
#ISCELL
  standard offpage *
  page106_i18
#CELL
  pure_quanta sconn288_adr50017p130cc *
  page106_i180
#CELL
  pure_quanta sconn288_adr50017p130cc *
  page106_i181
#ISCELL
  standard offpage *
  page106_i182
#CELL
  pure_quanta q_res *
  page106_i183
#ISCELL
  standard offpage *
  page106_i19
#CELL
  pure_quanta q_res *
  page106_i2
#ISCELL
  standard offpage *
  page106_i20
#ISCELL
  standard offpage *
  page106_i21
#ISCELL
  standard offpage *
  page106_i22
#ISCELL
  standard offpage *
  page106_i23
#ISCELL
  standard offpage *
  page106_i24
#ISCELL
  standard tap *
  page106_i26
#ISCELL
  standard tap *
  page106_i27
#ISCELL
  standard tap *
  page106_i28
#ISCELL
  standard tap *
  page106_i29
#ISCELL
  standard offpage *
  page106_i3
#ISCELL
  standard tap *
  page106_i30
#ISCELL
  standard tap *
  page106_i31
#ISCELL
  standard tap *
  page106_i32
#ISCELL
  standard tap *
  page106_i33
#ISCELL
  standard tap *
  page106_i34
#ISCELL
  standard tap *
  page106_i35
#ISCELL
  standard tap *
  page106_i36
#ISCELL
  standard tap *
  page106_i37
#ISCELL
  standard tap *
  page106_i38
#ISCELL
  standard tap *
  page106_i39
#ISCELL
  standard offpage *
  page106_i4
#ISCELL
  standard tap *
  page106_i40
#ISCELL
  standard tap *
  page106_i41
#ISCELL
  standard tap *
  page106_i42
#ISCELL
  standard tap *
  page106_i43
#ISCELL
  standard tap *
  page106_i44
#ISCELL
  standard tap *
  page106_i45
#ISCELL
  standard tap *
  page106_i46
#ISCELL
  standard tap *
  page106_i47
#ISCELL
  standard tap *
  page106_i48
#ISCELL
  standard tap *
  page106_i49
#ISCELL
  standard offpage *
  page106_i5
#ISCELL
  standard tap *
  page106_i50
#ISCELL
  standard tap *
  page106_i51
#ISCELL
  standard tap *
  page106_i52
#ISCELL
  standard tap *
  page106_i53
#ISCELL
  standard tap *
  page106_i54
#ISCELL
  standard tap *
  page106_i55
#ISCELL
  standard tap *
  page106_i56
#ISCELL
  standard tap *
  page106_i57
#ISCELL
  standard tap *
  page106_i58
#ISCELL
  standard tap *
  page106_i59
#ISCELL
  standard offpage *
  page106_i6
#ISCELL
  standard tap *
  page106_i60
#ISCELL
  standard tap *
  page106_i61
#ISCELL
  standard tap *
  page106_i62
#ISCELL
  standard tap *
  page106_i63
#ISCELL
  standard tap *
  page106_i64
#ISCELL
  standard tap *
  page106_i65
#ISCELL
  standard tap *
  page106_i66
#ISCELL
  standard tap *
  page106_i67
#ISCELL
  standard tap *
  page106_i68
#ISCELL
  standard tap *
  page106_i69
#ISCELL
  standard offpage *
  page106_i7
#ISCELL
  standard tap *
  page106_i70
#ISCELL
  standard tap *
  page106_i71
#ISCELL
  standard tap *
  page106_i72
#ISCELL
  standard tap *
  page106_i73
#ISCELL
  standard tap *
  page106_i74
#ISCELL
  standard tap *
  page106_i75
#ISCELL
  standard tap *
  page106_i76
#ISCELL
  standard tap *
  page106_i77
#ISCELL
  standard tap *
  page106_i78
#ISCELL
  standard tap *
  page106_i79
#ISCELL
  standard tap *
  page106_i80
#ISCELL
  standard tap *
  page106_i81
#ISCELL
  standard tap *
  page106_i82
#ISCELL
  standard tap *
  page106_i83
#ISCELL
  standard tap *
  page106_i84
#ISCELL
  standard tap *
  page106_i85
#ISCELL
  standard tap *
  page106_i86
#ISCELL
  standard tap *
  page106_i87
#ISCELL
  standard tap *
  page106_i88
#ISCELL
  standard tap *
  page106_i89
#ISCELL
  standard offpage *
  page106_i9
#ISCELL
  standard tap *
  page106_i90
#ISCELL
  standard tap *
  page106_i91
#ISCELL
  standard tap *
  page106_i92
#ISCELL
  standard tap *
  page106_i93
#ISCELL
  standard tap *
  page106_i94
#ISCELL
  standard tap *
  page106_i95
#ISCELL
  standard tap *
  page106_i96
#ISCELL
  standard tap *
  page106_i97
#ISCELL
  standard tap *
  page106_i98
#ISCELL
  standard tap *
  page106_i99
#ISCELL
  logical_power cad_note *
  *
#ISCELL
  pure_quanta quanta_title_block_c *
  *
#ISCELL
  logical_power universal_gnd *
  page107_i1
#ISCELL
  standard offpage *
  page107_i10
#ISCELL
  standard tap *
  page107_i100
#ISCELL
  standard tap *
  page107_i101
#ISCELL
  standard tap *
  page107_i102
#ISCELL
  standard tap *
  page107_i103
#ISCELL
  standard tap *
  page107_i104
#ISCELL
  standard tap *
  page107_i105
#ISCELL
  standard tap *
  page107_i106
#ISCELL
  standard tap *
  page107_i107
#ISCELL
  standard tap *
  page107_i108
#ISCELL
  standard tap *
  page107_i109
#ISCELL
  standard offpage *
  page107_i11
#ISCELL
  standard tap *
  page107_i110
#ISCELL
  standard tap *
  page107_i111
#ISCELL
  standard tap *
  page107_i112
#ISCELL
  standard tap *
  page107_i113
#ISCELL
  standard tap *
  page107_i114
#ISCELL
  standard tap *
  page107_i115
#ISCELL
  standard tap *
  page107_i116
#ISCELL
  standard offpage *
  page107_i117
#ISCELL
  standard tap *
  page107_i118
#ISCELL
  standard tap *
  page107_i119
#ISCELL
  logical_power vcc_core *
  page107_i12
#ISCELL
  logical_power universal_gnd *
  page107_i120
#ISCELL
  logical_power universal_gnd *
  page107_i121
#CELL
  pure_quanta q_cap *
  page107_i122
#ISCELL
  logical_power vcc_core *
  page107_i123
#ISCELL
  standard offpage *
  page107_i124
#CELL
  pure_quanta q_cap *
  page107_i126
#ISCELL
  logical_power vcc_core *
  page107_i127
#CELL
  pure_quanta q_cap *
  page107_i128
#ISCELL
  standard tap *
  page107_i129
#ISCELL
  standard offpage *
  page107_i13
#ISCELL
  standard tap *
  page107_i130
#ISCELL
  standard tap *
  page107_i131
#ISCELL
  standard tap *
  page107_i132
#ISCELL
  standard tap *
  page107_i133
#ISCELL
  standard tap *
  page107_i134
#ISCELL
  standard tap *
  page107_i135
#ISCELL
  standard tap *
  page107_i136
#ISCELL
  standard tap *
  page107_i137
#ISCELL
  standard tap *
  page107_i138
#ISCELL
  standard tap *
  page107_i139
#ISCELL
  standard offpage *
  page107_i14
#ISCELL
  standard tap *
  page107_i140
#ISCELL
  standard tap *
  page107_i141
#ISCELL
  standard tap *
  page107_i142
#ISCELL
  standard tap *
  page107_i143
#ISCELL
  standard tap *
  page107_i144
#ISCELL
  standard tap *
  page107_i145
#ISCELL
  standard tap *
  page107_i146
#ISCELL
  standard tap *
  page107_i147
#ISCELL
  standard tap *
  page107_i148
#ISCELL
  standard tap *
  page107_i149
#ISCELL
  standard offpage *
  page107_i15
#ISCELL
  standard tap *
  page107_i150
#ISCELL
  standard tap *
  page107_i151
#ISCELL
  standard tap *
  page107_i152
#ISCELL
  standard tap *
  page107_i153
#ISCELL
  standard tap *
  page107_i154
#ISCELL
  standard tap *
  page107_i155
#ISCELL
  standard tap *
  page107_i156
#ISCELL
  standard tap *
  page107_i157
#ISCELL
  standard tap *
  page107_i158
#ISCELL
  standard tap *
  page107_i159
#ISCELL
  standard offpage *
  page107_i16
#ISCELL
  standard tap *
  page107_i160
#ISCELL
  standard tap *
  page107_i161
#ISCELL
  standard tap *
  page107_i162
#ISCELL
  standard tap *
  page107_i163
#ISCELL
  standard tap *
  page107_i164
#ISCELL
  standard tap *
  page107_i165
#ISCELL
  standard tap *
  page107_i166
#ISCELL
  standard tap *
  page107_i167
#ISCELL
  standard offpage *
  page107_i168
#ISCELL
  standard offpage *
  page107_i169
#ISCELL
  standard offpage *
  page107_i17
#ISCELL
  standard offpage *
  page107_i170
#ISCELL
  standard offpage *
  page107_i171
#ISCELL
  standard tap *
  page107_i172
#ISCELL
  standard offpage *
  page107_i173
#ISCELL
  logical_power universal_gnd *
  page107_i174
#ISCELL
  logical_power universal_gnd *
  page107_i176
#ISCELL
  logical_power vcc_core *
  page107_i177
#CELL
  pure_quanta sconn288_adr50017p087cc *
  page107_i179
#ISCELL
  standard offpage *
  page107_i18
#CELL
  pure_quanta sconn288_adr50017p087cc *
  page107_i180
#CELL
  pure_quanta sconn288_adr50017p087cc *
  page107_i181
#ISCELL
  standard offpage *
  page107_i182
#CELL
  pure_quanta q_res *
  page107_i183
#ISCELL
  standard offpage *
  page107_i19
#CELL
  pure_quanta q_res *
  page107_i2
#ISCELL
  standard offpage *
  page107_i20
#ISCELL
  standard offpage *
  page107_i21
#ISCELL
  standard offpage *
  page107_i22
#ISCELL
  standard offpage *
  page107_i23
#ISCELL
  standard tap *
  page107_i25
#ISCELL
  standard tap *
  page107_i26
#ISCELL
  standard tap *
  page107_i27
#ISCELL
  standard tap *
  page107_i28
#ISCELL
  standard tap *
  page107_i29
#ISCELL
  standard offpage *
  page107_i3
#ISCELL
  standard tap *
  page107_i30
#ISCELL
  standard tap *
  page107_i31
#ISCELL
  standard tap *
  page107_i32
#ISCELL
  standard tap *
  page107_i33
#ISCELL
  standard tap *
  page107_i34
#ISCELL
  standard tap *
  page107_i35
#ISCELL
  standard tap *
  page107_i36
#ISCELL
  standard tap *
  page107_i37
#ISCELL
  standard tap *
  page107_i38
#ISCELL
  standard tap *
  page107_i39
#ISCELL
  standard offpage *
  page107_i4
#ISCELL
  standard tap *
  page107_i40
#ISCELL
  standard tap *
  page107_i41
#ISCELL
  standard tap *
  page107_i42
#ISCELL
  standard tap *
  page107_i43
#ISCELL
  standard tap *
  page107_i44
#ISCELL
  standard tap *
  page107_i45
#ISCELL
  standard tap *
  page107_i46
#ISCELL
  standard tap *
  page107_i47
#ISCELL
  standard tap *
  page107_i48
#ISCELL
  standard tap *
  page107_i49
#ISCELL
  standard offpage *
  page107_i5
#ISCELL
  standard tap *
  page107_i50
#ISCELL
  standard tap *
  page107_i51
#ISCELL
  standard tap *
  page107_i52
#ISCELL
  standard tap *
  page107_i53
#ISCELL
  standard tap *
  page107_i54
#ISCELL
  standard tap *
  page107_i55
#ISCELL
  standard tap *
  page107_i56
#ISCELL
  standard tap *
  page107_i57
#ISCELL
  standard tap *
  page107_i58
#ISCELL
  standard tap *
  page107_i59
#ISCELL
  standard offpage *
  page107_i6
#ISCELL
  standard tap *
  page107_i60
#ISCELL
  standard tap *
  page107_i61
#ISCELL
  standard tap *
  page107_i62
#ISCELL
  standard tap *
  page107_i63
#ISCELL
  standard tap *
  page107_i64
#ISCELL
  standard tap *
  page107_i65
#ISCELL
  standard tap *
  page107_i66
#ISCELL
  standard tap *
  page107_i67
#ISCELL
  standard tap *
  page107_i68
#ISCELL
  standard tap *
  page107_i69
#ISCELL
  standard tap *
  page107_i70
#ISCELL
  standard tap *
  page107_i71
#ISCELL
  standard tap *
  page107_i72
#ISCELL
  standard tap *
  page107_i73
#ISCELL
  standard tap *
  page107_i74
#ISCELL
  standard tap *
  page107_i75
#ISCELL
  standard tap *
  page107_i76
#ISCELL
  standard tap *
  page107_i77
#ISCELL
  standard tap *
  page107_i78
#ISCELL
  standard tap *
  page107_i79
#ISCELL
  standard offpage *
  page107_i8
#ISCELL
  standard tap *
  page107_i80
#ISCELL
  standard tap *
  page107_i81
#ISCELL
  standard tap *
  page107_i82
#ISCELL
  standard tap *
  page107_i83
#ISCELL
  standard tap *
  page107_i84
#ISCELL
  standard tap *
  page107_i85
#ISCELL
  standard tap *
  page107_i86
#ISCELL
  standard tap *
  page107_i87
#ISCELL
  standard tap *
  page107_i88
#ISCELL
  standard tap *
  page107_i89
#ISCELL
  standard offpage *
  page107_i9
#ISCELL
  standard tap *
  page107_i90
#ISCELL
  standard tap *
  page107_i91
#ISCELL
  standard tap *
  page107_i92
#ISCELL
  standard tap *
  page107_i93
#ISCELL
  standard tap *
  page107_i94
#ISCELL
  standard tap *
  page107_i95
#ISCELL
  standard tap *
  page107_i96
#ISCELL
  standard tap *
  page107_i97
#ISCELL
  standard tap *
  page107_i98
#ISCELL
  standard tap *
  page107_i99
#ISCELL
  logical_power cad_note *
  *
#ISCELL
  pure_quanta quanta_title_block_c *
  *
#ISCELL
  standard offpage *
  page108_i1
#CELL
  pure_quanta q_res *
  page108_i10
#ISCELL
  standard tap *
  page108_i100
#ISCELL
  standard tap *
  page108_i101
#ISCELL
  standard tap *
  page108_i102
#ISCELL
  standard offpage *
  page108_i103
#ISCELL
  standard offpage *
  page108_i104
#ISCELL
  standard tap *
  page108_i105
#ISCELL
  standard tap *
  page108_i106
#ISCELL
  standard tap *
  page108_i107
#ISCELL
  standard tap *
  page108_i108
#ISCELL
  standard tap *
  page108_i109
#ISCELL
  standard offpage *
  page108_i11
#ISCELL
  standard tap *
  page108_i110
#ISCELL
  standard tap *
  page108_i111
#ISCELL
  standard tap *
  page108_i112
#ISCELL
  standard tap *
  page108_i113
#ISCELL
  standard tap *
  page108_i114
#ISCELL
  standard tap *
  page108_i115
#ISCELL
  standard tap *
  page108_i116
#ISCELL
  standard tap *
  page108_i117
#ISCELL
  standard tap *
  page108_i118
#ISCELL
  standard offpage *
  page108_i119
#ISCELL
  standard offpage *
  page108_i12
#ISCELL
  logical_power universal_gnd *
  page108_i120
#CELL
  pure_quanta q_cap *
  page108_i121
#ISCELL
  logical_power vcc_core *
  page108_i122
#CELL
  pure_quanta q_cap *
  page108_i123
#ISCELL
  logical_power vcc_core *
  page108_i124
#ISCELL
  standard tap *
  page108_i126
#ISCELL
  standard tap *
  page108_i127
#ISCELL
  standard tap *
  page108_i128
#ISCELL
  standard tap *
  page108_i129
#ISCELL
  standard offpage *
  page108_i13
#ISCELL
  standard tap *
  page108_i130
#ISCELL
  standard tap *
  page108_i131
#ISCELL
  standard tap *
  page108_i132
#ISCELL
  standard tap *
  page108_i133
#ISCELL
  standard tap *
  page108_i134
#ISCELL
  standard tap *
  page108_i135
#ISCELL
  standard tap *
  page108_i136
#ISCELL
  standard tap *
  page108_i137
#ISCELL
  standard tap *
  page108_i138
#ISCELL
  standard tap *
  page108_i139
#ISCELL
  standard offpage *
  page108_i14
#ISCELL
  standard tap *
  page108_i140
#ISCELL
  standard tap *
  page108_i141
#ISCELL
  standard tap *
  page108_i142
#ISCELL
  standard tap *
  page108_i143
#ISCELL
  standard tap *
  page108_i144
#ISCELL
  standard tap *
  page108_i145
#ISCELL
  standard tap *
  page108_i146
#ISCELL
  standard tap *
  page108_i147
#ISCELL
  standard tap *
  page108_i148
#ISCELL
  standard tap *
  page108_i149
#ISCELL
  logical_power vcc_core *
  page108_i15
#ISCELL
  standard tap *
  page108_i150
#ISCELL
  standard tap *
  page108_i151
#ISCELL
  standard tap *
  page108_i152
#ISCELL
  standard tap *
  page108_i153
#ISCELL
  standard tap *
  page108_i154
#ISCELL
  standard tap *
  page108_i155
#ISCELL
  standard tap *
  page108_i156
#ISCELL
  standard tap *
  page108_i157
#ISCELL
  standard tap *
  page108_i158
#ISCELL
  logical_power universal_gnd *
  page108_i159
#ISCELL
  standard offpage *
  page108_i16
#CELL
  pure_quanta q_cap *
  page108_i160
#ISCELL
  logical_power universal_gnd *
  page108_i161
#ISCELL
  standard offpage *
  page108_i163
#ISCELL
  standard offpage *
  page108_i164
#ISCELL
  standard tap *
  page108_i165
#ISCELL
  standard tap *
  page108_i166
#ISCELL
  standard tap *
  page108_i167
#ISCELL
  standard tap *
  page108_i168
#ISCELL
  standard tap *
  page108_i169
#ISCELL
  standard offpage *
  page108_i17
#ISCELL
  standard tap *
  page108_i170
#ISCELL
  standard tap *
  page108_i171
#ISCELL
  standard offpage *
  page108_i172
#ISCELL
  standard offpage *
  page108_i173
#ISCELL
  logical_power vcc_core *
  page108_i174
#ISCELL
  logical_power universal_gnd *
  page108_i175
#ISCELL
  standard tap *
  page108_i176
#CELL
  pure_quanta sconn288_adr50017p130cc *
  page108_i178
#CELL
  pure_quanta sconn288_adr50017p130cc *
  page108_i179
#ISCELL
  standard offpage *
  page108_i18
#CELL
  pure_quanta sconn288_adr50017p130cc *
  page108_i180
#ISCELL
  standard offpage *
  page108_i181
#CELL
  pure_quanta q_res *
  page108_i182
#ISCELL
  standard offpage *
  page108_i19
#ISCELL
  standard offpage *
  page108_i2
#ISCELL
  standard offpage *
  page108_i20
#ISCELL
  standard offpage *
  page108_i21
#ISCELL
  standard offpage *
  page108_i22
#ISCELL
  standard offpage *
  page108_i23
#ISCELL
  standard tap *
  page108_i24
#ISCELL
  standard tap *
  page108_i25
#ISCELL
  standard tap *
  page108_i26
#ISCELL
  standard tap *
  page108_i27
#ISCELL
  standard tap *
  page108_i28
#ISCELL
  standard tap *
  page108_i29
#ISCELL
  standard offpage *
  page108_i3
#ISCELL
  standard tap *
  page108_i30
#ISCELL
  standard tap *
  page108_i31
#ISCELL
  standard tap *
  page108_i32
#ISCELL
  standard tap *
  page108_i33
#ISCELL
  standard tap *
  page108_i34
#ISCELL
  standard tap *
  page108_i35
#ISCELL
  standard tap *
  page108_i36
#ISCELL
  standard tap *
  page108_i37
#ISCELL
  standard tap *
  page108_i38
#ISCELL
  standard tap *
  page108_i39
#ISCELL
  standard offpage *
  page108_i4
#ISCELL
  standard tap *
  page108_i40
#ISCELL
  standard tap *
  page108_i41
#ISCELL
  standard tap *
  page108_i42
#ISCELL
  standard tap *
  page108_i43
#ISCELL
  standard tap *
  page108_i44
#ISCELL
  standard tap *
  page108_i45
#ISCELL
  standard tap *
  page108_i46
#ISCELL
  standard tap *
  page108_i47
#ISCELL
  standard tap *
  page108_i48
#ISCELL
  standard tap *
  page108_i49
#ISCELL
  standard tap *
  page108_i50
#ISCELL
  standard tap *
  page108_i51
#ISCELL
  standard tap *
  page108_i52
#ISCELL
  standard tap *
  page108_i53
#ISCELL
  standard tap *
  page108_i54
#ISCELL
  standard tap *
  page108_i55
#ISCELL
  standard tap *
  page108_i56
#ISCELL
  standard tap *
  page108_i57
#ISCELL
  standard tap *
  page108_i58
#ISCELL
  standard tap *
  page108_i59
#ISCELL
  standard offpage *
  page108_i6
#ISCELL
  standard tap *
  page108_i60
#ISCELL
  standard tap *
  page108_i61
#ISCELL
  standard tap *
  page108_i62
#ISCELL
  standard tap *
  page108_i63
#ISCELL
  standard tap *
  page108_i64
#ISCELL
  standard tap *
  page108_i65
#ISCELL
  standard tap *
  page108_i66
#ISCELL
  standard tap *
  page108_i67
#ISCELL
  standard tap *
  page108_i68
#ISCELL
  standard tap *
  page108_i69
#ISCELL
  standard offpage *
  page108_i7
#ISCELL
  standard tap *
  page108_i70
#ISCELL
  standard tap *
  page108_i71
#ISCELL
  standard tap *
  page108_i72
#ISCELL
  standard tap *
  page108_i73
#ISCELL
  standard tap *
  page108_i74
#ISCELL
  standard tap *
  page108_i75
#ISCELL
  standard tap *
  page108_i76
#ISCELL
  standard tap *
  page108_i77
#ISCELL
  standard tap *
  page108_i78
#ISCELL
  standard tap *
  page108_i79
#ISCELL
  standard offpage *
  page108_i8
#ISCELL
  standard tap *
  page108_i80
#ISCELL
  standard tap *
  page108_i81
#ISCELL
  standard tap *
  page108_i82
#ISCELL
  standard tap *
  page108_i83
#ISCELL
  standard tap *
  page108_i84
#ISCELL
  standard tap *
  page108_i85
#ISCELL
  standard tap *
  page108_i86
#ISCELL
  standard tap *
  page108_i87
#ISCELL
  standard tap *
  page108_i88
#ISCELL
  standard tap *
  page108_i89
#ISCELL
  logical_power universal_gnd *
  page108_i9
#ISCELL
  standard tap *
  page108_i90
#ISCELL
  standard tap *
  page108_i91
#ISCELL
  standard tap *
  page108_i92
#ISCELL
  standard tap *
  page108_i93
#ISCELL
  standard tap *
  page108_i94
#ISCELL
  standard tap *
  page108_i95
#ISCELL
  standard tap *
  page108_i96
#ISCELL
  standard tap *
  page108_i97
#ISCELL
  standard tap *
  page108_i98
#ISCELL
  standard tap *
  page108_i99
#ISCELL
  logical_power cad_note *
  *
#ISCELL
  pure_quanta quanta_title_block_c *
  *
#ISCELL
  standard offpage *
  page109_i1
#ISCELL
  standard offpage *
  page109_i10
#ISCELL
  standard tap *
  page109_i100
#ISCELL
  standard tap *
  page109_i101
#ISCELL
  standard tap *
  page109_i102
#ISCELL
  standard tap *
  page109_i103
#ISCELL
  standard tap *
  page109_i104
#ISCELL
  standard offpage *
  page109_i105
#ISCELL
  standard tap *
  page109_i106
#ISCELL
  standard tap *
  page109_i107
#ISCELL
  standard tap *
  page109_i108
#ISCELL
  standard tap *
  page109_i109
#ISCELL
  standard offpage *
  page109_i11
#ISCELL
  standard tap *
  page109_i110
#ISCELL
  standard tap *
  page109_i111
#ISCELL
  standard tap *
  page109_i112
#ISCELL
  standard tap *
  page109_i113
#ISCELL
  standard tap *
  page109_i114
#ISCELL
  standard tap *
  page109_i115
#ISCELL
  standard tap *
  page109_i116
#ISCELL
  standard tap *
  page109_i117
#ISCELL
  standard tap *
  page109_i118
#ISCELL
  standard tap *
  page109_i119
#ISCELL
  standard offpage *
  page109_i12
#ISCELL
  logical_power universal_gnd *
  page109_i120
#CELL
  pure_quanta q_cap *
  page109_i121
#ISCELL
  logical_power vcc_core *
  page109_i122
#ISCELL
  standard offpage *
  page109_i123
#CELL
  pure_quanta q_cap *
  page109_i125
#ISCELL
  logical_power vcc_core *
  page109_i126
#ISCELL
  logical_power universal_gnd *
  page109_i127
#CELL
  pure_quanta q_cap *
  page109_i128
#ISCELL
  logical_power universal_gnd *
  page109_i129
#ISCELL
  standard offpage *
  page109_i13
#ISCELL
  standard tap *
  page109_i130
#ISCELL
  standard tap *
  page109_i131
#ISCELL
  standard tap *
  page109_i132
#ISCELL
  standard tap *
  page109_i133
#ISCELL
  standard tap *
  page109_i134
#ISCELL
  standard tap *
  page109_i135
#ISCELL
  standard tap *
  page109_i136
#ISCELL
  standard tap *
  page109_i137
#ISCELL
  standard tap *
  page109_i138
#ISCELL
  standard tap *
  page109_i139
#ISCELL
  standard offpage *
  page109_i14
#ISCELL
  standard tap *
  page109_i140
#ISCELL
  standard tap *
  page109_i141
#ISCELL
  standard tap *
  page109_i142
#ISCELL
  standard tap *
  page109_i143
#ISCELL
  standard tap *
  page109_i144
#ISCELL
  standard tap *
  page109_i145
#ISCELL
  standard tap *
  page109_i146
#ISCELL
  standard tap *
  page109_i147
#ISCELL
  standard tap *
  page109_i148
#ISCELL
  standard tap *
  page109_i149
#ISCELL
  standard offpage *
  page109_i15
#ISCELL
  standard tap *
  page109_i150
#ISCELL
  standard tap *
  page109_i151
#ISCELL
  standard tap *
  page109_i152
#ISCELL
  standard tap *
  page109_i153
#ISCELL
  standard tap *
  page109_i154
#ISCELL
  standard tap *
  page109_i155
#ISCELL
  standard tap *
  page109_i156
#ISCELL
  standard tap *
  page109_i157
#ISCELL
  standard tap *
  page109_i158
#ISCELL
  standard tap *
  page109_i159
#ISCELL
  standard offpage *
  page109_i16
#ISCELL
  standard tap *
  page109_i160
#ISCELL
  standard tap *
  page109_i161
#ISCELL
  standard tap *
  page109_i162
#ISCELL
  standard offpage *
  page109_i163
#ISCELL
  standard offpage *
  page109_i164
#ISCELL
  standard offpage *
  page109_i165
#ISCELL
  standard tap *
  page109_i166
#ISCELL
  standard tap *
  page109_i167
#ISCELL
  standard tap *
  page109_i168
#ISCELL
  standard tap *
  page109_i169
#ISCELL
  standard offpage *
  page109_i17
#ISCELL
  standard tap *
  page109_i170
#ISCELL
  standard tap *
  page109_i171
#ISCELL
  standard tap *
  page109_i172
#ISCELL
  standard offpage *
  page109_i173
#ISCELL
  standard offpage *
  page109_i174
#ISCELL
  logical_power vcc_core *
  page109_i175
#CELL
  pure_quanta sconn288_adr50017p087cc *
  page109_i176
#ISCELL
  logical_power universal_gnd *
  page109_i177
#CELL
  pure_quanta sconn288_adr50017p087cc *
  page109_i178
#ISCELL
  standard offpage *
  page109_i179
#ISCELL
  standard offpage *
  page109_i18
#CELL
  pure_quanta q_res *
  page109_i180
#ISCELL
  standard offpage *
  page109_i19
#ISCELL
  standard offpage *
  page109_i2
#ISCELL
  standard offpage *
  page109_i20
#ISCELL
  logical_power vcc_core *
  page109_i21
#ISCELL
  standard tap *
  page109_i22
#ISCELL
  standard tap *
  page109_i23
#ISCELL
  standard tap *
  page109_i24
#ISCELL
  standard tap *
  page109_i25
#ISCELL
  standard tap *
  page109_i26
#ISCELL
  standard tap *
  page109_i27
#ISCELL
  standard tap *
  page109_i28
#ISCELL
  standard tap *
  page109_i29
#ISCELL
  standard offpage *
  page109_i3
#ISCELL
  standard tap *
  page109_i30
#ISCELL
  standard tap *
  page109_i31
#ISCELL
  standard tap *
  page109_i32
#ISCELL
  standard tap *
  page109_i33
#ISCELL
  standard tap *
  page109_i34
#ISCELL
  standard tap *
  page109_i35
#ISCELL
  standard tap *
  page109_i36
#ISCELL
  standard tap *
  page109_i37
#ISCELL
  standard tap *
  page109_i38
#ISCELL
  standard tap *
  page109_i39
#ISCELL
  standard offpage *
  page109_i4
#ISCELL
  standard tap *
  page109_i40
#ISCELL
  standard tap *
  page109_i41
#ISCELL
  standard tap *
  page109_i42
#ISCELL
  standard tap *
  page109_i43
#ISCELL
  standard tap *
  page109_i44
#ISCELL
  logical_power universal_gnd *
  page109_i45
#CELL
  pure_quanta q_res *
  page109_i46
#CELL
  pure_quanta sconn288_adr50017p087cc *
  page109_i47
#ISCELL
  standard tap *
  page109_i48
#ISCELL
  standard tap *
  page109_i49
#ISCELL
  standard tap *
  page109_i50
#ISCELL
  standard tap *
  page109_i51
#ISCELL
  standard tap *
  page109_i52
#ISCELL
  standard tap *
  page109_i53
#ISCELL
  standard tap *
  page109_i54
#ISCELL
  standard tap *
  page109_i55
#ISCELL
  standard tap *
  page109_i56
#ISCELL
  standard tap *
  page109_i57
#ISCELL
  standard tap *
  page109_i58
#ISCELL
  standard tap *
  page109_i59
#ISCELL
  standard offpage *
  page109_i6
#ISCELL
  standard tap *
  page109_i60
#ISCELL
  standard tap *
  page109_i61
#ISCELL
  standard tap *
  page109_i62
#ISCELL
  standard tap *
  page109_i63
#ISCELL
  standard tap *
  page109_i64
#ISCELL
  standard tap *
  page109_i65
#ISCELL
  standard tap *
  page109_i66
#ISCELL
  standard tap *
  page109_i67
#ISCELL
  standard tap *
  page109_i68
#ISCELL
  standard tap *
  page109_i69
#ISCELL
  standard offpage *
  page109_i7
#ISCELL
  standard tap *
  page109_i70
#ISCELL
  standard tap *
  page109_i71
#ISCELL
  standard tap *
  page109_i72
#ISCELL
  standard tap *
  page109_i73
#ISCELL
  standard tap *
  page109_i74
#ISCELL
  standard tap *
  page109_i75
#ISCELL
  standard tap *
  page109_i76
#ISCELL
  standard tap *
  page109_i77
#ISCELL
  standard tap *
  page109_i78
#ISCELL
  standard tap *
  page109_i79
#ISCELL
  standard offpage *
  page109_i8
#ISCELL
  standard tap *
  page109_i80
#ISCELL
  standard tap *
  page109_i81
#ISCELL
  standard tap *
  page109_i82
#ISCELL
  standard tap *
  page109_i83
#ISCELL
  standard tap *
  page109_i84
#ISCELL
  standard tap *
  page109_i85
#ISCELL
  standard tap *
  page109_i86
#ISCELL
  standard tap *
  page109_i87
#ISCELL
  standard tap *
  page109_i88
#ISCELL
  standard tap *
  page109_i89
#ISCELL
  standard offpage *
  page109_i9
#ISCELL
  standard tap *
  page109_i90
#ISCELL
  standard tap *
  page109_i91
#ISCELL
  standard tap *
  page109_i92
#ISCELL
  standard tap *
  page109_i93
#ISCELL
  standard tap *
  page109_i94
#ISCELL
  standard tap *
  page109_i95
#ISCELL
  standard tap *
  page109_i96
#ISCELL
  standard tap *
  page109_i97
#ISCELL
  standard tap *
  page109_i98
#ISCELL
  standard tap *
  page109_i99
#ISCELL
  logical_power cad_note *
  *
#ISCELL
  pure_quanta quanta_title_block_c *
  *
#ISCELL
  logical_power universal_gnd *
  page110_i1
#ISCELL
  standard offpage *
  page110_i10
#ISCELL
  standard tap *
  page110_i100
#ISCELL
  standard tap *
  page110_i101
#ISCELL
  standard tap *
  page110_i102
#ISCELL
  standard tap *
  page110_i103
#ISCELL
  standard tap *
  page110_i104
#ISCELL
  standard tap *
  page110_i105
#ISCELL
  standard offpage *
  page110_i106
#ISCELL
  standard tap *
  page110_i107
#ISCELL
  standard tap *
  page110_i108
#ISCELL
  standard tap *
  page110_i109
#ISCELL
  standard offpage *
  page110_i11
#ISCELL
  standard tap *
  page110_i110
#ISCELL
  standard tap *
  page110_i111
#ISCELL
  standard tap *
  page110_i112
#ISCELL
  standard tap *
  page110_i113
#ISCELL
  standard tap *
  page110_i114
#ISCELL
  standard tap *
  page110_i115
#ISCELL
  standard tap *
  page110_i116
#ISCELL
  standard tap *
  page110_i117
#ISCELL
  standard tap *
  page110_i118
#ISCELL
  logical_power universal_gnd *
  page110_i119
#ISCELL
  standard offpage *
  page110_i12
#CELL
  pure_quanta q_cap *
  page110_i120
#ISCELL
  logical_power vcc_core *
  page110_i121
#ISCELL
  standard offpage *
  page110_i122
#CELL
  pure_quanta q_cap *
  page110_i124
#ISCELL
  logical_power vcc_core *
  page110_i125
#CELL
  pure_quanta q_cap *
  page110_i126
#ISCELL
  logical_power universal_gnd *
  page110_i127
#ISCELL
  logical_power universal_gnd *
  page110_i128
#ISCELL
  standard tap *
  page110_i129
#ISCELL
  standard offpage *
  page110_i13
#ISCELL
  standard tap *
  page110_i130
#ISCELL
  standard tap *
  page110_i131
#ISCELL
  standard tap *
  page110_i132
#ISCELL
  standard tap *
  page110_i133
#ISCELL
  standard tap *
  page110_i134
#ISCELL
  standard tap *
  page110_i135
#ISCELL
  standard tap *
  page110_i136
#ISCELL
  standard tap *
  page110_i137
#ISCELL
  standard tap *
  page110_i138
#ISCELL
  standard tap *
  page110_i139
#ISCELL
  standard offpage *
  page110_i14
#ISCELL
  standard tap *
  page110_i140
#ISCELL
  standard tap *
  page110_i141
#ISCELL
  standard tap *
  page110_i142
#ISCELL
  standard tap *
  page110_i143
#ISCELL
  standard tap *
  page110_i144
#ISCELL
  standard tap *
  page110_i145
#ISCELL
  standard tap *
  page110_i146
#ISCELL
  standard tap *
  page110_i147
#ISCELL
  standard tap *
  page110_i148
#ISCELL
  standard tap *
  page110_i149
#ISCELL
  standard offpage *
  page110_i15
#ISCELL
  standard tap *
  page110_i150
#ISCELL
  standard tap *
  page110_i151
#ISCELL
  standard tap *
  page110_i152
#ISCELL
  standard tap *
  page110_i153
#ISCELL
  standard tap *
  page110_i154
#ISCELL
  standard tap *
  page110_i155
#ISCELL
  standard tap *
  page110_i156
#ISCELL
  standard tap *
  page110_i157
#ISCELL
  standard tap *
  page110_i158
#ISCELL
  standard tap *
  page110_i159
#ISCELL
  standard offpage *
  page110_i16
#ISCELL
  standard tap *
  page110_i160
#ISCELL
  standard tap *
  page110_i161
#ISCELL
  standard tap *
  page110_i162
#ISCELL
  standard offpage *
  page110_i163
#ISCELL
  standard offpage *
  page110_i164
#ISCELL
  standard offpage *
  page110_i165
#ISCELL
  standard tap *
  page110_i166
#ISCELL
  standard tap *
  page110_i167
#ISCELL
  standard tap *
  page110_i168
#ISCELL
  standard tap *
  page110_i169
#ISCELL
  standard offpage *
  page110_i17
#ISCELL
  standard tap *
  page110_i170
#ISCELL
  standard tap *
  page110_i171
#ISCELL
  standard offpage *
  page110_i172
#ISCELL
  standard offpage *
  page110_i173
#ISCELL
  logical_power vcc_core *
  page110_i174
#ISCELL
  logical_power universal_gnd *
  page110_i176
#CELL
  pure_quanta sconn288_adr50017p130cc *
  page110_i178
#CELL
  pure_quanta sconn288_adr50017p130cc *
  page110_i179
#ISCELL
  standard offpage *
  page110_i18
#CELL
  pure_quanta sconn288_adr50017p130cc *
  page110_i180
#ISCELL
  standard offpage *
  page110_i181
#CELL
  pure_quanta q_res *
  page110_i182
#ISCELL
  standard offpage *
  page110_i19
#ISCELL
  standard offpage *
  page110_i2
#ISCELL
  standard offpage *
  page110_i20
#ISCELL
  standard offpage *
  page110_i21
#ISCELL
  logical_power vcc_core *
  page110_i22
#ISCELL
  standard tap *
  page110_i23
#ISCELL
  standard tap *
  page110_i24
#ISCELL
  standard tap *
  page110_i25
#ISCELL
  standard tap *
  page110_i26
#ISCELL
  standard tap *
  page110_i27
#ISCELL
  standard tap *
  page110_i28
#ISCELL
  standard tap *
  page110_i29
#ISCELL
  standard offpage *
  page110_i3
#ISCELL
  standard tap *
  page110_i30
#ISCELL
  standard tap *
  page110_i31
#ISCELL
  standard tap *
  page110_i32
#ISCELL
  standard tap *
  page110_i33
#ISCELL
  standard tap *
  page110_i34
#ISCELL
  standard tap *
  page110_i35
#ISCELL
  standard tap *
  page110_i36
#ISCELL
  standard tap *
  page110_i37
#ISCELL
  standard tap *
  page110_i38
#ISCELL
  standard tap *
  page110_i39
#ISCELL
  standard offpage *
  page110_i4
#ISCELL
  standard tap *
  page110_i40
#ISCELL
  standard tap *
  page110_i41
#ISCELL
  standard tap *
  page110_i42
#ISCELL
  standard tap *
  page110_i43
#ISCELL
  standard tap *
  page110_i44
#ISCELL
  standard tap *
  page110_i45
#ISCELL
  standard tap *
  page110_i46
#CELL
  pure_quanta q_res *
  page110_i47
#ISCELL
  standard tap *
  page110_i48
#ISCELL
  standard tap *
  page110_i49
#ISCELL
  standard offpage *
  page110_i5
#ISCELL
  standard tap *
  page110_i50
#ISCELL
  standard tap *
  page110_i51
#ISCELL
  standard tap *
  page110_i52
#ISCELL
  standard tap *
  page110_i53
#ISCELL
  standard tap *
  page110_i54
#ISCELL
  standard tap *
  page110_i55
#ISCELL
  standard tap *
  page110_i56
#ISCELL
  standard tap *
  page110_i57
#ISCELL
  standard tap *
  page110_i58
#ISCELL
  standard tap *
  page110_i59
#ISCELL
  standard tap *
  page110_i60
#ISCELL
  standard tap *
  page110_i61
#ISCELL
  standard tap *
  page110_i62
#ISCELL
  standard tap *
  page110_i63
#ISCELL
  standard tap *
  page110_i64
#ISCELL
  standard tap *
  page110_i65
#ISCELL
  standard tap *
  page110_i66
#ISCELL
  standard tap *
  page110_i67
#ISCELL
  standard tap *
  page110_i68
#ISCELL
  standard tap *
  page110_i69
#ISCELL
  standard offpage *
  page110_i7
#ISCELL
  standard tap *
  page110_i70
#ISCELL
  standard tap *
  page110_i71
#ISCELL
  standard tap *
  page110_i72
#ISCELL
  standard tap *
  page110_i73
#ISCELL
  standard tap *
  page110_i74
#ISCELL
  standard tap *
  page110_i75
#ISCELL
  standard tap *
  page110_i76
#ISCELL
  standard tap *
  page110_i77
#ISCELL
  standard tap *
  page110_i78
#ISCELL
  standard tap *
  page110_i79
#ISCELL
  standard offpage *
  page110_i8
#ISCELL
  standard tap *
  page110_i80
#ISCELL
  standard tap *
  page110_i81
#ISCELL
  standard tap *
  page110_i82
#ISCELL
  standard tap *
  page110_i83
#ISCELL
  standard tap *
  page110_i84
#ISCELL
  standard tap *
  page110_i85
#ISCELL
  standard tap *
  page110_i86
#ISCELL
  standard tap *
  page110_i87
#ISCELL
  standard tap *
  page110_i88
#ISCELL
  standard tap *
  page110_i89
#ISCELL
  standard offpage *
  page110_i9
#ISCELL
  standard tap *
  page110_i90
#ISCELL
  standard tap *
  page110_i91
#ISCELL
  standard tap *
  page110_i92
#ISCELL
  standard tap *
  page110_i93
#ISCELL
  standard tap *
  page110_i94
#ISCELL
  standard tap *
  page110_i95
#ISCELL
  standard tap *
  page110_i96
#ISCELL
  standard tap *
  page110_i97
#ISCELL
  standard tap *
  page110_i98
#ISCELL
  standard tap *
  page110_i99
#ISCELL
  logical_power cad_note *
  *
#ISCELL
  pure_quanta quanta_title_block_c *
  *
#ISCELL
  standard offpage *
  page111_i1
#ISCELL
  standard offpage *
  page111_i10
#ISCELL
  standard tap *
  page111_i100
#ISCELL
  standard offpage *
  page111_i101
#ISCELL
  standard tap *
  page111_i102
#ISCELL
  standard tap *
  page111_i103
#ISCELL
  standard tap *
  page111_i104
#ISCELL
  standard tap *
  page111_i105
#ISCELL
  standard tap *
  page111_i106
#ISCELL
  standard tap *
  page111_i107
#ISCELL
  standard tap *
  page111_i108
#ISCELL
  standard tap *
  page111_i109
#ISCELL
  standard offpage *
  page111_i11
#ISCELL
  standard tap *
  page111_i110
#ISCELL
  standard tap *
  page111_i111
#ISCELL
  standard tap *
  page111_i112
#ISCELL
  standard tap *
  page111_i113
#ISCELL
  standard tap *
  page111_i114
#ISCELL
  standard tap *
  page111_i115
#ISCELL
  standard tap *
  page111_i116
#ISCELL
  standard tap *
  page111_i117
#ISCELL
  standard tap *
  page111_i118
#ISCELL
  standard tap *
  page111_i119
#ISCELL
  standard offpage *
  page111_i12
#ISCELL
  standard tap *
  page111_i120
#ISCELL
  standard tap *
  page111_i121
#ISCELL
  standard tap *
  page111_i122
#ISCELL
  standard tap *
  page111_i123
#ISCELL
  standard tap *
  page111_i124
#ISCELL
  standard tap *
  page111_i125
#ISCELL
  standard tap *
  page111_i126
#ISCELL
  standard tap *
  page111_i127
#ISCELL
  standard offpage *
  page111_i128
#ISCELL
  standard offpage *
  page111_i13
#ISCELL
  standard tap *
  page111_i130
#ISCELL
  standard tap *
  page111_i131
#ISCELL
  standard tap *
  page111_i132
#ISCELL
  standard tap *
  page111_i133
#ISCELL
  standard tap *
  page111_i134
#ISCELL
  standard tap *
  page111_i135
#ISCELL
  standard tap *
  page111_i136
#ISCELL
  standard tap *
  page111_i137
#ISCELL
  standard tap *
  page111_i138
#ISCELL
  standard tap *
  page111_i139
#ISCELL
  standard offpage *
  page111_i14
#ISCELL
  standard tap *
  page111_i140
#ISCELL
  standard tap *
  page111_i141
#ISCELL
  standard tap *
  page111_i142
#ISCELL
  standard tap *
  page111_i143
#ISCELL
  standard tap *
  page111_i144
#ISCELL
  standard tap *
  page111_i145
#ISCELL
  standard tap *
  page111_i146
#ISCELL
  standard tap *
  page111_i147
#ISCELL
  standard tap *
  page111_i148
#ISCELL
  standard tap *
  page111_i149
#ISCELL
  standard offpage *
  page111_i15
#ISCELL
  standard tap *
  page111_i150
#ISCELL
  standard tap *
  page111_i151
#ISCELL
  standard tap *
  page111_i152
#ISCELL
  standard tap *
  page111_i153
#ISCELL
  standard tap *
  page111_i154
#ISCELL
  standard tap *
  page111_i155
#ISCELL
  standard tap *
  page111_i156
#ISCELL
  standard tap *
  page111_i157
#ISCELL
  standard tap *
  page111_i158
#ISCELL
  standard tap *
  page111_i159
#ISCELL
  standard offpage *
  page111_i16
#ISCELL
  standard tap *
  page111_i160
#ISCELL
  standard tap *
  page111_i161
#ISCELL
  standard tap *
  page111_i162
#ISCELL
  standard tap *
  page111_i163
#ISCELL
  standard tap *
  page111_i164
#ISCELL
  standard tap *
  page111_i165
#ISCELL
  standard tap *
  page111_i166
#ISCELL
  standard tap *
  page111_i167
#ISCELL
  standard tap *
  page111_i168
#ISCELL
  standard tap *
  page111_i169
#ISCELL
  standard offpage *
  page111_i17
#ISCELL
  standard offpage *
  page111_i170
#ISCELL
  standard offpage *
  page111_i171
#ISCELL
  standard offpage *
  page111_i172
#ISCELL
  standard offpage *
  page111_i173
#ISCELL
  logical_power vcc_core *
  page111_i174
#ISCELL
  standard offpage *
  page111_i175
#ISCELL
  standard offpage *
  page111_i176
#CELL
  pure_quanta sconn288_adr50017p087cc *
  page111_i178
#CELL
  pure_quanta sconn288_adr50017p087cc *
  page111_i179
#ISCELL
  standard offpage *
  page111_i18
#CELL
  pure_quanta sconn288_adr50017p087cc *
  page111_i180
#ISCELL
  standard offpage *
  page111_i181
#CELL
  pure_quanta q_res *
  page111_i182
#ISCELL
  standard offpage *
  page111_i19
#ISCELL
  standard offpage *
  page111_i2
#ISCELL
  standard offpage *
  page111_i20
#ISCELL
  standard offpage *
  page111_i21
#ISCELL
  logical_power vcc_core *
  page111_i22
#ISCELL
  standard tap *
  page111_i23
#ISCELL
  standard tap *
  page111_i24
#ISCELL
  standard tap *
  page111_i25
#ISCELL
  standard tap *
  page111_i26
#ISCELL
  standard tap *
  page111_i27
#ISCELL
  standard tap *
  page111_i28
#ISCELL
  standard tap *
  page111_i29
#ISCELL
  standard offpage *
  page111_i3
#ISCELL
  standard tap *
  page111_i30
#ISCELL
  standard tap *
  page111_i31
#ISCELL
  standard tap *
  page111_i32
#ISCELL
  standard tap *
  page111_i33
#ISCELL
  standard tap *
  page111_i34
#ISCELL
  standard tap *
  page111_i35
#ISCELL
  standard tap *
  page111_i36
#ISCELL
  standard tap *
  page111_i37
#ISCELL
  standard tap *
  page111_i38
#ISCELL
  standard tap *
  page111_i39
#ISCELL
  logical_power universal_gnd *
  page111_i4
#ISCELL
  standard tap *
  page111_i40
#ISCELL
  standard tap *
  page111_i41
#ISCELL
  standard tap *
  page111_i42
#ISCELL
  standard tap *
  page111_i43
#ISCELL
  standard tap *
  page111_i44
#ISCELL
  standard tap *
  page111_i45
#ISCELL
  standard tap *
  page111_i46
#ISCELL
  standard tap *
  page111_i47
#ISCELL
  standard tap *
  page111_i48
#ISCELL
  standard tap *
  page111_i49
#CELL
  pure_quanta q_res *
  page111_i5
#ISCELL
  standard tap *
  page111_i50
#ISCELL
  standard tap *
  page111_i51
#ISCELL
  standard tap *
  page111_i52
#ISCELL
  logical_power universal_gnd *
  page111_i53
#CELL
  pure_quanta q_cap *
  page111_i54
#ISCELL
  logical_power vcc_core *
  page111_i55
#CELL
  pure_quanta q_cap *
  page111_i56
#ISCELL
  logical_power vcc_core *
  page111_i57
#ISCELL
  logical_power universal_gnd *
  page111_i58
#CELL
  pure_quanta q_cap *
  page111_i59
#ISCELL
  standard offpage *
  page111_i6
#ISCELL
  logical_power universal_gnd *
  page111_i60
#ISCELL
  logical_power universal_gnd *
  page111_i62
#ISCELL
  standard tap *
  page111_i63
#ISCELL
  standard tap *
  page111_i64
#ISCELL
  standard tap *
  page111_i65
#ISCELL
  standard tap *
  page111_i66
#ISCELL
  standard tap *
  page111_i67
#ISCELL
  standard tap *
  page111_i68
#ISCELL
  standard tap *
  page111_i69
#ISCELL
  standard tap *
  page111_i70
#ISCELL
  standard tap *
  page111_i71
#ISCELL
  standard tap *
  page111_i72
#ISCELL
  standard tap *
  page111_i73
#ISCELL
  standard tap *
  page111_i74
#ISCELL
  standard tap *
  page111_i75
#ISCELL
  standard tap *
  page111_i76
#ISCELL
  standard tap *
  page111_i77
#ISCELL
  standard tap *
  page111_i78
#ISCELL
  standard tap *
  page111_i79
#ISCELL
  standard offpage *
  page111_i8
#ISCELL
  standard tap *
  page111_i80
#ISCELL
  standard tap *
  page111_i81
#ISCELL
  standard tap *
  page111_i82
#ISCELL
  standard tap *
  page111_i83
#ISCELL
  standard tap *
  page111_i84
#ISCELL
  standard tap *
  page111_i85
#ISCELL
  standard tap *
  page111_i86
#ISCELL
  standard tap *
  page111_i87
#ISCELL
  standard tap *
  page111_i88
#ISCELL
  standard tap *
  page111_i89
#ISCELL
  standard offpage *
  page111_i9
#ISCELL
  standard tap *
  page111_i90
#ISCELL
  standard tap *
  page111_i91
#ISCELL
  standard tap *
  page111_i92
#ISCELL
  standard tap *
  page111_i93
#ISCELL
  standard tap *
  page111_i94
#ISCELL
  standard tap *
  page111_i95
#ISCELL
  standard tap *
  page111_i96
#ISCELL
  standard tap *
  page111_i97
#ISCELL
  standard tap *
  page111_i98
#ISCELL
  standard tap *
  page111_i99
#ISCELL
  logical_power cad_note *
  *
#ISCELL
  pure_quanta quanta_title_block_c *
  *
#ISCELL
  standard offpage *
  page112_i1
#ISCELL
  standard offpage *
  page112_i10
#ISCELL
  standard tap *
  page112_i100
#ISCELL
  standard offpage *
  page112_i101
#ISCELL
  standard tap *
  page112_i102
#ISCELL
  standard tap *
  page112_i103
#ISCELL
  standard tap *
  page112_i104
#ISCELL
  standard tap *
  page112_i105
#ISCELL
  standard tap *
  page112_i106
#ISCELL
  standard tap *
  page112_i107
#ISCELL
  standard tap *
  page112_i108
#ISCELL
  standard tap *
  page112_i109
#ISCELL
  standard offpage *
  page112_i11
#ISCELL
  standard tap *
  page112_i110
#ISCELL
  standard tap *
  page112_i111
#ISCELL
  standard tap *
  page112_i112
#ISCELL
  standard tap *
  page112_i113
#ISCELL
  standard tap *
  page112_i114
#ISCELL
  standard tap *
  page112_i115
#ISCELL
  standard tap *
  page112_i116
#ISCELL
  standard tap *
  page112_i117
#ISCELL
  standard tap *
  page112_i118
#ISCELL
  standard tap *
  page112_i119
#ISCELL
  logical_power vcc_core *
  page112_i12
#ISCELL
  standard tap *
  page112_i120
#ISCELL
  standard offpage *
  page112_i121
#ISCELL
  logical_power universal_gnd *
  page112_i122
#ISCELL
  logical_power universal_gnd *
  page112_i123
#CELL
  pure_quanta q_cap *
  page112_i124
#CELL
  pure_quanta q_cap *
  page112_i125
#CELL
  pure_quanta q_cap *
  page112_i126
#ISCELL
  logical_power vcc_core *
  page112_i127
#ISCELL
  logical_power vcc_core *
  page112_i129
#ISCELL
  standard tap *
  page112_i130
#ISCELL
  standard tap *
  page112_i131
#ISCELL
  standard tap *
  page112_i132
#ISCELL
  standard tap *
  page112_i133
#ISCELL
  standard tap *
  page112_i134
#ISCELL
  standard tap *
  page112_i135
#ISCELL
  standard tap *
  page112_i136
#ISCELL
  standard tap *
  page112_i137
#ISCELL
  standard tap *
  page112_i138
#ISCELL
  standard tap *
  page112_i139
#ISCELL
  standard tap *
  page112_i14
#ISCELL
  standard tap *
  page112_i140
#ISCELL
  standard tap *
  page112_i141
#ISCELL
  standard tap *
  page112_i142
#ISCELL
  standard tap *
  page112_i143
#ISCELL
  standard tap *
  page112_i144
#ISCELL
  standard tap *
  page112_i145
#ISCELL
  standard tap *
  page112_i146
#ISCELL
  standard tap *
  page112_i147
#ISCELL
  standard tap *
  page112_i148
#ISCELL
  standard tap *
  page112_i149
#ISCELL
  standard tap *
  page112_i15
#ISCELL
  standard tap *
  page112_i150
#ISCELL
  standard tap *
  page112_i151
#ISCELL
  standard tap *
  page112_i152
#ISCELL
  standard tap *
  page112_i153
#ISCELL
  standard tap *
  page112_i154
#ISCELL
  standard tap *
  page112_i155
#ISCELL
  standard tap *
  page112_i156
#ISCELL
  standard tap *
  page112_i157
#ISCELL
  standard tap *
  page112_i158
#ISCELL
  standard tap *
  page112_i159
#ISCELL
  standard tap *
  page112_i16
#ISCELL
  standard tap *
  page112_i160
#ISCELL
  standard tap *
  page112_i161
#ISCELL
  standard tap *
  page112_i162
#ISCELL
  standard tap *
  page112_i163
#ISCELL
  standard tap *
  page112_i164
#ISCELL
  standard tap *
  page112_i165
#ISCELL
  standard tap *
  page112_i166
#ISCELL
  standard tap *
  page112_i167
#ISCELL
  standard tap *
  page112_i168
#ISCELL
  standard tap *
  page112_i169
#ISCELL
  standard tap *
  page112_i17
#ISCELL
  logical_power universal_gnd *
  page112_i170
#ISCELL
  standard offpage *
  page112_i172
#ISCELL
  standard offpage *
  page112_i173
#ISCELL
  standard offpage *
  page112_i174
#ISCELL
  standard offpage *
  page112_i175
#ISCELL
  logical_power vcc_core *
  page112_i176
#ISCELL
  logical_power universal_gnd *
  page112_i177
#CELL
  pure_quanta sconn288_adr50017p130cc *
  page112_i178
#ISCELL
  standard tap *
  page112_i18
#CELL
  pure_quanta sconn288_adr50017p130cc *
  page112_i180
#CELL
  pure_quanta sconn288_adr50017p130cc *
  page112_i181
#ISCELL
  standard offpage *
  page112_i182
#CELL
  pure_quanta q_res *
  page112_i183
#ISCELL
  standard tap *
  page112_i19
#ISCELL
  logical_power universal_gnd *
  page112_i2
#ISCELL
  standard offpage *
  page112_i20
#ISCELL
  standard offpage *
  page112_i21
#ISCELL
  standard offpage *
  page112_i22
#ISCELL
  standard offpage *
  page112_i23
#ISCELL
  standard offpage *
  page112_i24
#ISCELL
  standard offpage *
  page112_i25
#ISCELL
  standard offpage *
  page112_i26
#ISCELL
  standard offpage *
  page112_i27
#ISCELL
  standard offpage *
  page112_i28
#ISCELL
  standard offpage *
  page112_i29
#CELL
  pure_quanta q_res *
  page112_i3
#ISCELL
  standard offpage *
  page112_i30
#ISCELL
  standard offpage *
  page112_i31
#ISCELL
  standard tap *
  page112_i32
#ISCELL
  standard tap *
  page112_i33
#ISCELL
  standard tap *
  page112_i34
#ISCELL
  standard tap *
  page112_i35
#ISCELL
  standard tap *
  page112_i36
#ISCELL
  standard tap *
  page112_i37
#ISCELL
  standard tap *
  page112_i38
#ISCELL
  standard tap *
  page112_i39
#ISCELL
  standard offpage *
  page112_i4
#ISCELL
  standard tap *
  page112_i40
#ISCELL
  standard tap *
  page112_i41
#ISCELL
  standard tap *
  page112_i42
#ISCELL
  standard tap *
  page112_i43
#ISCELL
  standard tap *
  page112_i44
#ISCELL
  standard tap *
  page112_i45
#ISCELL
  standard tap *
  page112_i46
#ISCELL
  standard tap *
  page112_i47
#ISCELL
  standard tap *
  page112_i48
#ISCELL
  standard tap *
  page112_i49
#ISCELL
  standard offpage *
  page112_i5
#ISCELL
  standard tap *
  page112_i50
#ISCELL
  standard tap *
  page112_i51
#ISCELL
  standard tap *
  page112_i52
#ISCELL
  standard tap *
  page112_i53
#ISCELL
  standard tap *
  page112_i54
#ISCELL
  standard tap *
  page112_i55
#ISCELL
  standard tap *
  page112_i56
#ISCELL
  standard tap *
  page112_i57
#ISCELL
  standard tap *
  page112_i58
#ISCELL
  standard tap *
  page112_i59
#ISCELL
  standard offpage *
  page112_i6
#ISCELL
  standard tap *
  page112_i60
#ISCELL
  standard tap *
  page112_i61
#ISCELL
  standard tap *
  page112_i62
#ISCELL
  standard tap *
  page112_i63
#ISCELL
  standard tap *
  page112_i64
#ISCELL
  standard tap *
  page112_i65
#ISCELL
  standard tap *
  page112_i66
#ISCELL
  standard tap *
  page112_i67
#ISCELL
  standard tap *
  page112_i68
#ISCELL
  standard tap *
  page112_i69
#ISCELL
  standard tap *
  page112_i70
#ISCELL
  standard tap *
  page112_i71
#ISCELL
  standard tap *
  page112_i72
#ISCELL
  standard tap *
  page112_i73
#ISCELL
  standard tap *
  page112_i74
#ISCELL
  standard tap *
  page112_i75
#ISCELL
  standard tap *
  page112_i76
#ISCELL
  standard tap *
  page112_i77
#ISCELL
  standard tap *
  page112_i78
#ISCELL
  standard tap *
  page112_i79
#ISCELL
  standard offpage *
  page112_i8
#ISCELL
  standard tap *
  page112_i80
#ISCELL
  standard tap *
  page112_i81
#ISCELL
  standard tap *
  page112_i82
#ISCELL
  standard tap *
  page112_i83
#ISCELL
  standard tap *
  page112_i84
#ISCELL
  standard tap *
  page112_i85
#ISCELL
  standard tap *
  page112_i86
#ISCELL
  standard tap *
  page112_i87
#ISCELL
  standard tap *
  page112_i88
#ISCELL
  standard tap *
  page112_i89
#ISCELL
  standard offpage *
  page112_i9
#ISCELL
  standard tap *
  page112_i90
#ISCELL
  standard tap *
  page112_i91
#ISCELL
  standard tap *
  page112_i92
#ISCELL
  standard tap *
  page112_i93
#ISCELL
  standard tap *
  page112_i94
#ISCELL
  standard tap *
  page112_i95
#ISCELL
  standard tap *
  page112_i96
#ISCELL
  standard tap *
  page112_i97
#ISCELL
  standard tap *
  page112_i98
#ISCELL
  standard tap *
  page112_i99
#ISCELL
  logical_power cad_note *
  *
#ISCELL
  pure_quanta quanta_title_block_c *
  *
#ISCELL
  logical_power universal_gnd *
  page113_i1
#ISCELL
  standard offpage *
  page113_i10
#ISCELL
  standard tap *
  page113_i100
#ISCELL
  standard tap *
  page113_i101
#ISCELL
  standard tap *
  page113_i102
#ISCELL
  standard tap *
  page113_i103
#ISCELL
  standard tap *
  page113_i104
#ISCELL
  standard tap *
  page113_i105
#ISCELL
  standard tap *
  page113_i106
#ISCELL
  standard tap *
  page113_i107
#ISCELL
  standard tap *
  page113_i108
#ISCELL
  standard offpage *
  page113_i109
#ISCELL
  standard offpage *
  page113_i11
#ISCELL
  standard tap *
  page113_i110
#ISCELL
  standard tap *
  page113_i111
#ISCELL
  standard tap *
  page113_i112
#ISCELL
  standard tap *
  page113_i113
#ISCELL
  logical_power universal_gnd *
  page113_i114
#ISCELL
  logical_power universal_gnd *
  page113_i115
#CELL
  pure_quanta q_cap *
  page113_i116
#ISCELL
  logical_power vcc_core *
  page113_i117
#ISCELL
  standard offpage *
  page113_i119
#ISCELL
  logical_power vcc_core *
  page113_i12
#CELL
  pure_quanta q_cap *
  page113_i120
#ISCELL
  logical_power vcc_core *
  page113_i121
#CELL
  pure_quanta q_cap *
  page113_i122
#ISCELL
  logical_power universal_gnd *
  page113_i123
#ISCELL
  standard tap *
  page113_i124
#ISCELL
  standard tap *
  page113_i125
#ISCELL
  standard tap *
  page113_i126
#ISCELL
  standard tap *
  page113_i127
#ISCELL
  standard tap *
  page113_i128
#ISCELL
  standard tap *
  page113_i129
#ISCELL
  standard tap *
  page113_i13
#ISCELL
  standard tap *
  page113_i130
#ISCELL
  standard tap *
  page113_i131
#ISCELL
  standard tap *
  page113_i132
#ISCELL
  standard tap *
  page113_i133
#ISCELL
  standard tap *
  page113_i134
#ISCELL
  standard tap *
  page113_i135
#ISCELL
  standard tap *
  page113_i136
#ISCELL
  standard tap *
  page113_i137
#ISCELL
  standard tap *
  page113_i138
#ISCELL
  standard tap *
  page113_i139
#ISCELL
  standard offpage *
  page113_i14
#ISCELL
  standard tap *
  page113_i140
#ISCELL
  standard tap *
  page113_i141
#ISCELL
  standard tap *
  page113_i142
#ISCELL
  standard tap *
  page113_i143
#ISCELL
  standard tap *
  page113_i144
#ISCELL
  standard tap *
  page113_i145
#ISCELL
  standard tap *
  page113_i146
#ISCELL
  standard tap *
  page113_i147
#ISCELL
  standard tap *
  page113_i148
#ISCELL
  standard tap *
  page113_i149
#ISCELL
  standard offpage *
  page113_i15
#ISCELL
  standard tap *
  page113_i150
#ISCELL
  standard tap *
  page113_i151
#ISCELL
  standard tap *
  page113_i152
#ISCELL
  standard tap *
  page113_i153
#ISCELL
  standard tap *
  page113_i154
#ISCELL
  standard tap *
  page113_i155
#ISCELL
  standard tap *
  page113_i156
#ISCELL
  standard tap *
  page113_i157
#ISCELL
  standard tap *
  page113_i158
#ISCELL
  standard tap *
  page113_i159
#ISCELL
  standard offpage *
  page113_i16
#ISCELL
  standard tap *
  page113_i160
#ISCELL
  standard tap *
  page113_i161
#ISCELL
  standard offpage *
  page113_i162
#ISCELL
  standard offpage *
  page113_i163
#ISCELL
  standard offpage *
  page113_i164
#ISCELL
  standard tap *
  page113_i165
#ISCELL
  standard tap *
  page113_i166
#ISCELL
  standard offpage *
  page113_i167
#ISCELL
  standard offpage *
  page113_i168
#ISCELL
  logical_power vcc_core *
  page113_i169
#ISCELL
  standard offpage *
  page113_i17
#ISCELL
  logical_power universal_gnd *
  page113_i171
#ISCELL
  standard offpage *
  page113_i172
#ISCELL
  standard offpage *
  page113_i173
#ISCELL
  standard offpage *
  page113_i174
#ISCELL
  standard tap *
  page113_i175
#ISCELL
  standard tap *
  page113_i176
#CELL
  pure_quanta sconn288_adr50017p087cc *
  page113_i177
#CELL
  pure_quanta sconn288_adr50017p087cc *
  page113_i179
#ISCELL
  standard offpage *
  page113_i18
#CELL
  pure_quanta sconn288_adr50017p087cc *
  page113_i180
#ISCELL
  standard offpage *
  page113_i181
#CELL
  pure_quanta q_res *
  page113_i182
#ISCELL
  standard offpage *
  page113_i19
#CELL
  pure_quanta q_res *
  page113_i2
#ISCELL
  standard offpage *
  page113_i20
#ISCELL
  standard offpage *
  page113_i21
#ISCELL
  standard tap *
  page113_i22
#ISCELL
  standard tap *
  page113_i23
#ISCELL
  standard tap *
  page113_i24
#ISCELL
  standard tap *
  page113_i25
#ISCELL
  standard tap *
  page113_i26
#ISCELL
  standard tap *
  page113_i27
#ISCELL
  standard tap *
  page113_i28
#ISCELL
  standard tap *
  page113_i29
#ISCELL
  standard offpage *
  page113_i3
#ISCELL
  standard tap *
  page113_i30
#ISCELL
  standard tap *
  page113_i31
#ISCELL
  standard tap *
  page113_i32
#ISCELL
  standard tap *
  page113_i33
#ISCELL
  standard tap *
  page113_i34
#ISCELL
  standard tap *
  page113_i35
#ISCELL
  standard tap *
  page113_i36
#ISCELL
  standard tap *
  page113_i37
#ISCELL
  standard tap *
  page113_i38
#ISCELL
  standard tap *
  page113_i39
#ISCELL
  standard tap *
  page113_i40
#ISCELL
  standard tap *
  page113_i41
#ISCELL
  standard tap *
  page113_i42
#ISCELL
  standard tap *
  page113_i43
#ISCELL
  standard tap *
  page113_i44
#ISCELL
  standard tap *
  page113_i45
#ISCELL
  standard tap *
  page113_i46
#ISCELL
  standard tap *
  page113_i47
#ISCELL
  standard tap *
  page113_i48
#ISCELL
  standard tap *
  page113_i49
#ISCELL
  standard offpage *
  page113_i5
#ISCELL
  standard tap *
  page113_i50
#ISCELL
  standard tap *
  page113_i51
#ISCELL
  standard tap *
  page113_i52
#ISCELL
  standard tap *
  page113_i53
#ISCELL
  standard tap *
  page113_i54
#ISCELL
  standard tap *
  page113_i55
#ISCELL
  standard tap *
  page113_i56
#ISCELL
  standard tap *
  page113_i57
#ISCELL
  standard tap *
  page113_i58
#ISCELL
  standard tap *
  page113_i59
#ISCELL
  standard offpage *
  page113_i6
#ISCELL
  standard tap *
  page113_i60
#ISCELL
  standard tap *
  page113_i61
#ISCELL
  standard tap *
  page113_i62
#ISCELL
  standard tap *
  page113_i63
#ISCELL
  standard tap *
  page113_i64
#ISCELL
  standard tap *
  page113_i65
#ISCELL
  standard tap *
  page113_i66
#ISCELL
  standard tap *
  page113_i67
#ISCELL
  standard tap *
  page113_i68
#ISCELL
  standard tap *
  page113_i69
#ISCELL
  standard offpage *
  page113_i7
#ISCELL
  standard tap *
  page113_i70
#ISCELL
  standard tap *
  page113_i71
#ISCELL
  standard tap *
  page113_i72
#ISCELL
  standard tap *
  page113_i73
#ISCELL
  standard tap *
  page113_i74
#ISCELL
  standard tap *
  page113_i75
#ISCELL
  standard tap *
  page113_i76
#ISCELL
  standard tap *
  page113_i77
#ISCELL
  standard tap *
  page113_i78
#ISCELL
  standard tap *
  page113_i79
#ISCELL
  standard offpage *
  page113_i8
#ISCELL
  standard tap *
  page113_i80
#ISCELL
  standard tap *
  page113_i81
#ISCELL
  standard tap *
  page113_i82
#ISCELL
  standard tap *
  page113_i83
#ISCELL
  standard tap *
  page113_i84
#ISCELL
  standard tap *
  page113_i85
#ISCELL
  standard tap *
  page113_i86
#ISCELL
  standard tap *
  page113_i87
#ISCELL
  standard tap *
  page113_i88
#ISCELL
  standard tap *
  page113_i89
#ISCELL
  standard offpage *
  page113_i9
#ISCELL
  standard tap *
  page113_i90
#ISCELL
  standard tap *
  page113_i91
#ISCELL
  standard tap *
  page113_i92
#ISCELL
  standard tap *
  page113_i93
#ISCELL
  standard tap *
  page113_i94
#ISCELL
  standard tap *
  page113_i95
#ISCELL
  standard tap *
  page113_i96
#ISCELL
  standard tap *
  page113_i97
#ISCELL
  standard tap *
  page113_i98
#ISCELL
  standard tap *
  page113_i99
#ISCELL
  pure_quanta quanta_title_block_c *
  *
#ISCELL
  standard offpage *
  page114_i1
#ISCELL
  standard offpage *
  page114_i10
#ISCELL
  standard offpage *
  page114_i11
#ISCELL
  standard offpage *
  page114_i12
#ISCELL
  standard offpage *
  page114_i13
#ISCELL
  standard offpage *
  page114_i14
#ISCELL
  standard offpage *
  page114_i15
#ISCELL
  standard offpage *
  page114_i16
#CELL
  pure_quanta q_res *
  page114_i17
#CELL
  pure_quanta q_res *
  page114_i18
#CELL
  pure_quanta q_res *
  page114_i19
#ISCELL
  standard offpage *
  page114_i2
#CELL
  pure_quanta q_res *
  page114_i20
#CELL
  pure_quanta q_res *
  page114_i21
#CELL
  pure_quanta q_res *
  page114_i22
#CELL
  pure_quanta q_res *
  page114_i23
#CELL
  pure_quanta q_res *
  page114_i24
#CELL
  pure_quanta q_res *
  page114_i25
#CELL
  pure_quanta q_res *
  page114_i26
#CELL
  pure_quanta q_res *
  page114_i27
#CELL
  pure_quanta q_res *
  page114_i28
#CELL
  pure_quanta q_res *
  page114_i29
#ISCELL
  standard offpage *
  page114_i3
#CELL
  pure_quanta q_res *
  page114_i30
#CELL
  pure_quanta q_res *
  page114_i31
#CELL
  pure_quanta q_res *
  page114_i32
#ISCELL
  standard offpage *
  page114_i34
#ISCELL
  standard offpage *
  page114_i36
#ISCELL
  standard offpage *
  page114_i38
#ISCELL
  standard offpage *
  page114_i39
#ISCELL
  standard offpage *
  page114_i4
#ISCELL
  standard offpage *
  page114_i40
#ISCELL
  standard offpage *
  page114_i41
#ISCELL
  standard offpage *
  page114_i42
#ISCELL
  standard offpage *
  page114_i43
#ISCELL
  standard offpage *
  page114_i44
#ISCELL
  standard offpage *
  page114_i45
#ISCELL
  standard offpage *
  page114_i46
#ISCELL
  standard offpage *
  page114_i47
#ISCELL
  standard offpage *
  page114_i48
#ISCELL
  standard offpage *
  page114_i49
#ISCELL
  standard offpage *
  page114_i5
#ISCELL
  standard offpage *
  page114_i50
#ISCELL
  standard offpage *
  page114_i51
#ISCELL
  standard offpage *
  page114_i53
#ISCELL
  standard offpage *
  page114_i54
#ISCELL
  standard offpage *
  page114_i55
#ISCELL
  standard offpage *
  page114_i56
#CELL
  pure_quanta q_res *
  page114_i57
#CELL
  pure_quanta q_res *
  page114_i58
#CELL
  pure_quanta q_res *
  page114_i59
#ISCELL
  standard offpage *
  page114_i6
#CELL
  pure_quanta q_res *
  page114_i60
#CELL
  pure_quanta q_res *
  page114_i61
#CELL
  pure_quanta q_res *
  page114_i62
#CELL
  pure_quanta q_res *
  page114_i63
#CELL
  pure_quanta q_res *
  page114_i64
#CELL
  pure_quanta q_res *
  page114_i65
#CELL
  pure_quanta q_res *
  page114_i66
#CELL
  pure_quanta q_res *
  page114_i67
#CELL
  pure_quanta q_res *
  page114_i68
#CELL
  pure_quanta q_res *
  page114_i69
#ISCELL
  standard offpage *
  page114_i7
#ISCELL
  standard offpage *
  page114_i71
#ISCELL
  standard offpage *
  page114_i74
#ISCELL
  standard offpage *
  page114_i75
#CELL
  pure_quanta q_res *
  page114_i77
#CELL
  pure_quanta q_res *
  page114_i78
#CELL
  pure_quanta q_res *
  page114_i79
#ISCELL
  standard offpage *
  page114_i8
#ISCELL
  standard offpage *
  page114_i80
#ISCELL
  standard offpage *
  page114_i9
#ISCELL
  pure_quanta quanta_title_block_c *
  *
#ISCELL
  standard offpage *
  page115_i1
#ISCELL
  logical_power universal_power *
  page115_i10
#CELL
  pure_quanta q_res *
  page115_i11
#CELL
  pure_quanta q_res *
  page115_i12
#ISCELL
  logical_power universal_power *
  page115_i13
#CELL
  pure_quanta q_res *
  page115_i14
#ISCELL
  logical_power universal_power *
  page115_i15
#CELL
  pure_quanta q_res *
  page115_i16
#CELL
  pure_quanta q_res *
  page115_i17
#CELL
  pure_quanta q_res *
  page115_i18
#CELL
  pure_quanta q_res *
  page115_i19
#ISCELL
  standard offpage *
  page115_i2
#ISCELL
  logical_power universal_power *
  page115_i20
#CELL
  pure_quanta schottky_12 *
  page115_i22
#ISCELL
  logical_power universal_power *
  page115_i24
#CELL
  pure_quanta schottky_12 *
  page115_i25
#CELL
  pure_quanta schottky_12 *
  page115_i27
#CELL
  pure_quanta schottky_12 *
  page115_i29
#ISCELL
  standard offpage *
  page115_i3
#ISCELL
  logical_power universal_power *
  page115_i30
#ISCELL
  logical_power universal_power *
  page115_i31
#ISCELL
  logical_power universal_power *
  page115_i32
#ISCELL
  standard offpage *
  page115_i33
#ISCELL
  standard offpage *
  page115_i34
#ISCELL
  standard offpage *
  page115_i35
#ISCELL
  standard offpage *
  page115_i36
#CELL
  pure_quanta q_res *
  page115_i37
#CELL
  pure_quanta q_res *
  page115_i38
#ISCELL
  logical_power universal_power *
  page115_i39
#ISCELL
  standard offpage *
  page115_i4
#CELL
  pure_quanta q_res *
  page115_i40
#CELL
  pure_quanta q_res *
  page115_i41
#CELL
  pure_quanta q_res *
  page115_i42
#ISCELL
  logical_power universal_power *
  page115_i43
#ISCELL
  logical_power universal_power *
  page115_i44
#CELL
  pure_quanta q_res *
  page115_i45
#CELL
  pure_quanta q_res *
  page115_i46
#ISCELL
  logical_power universal_power *
  page115_i47
#CELL
  pure_quanta q_res *
  page115_i48
#ISCELL
  standard offpage *
  page115_i5
#CELL
  pure_quanta schottky_12 *
  page115_i50
#CELL
  pure_quanta schottky_12 *
  page115_i52
#CELL
  pure_quanta schottky_12 *
  page115_i54
#ISCELL
  logical_power universal_power *
  page115_i56
#ISCELL
  logical_power universal_power *
  page115_i57
#ISCELL
  logical_power universal_power *
  page115_i58
#CELL
  pure_quanta schottky_12 *
  page115_i59
#ISCELL
  standard offpage *
  page115_i6
#ISCELL
  logical_power universal_power *
  page115_i60
#ISCELL
  standard offpage *
  page115_i61
#ISCELL
  standard offpage *
  page115_i62
#ISCELL
  standard offpage *
  page115_i63
#ISCELL
  standard offpage *
  page115_i64
#CELL
  pure_quanta q_res *
  page115_i65
#CELL
  pure_quanta q_res *
  page115_i66
#CELL
  pure_quanta q_res *
  page115_i67
#CELL
  pure_quanta q_res *
  page115_i68
#CELL
  pure_quanta q_res *
  page115_i69
#ISCELL
  standard offpage *
  page115_i7
#CELL
  pure_quanta q_res *
  page115_i70
#CELL
  pure_quanta q_res *
  page115_i71
#CELL
  pure_quanta q_res *
  page115_i72
#ISCELL
  standard offpage *
  page115_i8
#CELL
  pure_quanta q_res *
  page115_i9
#ISCELL
  pure_quanta quanta_title_block_c *
  *
#ISCELL
  pure_quanta quanta_title_block_c *
  *
#CELL
  pure_quanta q_res *
  page117_i10
#ISCELL
  standard offpage *
  page117_i11
#ISCELL
  standard offpage *
  page117_i12
#CELL
  pure_quanta q_res *
  page117_i13
#ISCELL
  logical_power universal_power *
  page117_i14
#ISCELL
  logical_power universal_power *
  page117_i15
#CELL
  pure_quanta q_res *
  page117_i16
#CELL
  pure_quanta q_res *
  page117_i17
#ISCELL
  logical_power universal_gnd *
  page117_i18
#CELL
  pure_quanta q_res *
  page117_i19
#ISCELL
  logical_power universal_gnd *
  page117_i20
#ISCELL
  standard offpage *
  page117_i6
#ISCELL
  standard offpage *
  page117_i7
#CELL
  pure_quanta q_res *
  page117_i9
#ISCELL
  pure_quanta quanta_title_block_c *
  *
#ISCELL
  standard offpage *
  page118_i100
#CELL
  pure_quanta q_res *
  page118_i101
#CELL
  pure_quanta q_res *
  page118_i102
#ISCELL
  standard offpage *
  page118_i12
#CELL
  pure_quanta q_res *
  page118_i23
#ISCELL
  standard offpage *
  page118_i55
#CELL
  pure_quanta q_res *
  page118_i63
#ISCELL
  standard offpage *
  page118_i64
#CELL
  pure_quanta q_res *
  page118_i65
#ISCELL
  logical_power universal_power *
  page118_i66
#CELL
  pure_quanta q_res *
  page118_i67
#ISCELL
  logical_power universal_power *
  page118_i68
#CELL
  pure_quanta q_res *
  page118_i73
#ISCELL
  logical_power universal_power *
  page118_i74
#CELL
  pure_quanta q_res *
  page118_i76
#ISCELL
  logical_power universal_power *
  page118_i78
#ISCELL
  standard offpage *
  page118_i79
#ISCELL
  standard offpage *
  page118_i80
#ISCELL
  standard offpage *
  page118_i84
#CELL
  pure_quanta q_res *
  page118_i92
#ISCELL
  standard offpage *
  page118_i98
#ISCELL
  logical_power design_note *
  *
#ISCELL
  mstr_misc dns *
  *
#ISCELL
  pure_quanta quanta_title_block_c *
  *
#CELL
  pure_quanta q_res *
  page119_i100
#CELL
  pure_quanta q_res *
  page119_i101
#ISCELL
  logical_power universal_power *
  page119_i102
#ISCELL
  standard offpage *
  page119_i103
#ISCELL
  standard offpage *
  page119_i104
#ISCELL
  standard offpage *
  page119_i105
#ISCELL
  standard offpage *
  page119_i106
#ISCELL
  standard offpage *
  page119_i107
#ISCELL
  standard offpage *
  page119_i108
#ISCELL
  standard offpage *
  page119_i109
#ISCELL
  standard offpage *
  page119_i110
#ISCELL
  standard offpage *
  page119_i111
#ISCELL
  standard offpage *
  page119_i112
#ISCELL
  standard offpage *
  page119_i113
#ISCELL
  standard offpage *
  page119_i114
#CELL
  pure_quanta q_res *
  page119_i116
#ISCELL
  standard offpage *
  page119_i120
#ISCELL
  standard offpage *
  page119_i121
#ISCELL
  standard offpage *
  page119_i124
#CELL
  pure_quanta q_res *
  page119_i125
#CELL
  pure_quanta q_res *
  page119_i135
#CELL
  pure_quanta q_res *
  page119_i136
#ISCELL
  standard offpage *
  page119_i137
#ISCELL
  logical_power universal_power *
  page119_i138
#CELL
  pure_quanta q_res *
  page119_i139
#ISCELL
  logical_power universal_power *
  page119_i141
#ISCELL
  standard offpage *
  page119_i142
#ISCELL
  standard offpage *
  page119_i143
#ISCELL
  standard offpage *
  page119_i144
#ISCELL
  standard offpage *
  page119_i145
#ISCELL
  standard offpage *
  page119_i146
#CELL
  pure_quanta q_res *
  page119_i147
#CELL
  pure_quanta q_res *
  page119_i148
#ISCELL
  logical_power universal_power *
  page119_i149
#CELL
  pure_quanta q_res *
  page119_i150
#CELL
  pure_quanta q_res *
  page119_i151
#CELL
  pure_quanta q_res *
  page119_i152
#ISCELL
  standard offpage *
  page119_i155
#CELL
  pure_quanta q_res *
  page119_i156
#ISCELL
  standard offpage *
  page119_i157
#CELL
  pure_quanta q_res *
  page119_i158
#ISCELL
  standard offpage *
  page119_i159
#CELL
  pure_quanta q_res *
  page119_i160
#CELL
  pure_quanta q_res *
  page119_i161
#ISCELL
  standard offpage *
  page119_i162
#CELL
  pure_quanta q_res *
  page119_i163
#ISCELL
  standard offpage *
  page119_i164
#ISCELL
  standard offpage *
  page119_i167
#ISCELL
  standard offpage *
  page119_i168
#CELL
  pure_quanta q_res *
  page119_i169
#CELL
  pure_quanta q_res *
  page119_i170
#ISCELL
  logical_power universal_gnd *
  page119_i171
#CELL
  pure_quanta q_res *
  page119_i172
#ISCELL
  standard offpage *
  page119_i173
#ISCELL
  standard offpage *
  page119_i174
#ISCELL
  standard offpage *
  page119_i175
#CELL
  pure_quanta q_res *
  page119_i176
#CELL
  pure_quanta q_res *
  page119_i177
#ISCELL
  standard offpage *
  page119_i178
#ISCELL
  logical_power universal_power *
  page119_i18
#CELL
  pure_quanta q_res *
  page119_i196
#ISCELL
  logical_power universal_gnd *
  page119_i197
#ISCELL
  standard offpage *
  page119_i199
#ISCELL
  logical_power universal_power *
  page119_i210
#CELL
  pure_quanta q_res *
  page119_i211
#ISCELL
  standard offpage *
  page119_i212
#ISCELL
  logical_power universal_gnd *
  page119_i213
#ISCELL
  logical_power universal_power *
  page119_i214
#CELL
  pure_quanta q_res *
  page119_i215
#CELL
  pure_quanta q_res *
  page119_i216
#ISCELL
  standard offpage *
  page119_i217
#ISCELL
  logical_power universal_power *
  page119_i218
#CELL
  pure_quanta q_res *
  page119_i219
#CELL
  pure_quanta q_res *
  page119_i220
#ISCELL
  logical_power universal_gnd *
  page119_i221
#ISCELL
  standard offpage *
  page119_i222
#ISCELL
  logical_power universal_power *
  page119_i223
#CELL
  pure_quanta q_res *
  page119_i224
#CELL
  pure_quanta q_res *
  page119_i225
#ISCELL
  logical_power universal_gnd *
  page119_i226
#ISCELL
  standard offpage *
  page119_i29
#ISCELL
  standard offpage *
  page119_i40
#ISCELL
  logical_power universal_gnd *
  page119_i44
#ISCELL
  standard offpage *
  page119_i49
#ISCELL
  standard offpage *
  page119_i50
#CELL
  pure_quanta q_res *
  page119_i53
#CELL
  pure_quanta q_res *
  page119_i54
#ISCELL
  standard offpage *
  page119_i56
#CELL
  pure_quanta q_res *
  page119_i57
#CELL
  pure_quanta q_res *
  page119_i58
#ISCELL
  standard offpage *
  page119_i59
#ISCELL
  standard offpage *
  page119_i60
#CELL
  pure_quanta q_res *
  page119_i61
#CELL
  pure_quanta q_res *
  page119_i62
#ISCELL
  standard offpage *
  page119_i63
#ISCELL
  standard offpage *
  page119_i65
#CELL
  pure_quanta q_res *
  page119_i66
#ISCELL
  standard offpage *
  page119_i67
#CELL
  pure_quanta q_res *
  page119_i68
#CELL
  pure_quanta q_res *
  page119_i71
#CELL
  pure_quanta q_res *
  page119_i72
#CELL
  pure_quanta q_res *
  page119_i88
#CELL
  pure_quanta q_res *
  page119_i89
#CELL
  pure_quanta q_res *
  page119_i90
#ISCELL
  logical_power universal_power *
  page119_i91
#CELL
  pure_quanta q_res *
  page119_i92
#CELL
  pure_quanta q_res *
  page119_i93
#CELL
  pure_quanta q_res *
  page119_i94
#CELL
  pure_quanta q_res *
  page119_i95
#CELL
  pure_quanta q_res *
  page119_i96
#CELL
  pure_quanta q_res *
  page119_i97
#CELL
  pure_quanta q_res *
  page119_i98
#ISCELL
  mstr_misc dns *
  *
#ISCELL
  pure_quanta quanta_title_block_c *
  *
#ISCELL
  standard offpage *
  page120_i11
#ISCELL
  standard offpage *
  page120_i12
#ISCELL
  standard offpage *
  page120_i14
#ISCELL
  standard offpage *
  page120_i15
#ISCELL
  standard offpage *
  page120_i16
#ISCELL
  standard offpage *
  page120_i17
#CELL
  pure_quanta q_res *
  page120_i27
#CELL
  pure_quanta q_res *
  page120_i28
#CELL
  pure_quanta q_res *
  page120_i29
#CELL
  pure_quanta q_res *
  page120_i30
#CELL
  pure_quanta q_res *
  page120_i31
#CELL
  pure_quanta q_res *
  page120_i32
#ISCELL
  standard offpage *
  page120_i35
#ISCELL
  standard offpage *
  page120_i36
#ISCELL
  standard offpage *
  page120_i37
#ISCELL
  standard offpage *
  page120_i38
#ISCELL
  standard offpage *
  page120_i39
#ISCELL
  standard offpage *
  page120_i40
#ISCELL
  logical_power universal_power *
  page120_i41
#CELL
  pure_quanta q_res *
  page120_i42
#CELL
  pure_quanta q_res *
  page120_i43
#CELL
  pure_quanta q_res *
  page120_i44
#CELL
  pure_quanta q_res *
  page120_i45
#CELL
  pure_quanta q_res *
  page120_i46
#CELL
  pure_quanta q_res *
  page120_i48
#ISCELL
  logical_power universal_gnd *
  page120_i55
#ISCELL
  standard offpage *
  page120_i57
#ISCELL
  standard offpage *
  page120_i58
#CELL
  pure_quanta q_res *
  page120_i61
#CELL
  pure_quanta q_res *
  page120_i62
#ISCELL
  logical_power universal_gnd *
  page120_i63
#ISCELL
  standard offpage *
  page120_i64
#ISCELL
  standard offpage *
  page120_i65
#CELL
  pure_quanta q_res *
  page120_i66
#CELL
  pure_quanta q_res *
  page120_i67
#ISCELL
  logical_power universal_power *
  page120_i8
#ISCELL
  pure_quanta quanta_title_block_c *
  *
#ISCELL
  standard offpage *
  page121_i1
#CELL
  pure_quanta q_res *
  page121_i10
#ISCELL
  standard offpage *
  page121_i11
#ISCELL
  logical_power universal_power *
  page121_i12
#CELL
  pure_quanta q_res *
  page121_i13
#ISCELL
  logical_power universal_power *
  page121_i14
#CELL
  pure_quanta q_res *
  page121_i15
#CELL
  pure_quanta q_res *
  page121_i16
#CELL
  pure_quanta bc847bpn *
  page121_i17
#ISCELL
  logical_power universal_power *
  page121_i18
#CELL
  pure_quanta q_res *
  page121_i19
#ISCELL
  standard offpage *
  page121_i2
#ISCELL
  logical_power universal_power *
  page121_i20
#CELL
  pure_quanta bc847bpn *
  page121_i21
#ISCELL
  logical_power universal_gnd *
  page121_i22
#CELL
  pure_quanta q_res *
  page121_i23
#ISCELL
  logical_power universal_power *
  page121_i24
#ISCELL
  logical_power universal_power *
  page121_i25
#CELL
  pure_quanta q_res *
  page121_i26
#ISCELL
  standard offpage *
  page121_i27
#ISCELL
  standard offpage *
  page121_i28
#CELL
  pure_quanta q_res *
  page121_i29
#ISCELL
  standard offpage *
  page121_i3
#ISCELL
  standard offpage *
  page121_i30
#CELL
  pure_quanta bc847bpn *
  page121_i31
#ISCELL
  logical_power universal_gnd *
  page121_i32
#CELL
  pure_quanta q_res *
  page121_i33
#ISCELL
  logical_power universal_power *
  page121_i34
#CELL
  pure_quanta q_res *
  page121_i35
#ISCELL
  standard offpage *
  page121_i36
#CELL
  pure_quanta q_res *
  page121_i4
#CELL
  pure_quanta q_res *
  page121_i5
#CELL
  pure_quanta q_res *
  page121_i6
#CELL
  pure_quanta q_res *
  page121_i7
#CELL
  pure_quanta bc847bpn *
  page121_i8
#ISCELL
  logical_power universal_power *
  page121_i9
#ISCELL
  pure_quanta quanta_title_block_c *
  *
#ISCELL
  standard offpage *
  page122_i1
#CELL
  pure_quanta bc847bpn *
  page122_i10
#ISCELL
  logical_power universal_power *
  page122_i11
#CELL
  pure_quanta bc847bpn *
  page122_i12
#ISCELL
  logical_power universal_power *
  page122_i13
#ISCELL
  logical_power universal_power *
  page122_i14
#CELL
  pure_quanta q_res *
  page122_i15
#CELL
  pure_quanta q_res *
  page122_i16
#CELL
  pure_quanta bc847bpn *
  page122_i17
#CELL
  pure_quanta q_res *
  page122_i18
#ISCELL
  standard offpage *
  page122_i19
#ISCELL
  standard offpage *
  page122_i2
#CELL
  pure_quanta q_res *
  page122_i20
#CELL
  pure_quanta q_res *
  page122_i21
#CELL
  pure_quanta bc847bpn *
  page122_i22
#ISCELL
  logical_power universal_gnd *
  page122_i23
#CELL
  pure_quanta q_res *
  page122_i24
#ISCELL
  logical_power universal_power *
  page122_i25
#ISCELL
  logical_power universal_gnd *
  page122_i26
#CELL
  pure_quanta q_res *
  page122_i27
#ISCELL
  logical_power universal_power *
  page122_i28
#CELL
  pure_quanta q_res *
  page122_i29
#ISCELL
  standard offpage *
  page122_i3
#ISCELL
  logical_power universal_power *
  page122_i30
#CELL
  pure_quanta q_res *
  page122_i31
#ISCELL
  standard offpage *
  page122_i32
#CELL
  pure_quanta q_res *
  page122_i33
#CELL
  pure_quanta q_res *
  page122_i34
#ISCELL
  standard offpage *
  page122_i35
#ISCELL
  standard offpage *
  page122_i36
#CELL
  pure_quanta q_res *
  page122_i37
#ISCELL
  logical_power universal_power *
  page122_i38
#ISCELL
  standard offpage *
  page122_i4
#CELL
  pure_quanta q_res *
  page122_i5
#CELL
  pure_quanta q_res *
  page122_i6
#ISCELL
  logical_power universal_power *
  page122_i7
#CELL
  pure_quanta q_res *
  page122_i8
#CELL
  pure_quanta q_res *
  page122_i9
#ISCELL
  pure_quanta quanta_title_block_c *
  *
#ISCELL
  standard offpage *
  page123_i1
#CELL
  pure_quanta q_res *
  page123_i10
#CELL
  pure_quanta bc847bpn *
  page123_i11
#CELL
  pure_quanta bc847bpn *
  page123_i12
#ISCELL
  logical_power universal_power *
  page123_i13
#CELL
  pure_quanta q_res *
  page123_i14
#CELL
  pure_quanta q_res *
  page123_i15
#CELL
  pure_quanta bc847bpn *
  page123_i16
#ISCELL
  logical_power universal_gnd *
  page123_i17
#CELL
  pure_quanta bc847bpn *
  page123_i18
#CELL
  pure_quanta q_res *
  page123_i19
#ISCELL
  standard offpage *
  page123_i2
#ISCELL
  logical_power universal_power *
  page123_i20
#ISCELL
  logical_power universal_power *
  page123_i21
#ISCELL
  logical_power universal_gnd *
  page123_i22
#CELL
  pure_quanta q_res *
  page123_i23
#ISCELL
  logical_power universal_power *
  page123_i24
#ISCELL
  standard offpage *
  page123_i25
#ISCELL
  standard offpage *
  page123_i26
#CELL
  pure_quanta q_res *
  page123_i27
#ISCELL
  logical_power universal_power *
  page123_i28
#CELL
  pure_quanta q_res *
  page123_i29
#ISCELL
  standard offpage *
  page123_i3
#ISCELL
  logical_power universal_power *
  page123_i30
#CELL
  pure_quanta q_res *
  page123_i31
#CELL
  pure_quanta q_res *
  page123_i32
#CELL
  pure_quanta q_res *
  page123_i33
#ISCELL
  standard offpage *
  page123_i34
#ISCELL
  standard offpage *
  page123_i35
#ISCELL
  logical_power universal_power *
  page123_i36
#CELL
  pure_quanta q_res *
  page123_i4
#CELL
  pure_quanta q_res *
  page123_i5
#CELL
  pure_quanta q_res *
  page123_i6
#CELL
  pure_quanta q_res *
  page123_i7
#CELL
  pure_quanta q_res *
  page123_i8
#ISCELL
  logical_power universal_power *
  page123_i9
#ISCELL
  pure_quanta quanta_title_block_c *
  *
#ISCELL
  standard offpage *
  page124_i11
#CELL
  pure_quanta q_res *
  page124_i17
#CELL
  pure_quanta q_res *
  page124_i19
#ISCELL
  standard offpage *
  page124_i20
#CELL
  pure_quanta q_res *
  page124_i26
#ISCELL
  standard offpage *
  page124_i27
#CELL
  pure_quanta q_res *
  page124_i33
#ISCELL
  standard offpage *
  page124_i34
#ISCELL
  standard offpage *
  page124_i40
#CELL
  pure_quanta q_res *
  page124_i43
#ISCELL
  logical_power universal_power *
  page124_i51
#CELL
  pure_quanta q_res *
  page124_i52
#ISCELL
  standard offpage *
  page124_i54
#ISCELL
  standard offpage *
  page124_i57
#ISCELL
  standard offpage *
  page124_i58
#ISCELL
  logical_power universal_power *
  page124_i59
#CELL
  pure_quanta q_res *
  page124_i60
#CELL
  pure_quanta q_res *
  page124_i62
#CELL
  pure_quanta q_res *
  page124_i68
#ISCELL
  logical_power universal_power *
  page124_i69
#CELL
  pure_quanta q_res *
  page124_i70
#ISCELL
  logical_power universal_power *
  page124_i71
#CELL
  pure_quanta q_res *
  page124_i72
#ISCELL
  logical_power universal_power *
  page124_i73
#ISCELL
  logical_power universal_power *
  page124_i75
#CELL
  pure_quanta q_res *
  page124_i76
#CELL
  pure_quanta q_res *
  page124_i77
#CELL
  pure_quanta q_res *
  page124_i78
#CELL
  pure_quanta q_res *
  page124_i79
#ISCELL
  standard offpage *
  page124_i80
#CELL
  pure_quanta q_res *
  page124_i82
#ISCELL
  standard offpage *
  page124_i83
#CELL
  pure_quanta q_res *
  page124_i85
#ISCELL
  standard offpage *
  page124_i86
#CELL
  pure_quanta q_res *
  page124_i87
#ISCELL
  standard offpage *
  page124_i88
#ISCELL
  pure_quanta quanta_title_block_c *
  *
#ISCELL
  standard offpage *
  page125_i1
#ISCELL
  standard offpage *
  page125_i10
#ISCELL
  standard offpage *
  page125_i11
#CELL
  pure_quanta q_res *
  page125_i13
#CELL
  pure_quanta q_res *
  page125_i15
#CELL
  pure_quanta q_res *
  page125_i17
#ISCELL
  standard offpage *
  page125_i2
#CELL
  pure_quanta q_res *
  page125_i24
#CELL
  pure_quanta q_res *
  page125_i26
#ISCELL
  logical_power universal_power *
  page125_i27
#ISCELL
  standard offpage *
  page125_i28
#ISCELL
  logical_power universal_power *
  page125_i29
#CELL
  pure_quanta q_res *
  page125_i3
#ISCELL
  standard offpage *
  page125_i30
#CELL
  pure_quanta q_res *
  page125_i5
#CELL
  pure_quanta q_res *
  page125_i56
#ISCELL
  logical_power universal_power *
  page125_i57
#CELL
  pure_quanta q_res *
  page125_i58
#ISCELL
  logical_power universal_power *
  page125_i59
#CELL
  pure_quanta q_res *
  page125_i60
#ISCELL
  logical_power universal_power *
  page125_i61
#CELL
  pure_quanta q_res *
  page125_i62
#ISCELL
  logical_power universal_power *
  page125_i63
#CELL
  pure_quanta q_res *
  page125_i64
#CELL
  pure_quanta q_res *
  page125_i65
#CELL
  pure_quanta q_res *
  page125_i66
#ISCELL
  standard offpage *
  page125_i67
#CELL
  pure_quanta q_res *
  page125_i68
#ISCELL
  standard offpage *
  page125_i69
#CELL
  pure_quanta q_res *
  page125_i7
#CELL
  pure_quanta q_res *
  page125_i70
#ISCELL
  standard offpage *
  page125_i71
#CELL
  pure_quanta q_res *
  page125_i72
#ISCELL
  standard offpage *
  page125_i73
#ISCELL
  standard offpage *
  page125_i8
#ISCELL
  standard offpage *
  page125_i9
#ISCELL
  mstr_misc dns *
  *
#ISCELL
  pure_quanta quanta_title_block_c *
  *
#CELL
  pure_quanta q_res *
  page126_i114
#ISCELL
  standard offpage *
  page126_i133
#ISCELL
  standard offpage *
  page126_i134
#CELL
  pure_quanta q_res *
  page126_i135
#CELL
  pure_quanta q_res *
  page126_i136
#ISCELL
  logical_power universal_power *
  page126_i137
#ISCELL
  standard offpage *
  page126_i138
#ISCELL
  standard offpage *
  page126_i139
#CELL
  pure_quanta q_res *
  page126_i140
#CELL
  pure_quanta q_res *
  page126_i141
#CELL
  pure_quanta q_res *
  page126_i22
#CELL
  pure_quanta q_res *
  page126_i23
#ISCELL
  logical_power universal_power *
  page126_i24
#CELL
  pure_quanta q_res *
  page126_i25
#ISCELL
  standard offpage *
  page126_i42
#ISCELL
  standard offpage *
  page126_i43
#ISCELL
  standard offpage *
  page126_i44
#ISCELL
  standard offpage *
  page126_i45
#ISCELL
  mstr_misc dns *
  *
#ISCELL
  pure_quanta quanta_title_block_c *
  *
#CELL
  pure_quanta q_res *
  page127_i1
#ISCELL
  standard offpage *
  page127_i10
#ISCELL
  standard offpage *
  page127_i11
#ISCELL
  standard offpage *
  page127_i12
#CELL
  pure_quanta q_res *
  page127_i13
#CELL
  pure_quanta q_res *
  page127_i14
#CELL
  pure_quanta q_res *
  page127_i15
#ISCELL
  logical_power universal_gnd *
  page127_i16
#CELL
  pure_quanta q_res *
  page127_i17
#ISCELL
  logical_power universal_gnd *
  page127_i18
#ISCELL
  logical_power universal_power *
  page127_i19
#ISCELL
  standard offpage *
  page127_i2
#CELL
  pure_quanta q_res *
  page127_i20
#CELL
  pure_quanta q_res *
  page127_i21
#ISCELL
  logical_power universal_gnd *
  page127_i22
#ISCELL
  logical_power universal_power *
  page127_i23
#CELL
  pure_quanta q_res *
  page127_i24
#ISCELL
  logical_power universal_gnd *
  page127_i25
#CELL
  pure_quanta q_res *
  page127_i26
#ISCELL
  standard offpage *
  page127_i27
#ISCELL
  logical_power universal_power *
  page127_i28
#ISCELL
  standard offpage *
  page127_i3
#ISCELL
  logical_power universal_gnd *
  page127_i30
#CELL
  pure_quanta q_res *
  page127_i31
#CELL
  pure_quanta q_res *
  page127_i32
#ISCELL
  standard offpage *
  page127_i33
#ISCELL
  logical_power universal_power *
  page127_i34
#CELL
  pure_quanta q_res *
  page127_i35
#CELL
  pure_quanta q_res *
  page127_i36
#ISCELL
  logical_power universal_gnd *
  page127_i37
#ISCELL
  standard offpage *
  page127_i4
#CELL
  pure_quanta q_res *
  page127_i5
#CELL
  pure_quanta q_res *
  page127_i6
#CELL
  pure_quanta q_res *
  page127_i7
#ISCELL
  logical_power universal_gnd *
  page127_i8
#ISCELL
  logical_power universal_gnd *
  page127_i9
#ISCELL
  pure_quanta quanta_title_block_c *
  *
#ISCELL
  standard offpage *
  page128_i1
#CELL
  pure_quanta q_res *
  page128_i10
#CELL
  pure_quanta q_res *
  page128_i11
#CELL
  pure_quanta q_res *
  page128_i12
#ISCELL
  standard offpage *
  page128_i2
#ISCELL
  standard offpage *
  page128_i3
#ISCELL
  standard offpage *
  page128_i30
#ISCELL
  standard offpage *
  page128_i31
#ISCELL
  standard offpage *
  page128_i32
#ISCELL
  standard offpage *
  page128_i33
#ISCELL
  standard offpage *
  page128_i4
#ISCELL
  standard offpage *
  page128_i44
#ISCELL
  standard offpage *
  page128_i45
#ISCELL
  standard offpage *
  page128_i46
#ISCELL
  standard offpage *
  page128_i47
#CELL
  pure_quanta q_res *
  page128_i48
#CELL
  pure_quanta q_res *
  page128_i49
#CELL
  pure_quanta q_res *
  page128_i50
#CELL
  pure_quanta q_res *
  page128_i51
#ISCELL
  standard offpage *
  page128_i68
#ISCELL
  standard offpage *
  page128_i69
#ISCELL
  standard offpage *
  page128_i70
#ISCELL
  standard offpage *
  page128_i71
#CELL
  pure_quanta q_res *
  page128_i77
#CELL
  pure_quanta q_res *
  page128_i78
#CELL
  pure_quanta q_res *
  page128_i79
#CELL
  pure_quanta q_res *
  page128_i80
#ISCELL
  logical_power universal_gnd *
  page128_i81
#CELL
  pure_quanta q_res *
  page128_i82
#CELL
  pure_quanta q_res *
  page128_i83
#ISCELL
  logical_power universal_gnd *
  page128_i84
#CELL
  pure_quanta q_res *
  page128_i85
#CELL
  pure_quanta q_res *
  page128_i86
#CELL
  pure_quanta q_res *
  page128_i9
#ISCELL
  mstr_misc dns *
  *
#ISCELL
  pure_quanta quanta_title_block_c *
  *
#ISCELL
  logical_power universal_gnd *
  page129_i100
#CELL
  pure_quanta q_cap *
  page129_i102
#CELL
  pure_quanta q_res *
  page129_i103
#CELL
  pure_quanta q_res *
  page129_i106
#CELL
  pure_quanta q_res *
  page129_i109
#CELL
  pure_quanta q_res *
  page129_i112
#CELL
  pure_quanta q_res *
  page129_i119
#ISCELL
  logical_power universal_power *
  page129_i120
#CELL
  pure_quanta q_res *
  page129_i121
#ISCELL
  logical_power universal_power *
  page129_i122
#CELL
  pure_quanta q_res *
  page129_i123
#ISCELL
  logical_power universal_power *
  page129_i124
#CELL
  pure_quanta q_res *
  page129_i125
#ISCELL
  logical_power universal_power *
  page129_i126
#ISCELL
  standard offpage *
  page129_i22
#CELL
  pure_quanta q_res *
  page129_i26
#ISCELL
  standard offpage *
  page129_i51
#ISCELL
  standard offpage *
  page129_i52
#CELL
  pure_quanta q_res *
  page129_i59
#ISCELL
  standard offpage *
  page129_i64
#ISCELL
  standard offpage *
  page129_i65
#ISCELL
  standard offpage *
  page129_i66
#CELL
  pure_quanta q_res *
  page129_i76
#ISCELL
  standard offpage *
  page129_i83
#CELL
  pure_quanta q_res *
  page129_i86
#ISCELL
  standard offpage *
  page129_i90
#CELL
  pure_quanta q_cap *
  page129_i91
#ISCELL
  logical_power universal_gnd *
  page129_i93
#CELL
  pure_quanta q_cap *
  page129_i94
#ISCELL
  logical_power universal_gnd *
  page129_i96
#ISCELL
  logical_power universal_gnd *
  page129_i97
#CELL
  pure_quanta q_cap *
  page129_i99
#ISCELL
  mstr_misc dns *
  *
#ISCELL
  pure_quanta quanta_title_block_c *
  *
#CELL
  pure_quanta q_res *
  page130_i11
#CELL
  pure_quanta q_res *
  page130_i22
#CELL
  pure_quanta q_res *
  page130_i26
#CELL
  pure_quanta q_res *
  page130_i37
#ISCELL
  standard offpage *
  page130_i53
#ISCELL
  standard offpage *
  page130_i54
#ISCELL
  standard offpage *
  page130_i55
#ISCELL
  standard offpage *
  page130_i56
#ISCELL
  logical_power universal_gnd *
  page130_i57
#ISCELL
  logical_power universal_gnd *
  page130_i58
#CELL
  pure_quanta q_cap *
  page130_i59
#ISCELL
  logical_power universal_gnd *
  page130_i61
#CELL
  pure_quanta q_cap *
  page130_i62
#CELL
  pure_quanta q_res *
  page130_i63
#ISCELL
  logical_power universal_gnd *
  page130_i64
#CELL
  pure_quanta q_cap *
  page130_i65
#CELL
  pure_quanta q_cap *
  page130_i68
#CELL
  pure_quanta q_res *
  page130_i75
#CELL
  pure_quanta q_res *
  page130_i76
#CELL
  pure_quanta q_res *
  page130_i79
#ISCELL
  standard offpage *
  page130_i80
#ISCELL
  logical_power universal_power *
  page130_i81
#CELL
  pure_quanta q_res *
  page130_i82
#ISCELL
  logical_power universal_power *
  page130_i83
#CELL
  pure_quanta q_res *
  page130_i84
#ISCELL
  standard offpage *
  page130_i85
#ISCELL
  standard offpage *
  page130_i86
#ISCELL
  logical_power universal_power *
  page130_i87
#CELL
  pure_quanta q_res *
  page130_i88
#ISCELL
  logical_power universal_power *
  page130_i89
#CELL
  pure_quanta q_res *
  page130_i90
#ISCELL
  standard offpage *
  page130_i91
#ISCELL
  mstr_misc dns *
  *
#ISCELL
  pure_quanta quanta_title_block_c *
  *
#CELL
  pure_quanta q_res *
  page133_i10
#CELL
  pure_quanta q_cap *
  page133_i100
#ISCELL
  logical_power universal_gnd *
  page133_i101
#CELL
  pure_quanta q_res *
  page133_i102
#ISCELL
  logical_power universal_gnd *
  page133_i103
#ISCELL
  logical_power universal_gnd *
  page133_i104
#CELL
  pure_quanta q_cap *
  page133_i105
#ISCELL
  standard offpage *
  page133_i106
#ISCELL
  logical_power universal_power *
  page133_i109
#ISCELL
  logical_power universal_power *
  page133_i11
#CELL
  pure_quanta q_res *
  page133_i111
#CELL
  pure_quanta q_res *
  page133_i112
#CELL
  pure_quanta q_res *
  page133_i113
#ISCELL
  standard offpage *
  page133_i115
#ISCELL
  standard offpage *
  page133_i116
#CELL
  pure_quanta q_res *
  page133_i118
#ISCELL
  logical_power universal_gnd *
  page133_i12
#CELL
  pure_quanta q_res *
  page133_i120
#ISCELL
  standard offpage *
  page133_i121
#ISCELL
  standard offpage *
  page133_i122
#ISCELL
  standard offpage *
  page133_i123
#CELL
  pure_quanta q_res *
  page133_i124
#ISCELL
  logical_power universal_gnd *
  page133_i126
#ISCELL
  logical_power universal_gnd *
  page133_i128
#CELL
  pure_quanta q_cap *
  page133_i129
#ISCELL
  standard offpage *
  page133_i13
#CELL
  pure_quanta q_cap *
  page133_i130
#ISCELL
  standard offpage *
  page133_i131
#CELL
  pure_quanta q_res *
  page133_i132
#ISCELL
  logical_power universal_gnd *
  page133_i133
#ISCELL
  standard offpage *
  page133_i134
#ISCELL
  standard offpage *
  page133_i137
#ISCELL
  standard offpage *
  page133_i138
#ISCELL
  standard offpage *
  page133_i139
#ISCELL
  logical_power universal_power *
  page133_i14
#CELL
  pure_quanta q_res *
  page133_i144
#ISCELL
  standard offpage *
  page133_i145
#ISCELL
  standard offpage *
  page133_i147
#CELL
  pure_quanta q_res *
  page133_i148
#CELL
  pure_quanta q_res *
  page133_i15
#ISCELL
  standard offpage *
  page133_i150
#ISCELL
  standard offpage *
  page133_i151
#ISCELL
  standard offpage *
  page133_i152
#CELL
  pure_quanta q_res *
  page133_i153
#ISCELL
  standard offpage *
  page133_i16
#ISCELL
  logical_power universal_power *
  page133_i20
#ISCELL
  standard offpage *
  page133_i4
#CELL
  pure_quanta sconn60_asp21410801 *
  page133_i44
#ISCELL
  standard offpage *
  page133_i45
#ISCELL
  standard offpage *
  page133_i47
#ISCELL
  standard offpage *
  page133_i49
#CELL
  pure_quanta q_res *
  page133_i5
#ISCELL
  standard offpage *
  page133_i50
#ISCELL
  standard offpage *
  page133_i51
#ISCELL
  standard offpage *
  page133_i52
#ISCELL
  standard offpage *
  page133_i53
#ISCELL
  standard offpage *
  page133_i54
#ISCELL
  standard offpage *
  page133_i55
#ISCELL
  standard offpage *
  page133_i56
#ISCELL
  standard offpage *
  page133_i57
#ISCELL
  standard offpage *
  page133_i58
#ISCELL
  standard offpage *
  page133_i59
#ISCELL
  standard offpage *
  page133_i60
#ISCELL
  logical_power universal_gnd *
  page133_i61
#ISCELL
  standard offpage *
  page133_i62
#ISCELL
  standard offpage *
  page133_i63
#ISCELL
  standard offpage *
  page133_i64
#ISCELL
  standard offpage *
  page133_i65
#ISCELL
  standard offpage *
  page133_i66
#ISCELL
  standard offpage *
  page133_i67
#ISCELL
  standard offpage *
  page133_i68
#ISCELL
  logical_power universal_power *
  page133_i69
#CELL
  pure_quanta q_res *
  page133_i7
#CELL
  pure_quanta q_res *
  page133_i70
#CELL
  pure_quanta q_res *
  page133_i71
#CELL
  pure_quanta q_res *
  page133_i74
#ISCELL
  standard offpage *
  page133_i76
#ISCELL
  standard offpage *
  page133_i78
#ISCELL
  standard offpage *
  page133_i79
#ISCELL
  standard offpage *
  page133_i8
#ISCELL
  standard offpage *
  page133_i80
#ISCELL
  standard offpage *
  page133_i81
#CELL
  pure_quanta q_res *
  page133_i83
#ISCELL
  standard offpage *
  page133_i85
#ISCELL
  standard offpage *
  page133_i86
#ISCELL
  standard offpage *
  page133_i87
#ISCELL
  standard offpage *
  page133_i88
#ISCELL
  standard offpage *
  page133_i89
#ISCELL
  standard offpage *
  page133_i9
#ISCELL
  standard offpage *
  page133_i91
#CELL
  pure_quanta q_res *
  page133_i92
#ISCELL
  logical_power universal_power *
  page133_i94
#CELL
  pure_quanta q_res *
  page133_i95
#CELL
  pure_quanta q_cap *
  page133_i96
#ISCELL
  logical_power universal_gnd *
  page133_i97
#ISCELL
  logical_power universal_gnd *
  page133_i98
#CELL
  pure_quanta q_cap *
  page133_i99
#ISCELL
  pure_quanta quanta_title_block_c *
  *
#ISCELL
  standard offpage *
  page134_i116
#ISCELL
  standard offpage *
  page134_i117
#ISCELL
  standard offpage *
  page134_i124
#ISCELL
  standard offpage *
  page134_i125
#CELL
  pure_quanta q_res *
  page134_i126
#CELL
  pure_quanta q_res *
  page134_i127
#CELL
  pure_quanta q_res *
  page134_i128
#CELL
  pure_quanta 74cbtlv3126pw *
  page134_i129
#ISCELL
  logical_power universal_power *
  page134_i134
#CELL
  pure_quanta q_cap *
  page134_i135
#ISCELL
  logical_power universal_gnd *
  page134_i136
#ISCELL
  standard offpage *
  page134_i140
#ISCELL
  standard offpage *
  page134_i141
#ISCELL
  standard offpage *
  page134_i142
#ISCELL
  standard offpage *
  page134_i143
#ISCELL
  standard offpage *
  page134_i145
#CELL
  pure_quanta q_res *
  page134_i147
#CELL
  pure_quanta q_res *
  page134_i148
#ISCELL
  standard offpage *
  page134_i153
#ISCELL
  standard offpage *
  page134_i154
#ISCELL
  standard offpage *
  page134_i156
#ISCELL
  standard offpage *
  page134_i157
#ISCELL
  standard offpage *
  page134_i158
#ISCELL
  standard offpage *
  page134_i159
#ISCELL
  standard offpage *
  page134_i160
#ISCELL
  standard offpage *
  page134_i161
#ISCELL
  standard offpage *
  page134_i162
#ISCELL
  standard offpage *
  page134_i163
#ISCELL
  logical_power universal_gnd *
  page134_i164
#ISCELL
  logical_power universal_gnd *
  page134_i165
#CELL
  pure_quanta q_res *
  page134_i166
#ISCELL
  logical_power universal_power *
  page134_i167
#CELL
  pure_quanta q_res *
  page134_i168
#CELL
  pure_quanta q_res *
  page134_i169
#ISCELL
  logical_power universal_power *
  page134_i172
#CELL
  pure_quanta q_res *
  page134_i174
#CELL
  pure_quanta q_res *
  page134_i175
#CELL
  pure_quanta q_res *
  page134_i176
#CELL
  pure_quanta q_res *
  page134_i177
#CELL
  pure_quanta q_res *
  page134_i178
#CELL
  pure_quanta q_res *
  page134_i179
#CELL
  pure_quanta q_res *
  page134_i180
#ISCELL
  logical_power universal_power *
  page134_i181
#CELL
  pure_quanta 74cbtlv3126pw *
  page134_i80
#ISCELL
  logical_power universal_power *
  page134_i81
#ISCELL
  standard offpage *
  page134_i82
#ISCELL
  standard offpage *
  page134_i86
#ISCELL
  standard offpage *
  page134_i87
#ISCELL
  standard offpage *
  page134_i88
#ISCELL
  standard offpage *
  page134_i89
#CELL
  pure_quanta q_res *
  page134_i90
#ISCELL
  logical_power universal_gnd *
  page134_i91
#ISCELL
  logical_power universal_gnd *
  page134_i92
#CELL
  pure_quanta q_cap *
  page134_i93
#ISCELL
  standard offpage *
  page134_i95
#ISCELL
  standard offpage *
  page134_i97
#ISCELL
  pure_quanta quanta_title_block_c *
  *
#CELL
  pure_quanta q_cap *
  page135_i100
#ISCELL
  logical_power universal_gnd *
  page135_i103
#CELL
  pure_quanta q_res *
  page135_i106
#CELL
  pure_quanta q_res *
  page135_i107
#ISCELL
  logical_power universal_power *
  page135_i108
#CELL
  pure_quanta q_res *
  page135_i109
#CELL
  pure_quanta q_res *
  page135_i110
#ISCELL
  standard offpage *
  page135_i111
#ISCELL
  standard offpage *
  page135_i112
#ISCELL
  standard offpage *
  page135_i113
#ISCELL
  standard offpage *
  page135_i114
#CELL
  pure_quanta 74lvc1g66gv *
  page135_i115
#ISCELL
  standard offpage *
  page135_i23
#ISCELL
  logical_power universal_gnd *
  page135_i27
#CELL
  pure_quanta nc7sb3157 *
  page135_i58
#ISCELL
  standard offpage *
  page135_i59
#ISCELL
  logical_power universal_power *
  page135_i60
#CELL
  pure_quanta q_cap *
  page135_i61
#ISCELL
  standard offpage *
  page135_i63
#ISCELL
  standard offpage *
  page135_i64
#CELL
  pure_quanta q_res *
  page135_i65
#CELL
  pure_quanta q_res *
  page135_i66
#ISCELL
  logical_power universal_power *
  page135_i67
#ISCELL
  logical_power universal_power *
  page135_i68
#ISCELL
  logical_power universal_gnd *
  page135_i69
#CELL
  pure_quanta q_cap *
  page135_i70
#CELL
  pure_quanta nc7sb3157 *
  page135_i71
#ISCELL
  logical_power universal_power *
  page135_i72
#ISCELL
  logical_power universal_power *
  page135_i73
#ISCELL
  logical_power universal_power *
  page135_i74
#CELL
  pure_quanta q_res *
  page135_i77
#CELL
  pure_quanta q_res *
  page135_i78
#ISCELL
  logical_power universal_gnd *
  page135_i79
#CELL
  pure_quanta q_cap *
  page135_i80
#CELL
  pure_quanta q_cap *
  page135_i81
#ISCELL
  logical_power universal_gnd *
  page135_i82
#ISCELL
  standard offpage *
  page135_i84
#ISCELL
  standard offpage *
  page135_i85
#ISCELL
  standard offpage *
  page135_i86
#ISCELL
  standard offpage *
  page135_i87
#ISCELL
  standard offpage *
  page135_i90
#ISCELL
  standard offpage *
  page135_i91
#ISCELL
  logical_power universal_gnd *
  page135_i92
#ISCELL
  logical_power universal_power *
  page135_i93
#CELL
  pure_quanta q_cap *
  page135_i94
#ISCELL
  logical_power universal_gnd *
  page135_i95
#CELL
  pure_quanta 74lvc1g02gw *
  page135_i96
#CELL
  pure_quanta q_res *
  page135_i97
#ISCELL
  logical_power universal_power *
  page135_i98
#ISCELL
  logical_power universal_gnd *
  page135_i99
#ISCELL
  logical_power design_note *
  *
#ISCELL
  mstr_misc dns *
  *
#ISCELL
  pure_quanta quanta_title_block_c *
  *
#ISCELL
  logical_power universal_gnd *
  page137_i101
#CELL
  pure_quanta q_res *
  page137_i102
#CELL
  pure_quanta q_res *
  page137_i103
#ISCELL
  logical_power universal_gnd *
  page137_i104
#CELL
  pure_quanta q_res *
  page137_i105
#CELL
  pure_quanta q_res *
  page137_i106
#ISCELL
  logical_power universal_gnd *
  page137_i107
#CELL
  pure_quanta nc7sb3157 *
  page137_i109
#CELL
  pure_quanta q_cap *
  page137_i110
#ISCELL
  logical_power universal_power *
  page137_i111
#CELL
  pure_quanta q_cap *
  page137_i112
#ISCELL
  logical_power universal_gnd *
  page137_i113
#ISCELL
  standard offpage *
  page137_i114
#ISCELL
  standard offpage *
  page137_i115
#CELL
  pure_quanta q_res *
  page137_i116
#ISCELL
  logical_power universal_gnd *
  page137_i117
#ISCELL
  logical_power universal_power *
  page137_i118
#ISCELL
  standard offpage *
  page137_i119
#CELL
  pure_quanta 74cbtlv3126pw *
  page137_i84
#ISCELL
  standard offpage *
  page137_i85
#ISCELL
  standard offpage *
  page137_i86
#CELL
  pure_quanta q_res *
  page137_i87
#CELL
  pure_quanta q_res *
  page137_i88
#ISCELL
  logical_power universal_power *
  page137_i89
#CELL
  pure_quanta q_cap *
  page137_i90
#ISCELL
  logical_power universal_gnd *
  page137_i91
#ISCELL
  logical_power universal_gnd *
  page137_i92
#ISCELL
  logical_power universal_power *
  page137_i93
#ISCELL
  logical_power universal_gnd *
  page137_i94
#CELL
  pure_quanta q_cap *
  page137_i95
#CELL
  pure_quanta mosfet_n *
  page137_i96
#CELL
  pure_quanta q_res *
  page137_i97
#CELL
  pure_quanta q_res *
  page137_i98
#ISCELL
  pure_quanta quanta_title_block_c *
  *
#ISCELL
  pure_quanta quanta_title_block_c *
  *
#ISCELL
  logical_power universal_gnd *
  page142_i1
#ISCELL
  standard offpage *
  page142_i10
#ISCELL
  standard offpage *
  page142_i11
#ISCELL
  standard offpage *
  page142_i12
#ISCELL
  standard offpage *
  page142_i13
#ISCELL
  standard offpage *
  page142_i14
#ISCELL
  standard offpage *
  page142_i15
#ISCELL
  standard offpage *
  page142_i16
#ISCELL
  standard offpage *
  page142_i17
#ISCELL
  standard offpage *
  page142_i18
#ISCELL
  standard offpage *
  page142_i19
#ISCELL
  standard offpage *
  page142_i2
#ISCELL
  standard offpage *
  page142_i20
#ISCELL
  standard offpage *
  page142_i21
#ISCELL
  standard offpage *
  page142_i22
#ISCELL
  standard offpage *
  page142_i23
#ISCELL
  standard offpage *
  page142_i24
#ISCELL
  standard offpage *
  page142_i25
#ISCELL
  standard offpage *
  page142_i26
#ISCELL
  standard offpage *
  page142_i27
#ISCELL
  standard offpage *
  page142_i28
#ISCELL
  standard offpage *
  page142_i29
#ISCELL
  standard offpage *
  page142_i3
#ISCELL
  standard offpage *
  page142_i30
#ISCELL
  standard offpage *
  page142_i31
#ISCELL
  standard offpage *
  page142_i32
#ISCELL
  standard offpage *
  page142_i33
#ISCELL
  logical_power universal_gnd *
  page142_i34
#ISCELL
  standard offpage *
  page142_i35
#ISCELL
  standard offpage *
  page142_i36
#ISCELL
  standard offpage *
  page142_i37
#ISCELL
  standard offpage *
  page142_i38
#ISCELL
  standard offpage *
  page142_i39
#ISCELL
  standard offpage *
  page142_i4
#ISCELL
  standard offpage *
  page142_i40
#ISCELL
  standard offpage *
  page142_i41
#ISCELL
  standard offpage *
  page142_i42
#ISCELL
  standard offpage *
  page142_i43
#ISCELL
  standard offpage *
  page142_i44
#ISCELL
  standard offpage *
  page142_i45
#ISCELL
  standard offpage *
  page142_i46
#ISCELL
  standard offpage *
  page142_i47
#ISCELL
  standard offpage *
  page142_i48
#ISCELL
  standard offpage *
  page142_i49
#ISCELL
  standard offpage *
  page142_i5
#ISCELL
  standard offpage *
  page142_i50
#ISCELL
  standard offpage *
  page142_i51
#ISCELL
  standard offpage *
  page142_i52
#ISCELL
  standard offpage *
  page142_i53
#ISCELL
  standard offpage *
  page142_i54
#ISCELL
  standard offpage *
  page142_i55
#ISCELL
  standard offpage *
  page142_i56
#ISCELL
  standard offpage *
  page142_i57
#ISCELL
  standard offpage *
  page142_i58
#ISCELL
  standard offpage *
  page142_i59
#ISCELL
  standard offpage *
  page142_i6
#ISCELL
  standard offpage *
  page142_i60
#ISCELL
  standard offpage *
  page142_i61
#ISCELL
  standard offpage *
  page142_i62
#ISCELL
  standard offpage *
  page142_i63
#ISCELL
  standard offpage *
  page142_i64
#CELL
  pure_quanta conn112_10137002101lf *
  page142_i65
#ISCELL
  standard offpage *
  page142_i66
#ISCELL
  standard offpage *
  page142_i67
#CELL
  pure_quanta conn112_10137002101lf *
  page142_i68
#ISCELL
  standard offpage *
  page142_i7
#ISCELL
  standard offpage *
  page142_i8
#ISCELL
  standard offpage *
  page142_i80
#ISCELL
  standard offpage *
  page142_i83
#ISCELL
  standard offpage *
  page142_i84
#ISCELL
  standard offpage *
  page142_i85
#ISCELL
  standard offpage *
  page142_i86
#ISCELL
  standard offpage *
  page142_i87
#ISCELL
  standard offpage *
  page142_i88
#ISCELL
  standard offpage *
  page142_i89
#ISCELL
  standard offpage *
  page142_i9
#ISCELL
  pure_quanta quanta_title_block_c *
  *
#ISCELL
  standard offpage *
  page144_i1
#ISCELL
  standard offpage *
  page144_i10
#ISCELL
  standard offpage *
  page144_i11
#ISCELL
  standard offpage *
  page144_i12
#ISCELL
  standard offpage *
  page144_i13
#ISCELL
  standard offpage *
  page144_i14
#ISCELL
  standard offpage *
  page144_i15
#ISCELL
  standard offpage *
  page144_i16
#ISCELL
  logical_power universal_gnd *
  page144_i17
#ISCELL
  standard offpage *
  page144_i18
#ISCELL
  standard offpage *
  page144_i19
#ISCELL
  standard offpage *
  page144_i2
#ISCELL
  standard offpage *
  page144_i20
#ISCELL
  standard offpage *
  page144_i21
#ISCELL
  standard offpage *
  page144_i22
#ISCELL
  standard offpage *
  page144_i23
#ISCELL
  standard offpage *
  page144_i24
#ISCELL
  standard offpage *
  page144_i25
#ISCELL
  standard offpage *
  page144_i26
#ISCELL
  standard offpage *
  page144_i27
#ISCELL
  standard offpage *
  page144_i28
#ISCELL
  standard offpage *
  page144_i29
#ISCELL
  standard offpage *
  page144_i3
#ISCELL
  standard offpage *
  page144_i30
#ISCELL
  standard offpage *
  page144_i31
#ISCELL
  standard offpage *
  page144_i32
#ISCELL
  standard offpage *
  page144_i33
#ISCELL
  standard offpage *
  page144_i34
#ISCELL
  standard offpage *
  page144_i35
#ISCELL
  standard offpage *
  page144_i36
#ISCELL
  standard offpage *
  page144_i37
#ISCELL
  standard offpage *
  page144_i38
#ISCELL
  standard offpage *
  page144_i39
#ISCELL
  standard offpage *
  page144_i4
#ISCELL
  standard offpage *
  page144_i40
#ISCELL
  standard offpage *
  page144_i41
#ISCELL
  standard offpage *
  page144_i42
#ISCELL
  standard offpage *
  page144_i43
#ISCELL
  standard offpage *
  page144_i44
#ISCELL
  standard offpage *
  page144_i45
#ISCELL
  standard offpage *
  page144_i46
#ISCELL
  standard offpage *
  page144_i47
#ISCELL
  logical_power universal_gnd *
  page144_i48
#ISCELL
  standard offpage *
  page144_i49
#ISCELL
  standard offpage *
  page144_i5
#ISCELL
  standard offpage *
  page144_i50
#ISCELL
  standard offpage *
  page144_i51
#ISCELL
  standard offpage *
  page144_i52
#ISCELL
  standard offpage *
  page144_i53
#ISCELL
  standard offpage *
  page144_i54
#ISCELL
  standard offpage *
  page144_i55
#ISCELL
  standard offpage *
  page144_i56
#ISCELL
  standard offpage *
  page144_i57
#ISCELL
  standard offpage *
  page144_i58
#ISCELL
  standard offpage *
  page144_i59
#ISCELL
  standard offpage *
  page144_i6
#ISCELL
  standard offpage *
  page144_i60
#ISCELL
  standard offpage *
  page144_i61
#ISCELL
  standard offpage *
  page144_i62
#ISCELL
  standard offpage *
  page144_i63
#ISCELL
  standard offpage *
  page144_i64
#CELL
  pure_quanta conn112_10137002101lf *
  page144_i65
#ISCELL
  standard offpage *
  page144_i66
#ISCELL
  standard offpage *
  page144_i67
#CELL
  pure_quanta conn112_10137002101lf *
  page144_i68
#ISCELL
  standard offpage *
  page144_i7
#ISCELL
  standard offpage *
  page144_i8
#ISCELL
  standard offpage *
  page144_i82
#ISCELL
  standard offpage *
  page144_i85
#ISCELL
  standard offpage *
  page144_i86
#ISCELL
  standard offpage *
  page144_i88
#ISCELL
  standard offpage *
  page144_i89
#ISCELL
  standard offpage *
  page144_i9
#ISCELL
  standard offpage *
  page144_i90
#ISCELL
  standard offpage *
  page144_i91
#ISCELL
  pure_quanta quanta_title_block_c *
  *
#ISCELL
  standard offpage *
  page317_i1
#ISCELL
  standard offpage *
  page317_i10
#ISCELL
  standard offpage *
  page317_i12
#ISCELL
  standard offpage *
  page317_i13
#ISCELL
  standard offpage *
  page317_i14
#ISCELL
  standard offpage *
  page317_i15
#ISCELL
  standard offpage *
  page317_i16
#ISCELL
  standard offpage *
  page317_i17
#ISCELL
  standard offpage *
  page317_i18
#ISCELL
  logical_power universal_gnd *
  page317_i19
#ISCELL
  standard offpage *
  page317_i2
#ISCELL
  standard offpage *
  page317_i20
#ISCELL
  standard offpage *
  page317_i21
#ISCELL
  standard offpage *
  page317_i22
#ISCELL
  standard offpage *
  page317_i23
#ISCELL
  standard offpage *
  page317_i24
#ISCELL
  standard offpage *
  page317_i27
#ISCELL
  standard offpage *
  page317_i28
#ISCELL
  standard offpage *
  page317_i29
#ISCELL
  standard offpage *
  page317_i3
#ISCELL
  standard offpage *
  page317_i30
#ISCELL
  standard offpage *
  page317_i31
#ISCELL
  standard offpage *
  page317_i32
#ISCELL
  standard offpage *
  page317_i33
#ISCELL
  standard offpage *
  page317_i34
#ISCELL
  standard offpage *
  page317_i35
#ISCELL
  standard offpage *
  page317_i36
#ISCELL
  standard offpage *
  page317_i37
#CELL
  pure_quanta conn112_10137002101lf *
  page317_i38
#ISCELL
  standard offpage *
  page317_i39
#ISCELL
  standard offpage *
  page317_i4
#ISCELL
  standard offpage *
  page317_i40
#ISCELL
  standard offpage *
  page317_i41
#ISCELL
  standard offpage *
  page317_i42
#ISCELL
  standard offpage *
  page317_i43
#ISCELL
  standard offpage *
  page317_i44
#ISCELL
  standard offpage *
  page317_i45
#ISCELL
  standard offpage *
  page317_i46
#ISCELL
  standard offpage *
  page317_i49
#ISCELL
  standard offpage *
  page317_i5
#ISCELL
  standard offpage *
  page317_i50
#ISCELL
  standard offpage *
  page317_i51
#ISCELL
  standard offpage *
  page317_i52
#ISCELL
  standard offpage *
  page317_i53
#ISCELL
  standard offpage *
  page317_i54
#ISCELL
  standard offpage *
  page317_i55
#ISCELL
  standard offpage *
  page317_i56
#ISCELL
  logical_power universal_gnd *
  page317_i57
#CELL
  pure_quanta conn112_10137002101lf *
  page317_i58
#ISCELL
  standard offpage *
  page317_i59
#ISCELL
  standard offpage *
  page317_i6
#ISCELL
  standard offpage *
  page317_i60
#ISCELL
  standard offpage *
  page317_i61
#ISCELL
  standard offpage *
  page317_i62
#ISCELL
  standard offpage *
  page317_i63
#ISCELL
  standard offpage *
  page317_i64
#ISCELL
  standard offpage *
  page317_i65
#ISCELL
  standard offpage *
  page317_i66
#ISCELL
  standard offpage *
  page317_i69
#ISCELL
  standard offpage *
  page317_i70
#ISCELL
  standard offpage *
  page317_i71
#ISCELL
  standard offpage *
  page317_i72
#ISCELL
  standard offpage *
  page317_i73
#ISCELL
  standard offpage *
  page317_i74
#ISCELL
  standard offpage *
  page317_i75
#ISCELL
  standard offpage *
  page317_i76
#ISCELL
  standard offpage *
  page317_i77
#ISCELL
  standard offpage *
  page317_i78
#ISCELL
  standard offpage *
  page317_i79
#ISCELL
  standard offpage *
  page317_i8
#ISCELL
  standard offpage *
  page317_i9
#ISCELL
  pure_quanta quanta_title_block_c *
  *
#ISCELL
  standard offpage *
  page320_i1
#ISCELL
  standard offpage *
  page320_i10
#ISCELL
  standard offpage *
  page320_i11
#ISCELL
  standard offpage *
  page320_i13
#ISCELL
  standard offpage *
  page320_i14
#ISCELL
  standard offpage *
  page320_i15
#ISCELL
  standard offpage *
  page320_i16
#ISCELL
  standard offpage *
  page320_i17
#ISCELL
  standard offpage *
  page320_i18
#ISCELL
  logical_power universal_gnd *
  page320_i19
#ISCELL
  standard offpage *
  page320_i2
#ISCELL
  standard offpage *
  page320_i20
#ISCELL
  standard offpage *
  page320_i21
#ISCELL
  standard offpage *
  page320_i22
#ISCELL
  standard offpage *
  page320_i23
#ISCELL
  standard offpage *
  page320_i24
#ISCELL
  standard offpage *
  page320_i25
#ISCELL
  standard offpage *
  page320_i26
#ISCELL
  standard offpage *
  page320_i27
#ISCELL
  standard offpage *
  page320_i3
#ISCELL
  standard offpage *
  page320_i30
#ISCELL
  standard offpage *
  page320_i31
#ISCELL
  standard offpage *
  page320_i32
#ISCELL
  standard offpage *
  page320_i33
#ISCELL
  standard offpage *
  page320_i34
#ISCELL
  standard offpage *
  page320_i35
#ISCELL
  standard offpage *
  page320_i36
#ISCELL
  standard offpage *
  page320_i37
#ISCELL
  standard offpage *
  page320_i38
#ISCELL
  standard offpage *
  page320_i39
#ISCELL
  standard offpage *
  page320_i4
#ISCELL
  standard offpage *
  page320_i40
#ISCELL
  standard offpage *
  page320_i41
#ISCELL
  standard offpage *
  page320_i42
#ISCELL
  standard offpage *
  page320_i43
#ISCELL
  standard offpage *
  page320_i44
#ISCELL
  standard offpage *
  page320_i45
#ISCELL
  standard offpage *
  page320_i47
#ISCELL
  standard offpage *
  page320_i48
#ISCELL
  standard offpage *
  page320_i5
#ISCELL
  standard offpage *
  page320_i50
#ISCELL
  standard offpage *
  page320_i51
#ISCELL
  standard offpage *
  page320_i52
#ISCELL
  standard offpage *
  page320_i53
#ISCELL
  standard offpage *
  page320_i54
#ISCELL
  standard offpage *
  page320_i55
#ISCELL
  logical_power universal_gnd *
  page320_i56
#CELL
  pure_quanta conn112_10137002101lf *
  page320_i57
#ISCELL
  standard offpage *
  page320_i58
#ISCELL
  standard offpage *
  page320_i59
#ISCELL
  standard offpage *
  page320_i6
#ISCELL
  standard offpage *
  page320_i60
#ISCELL
  standard offpage *
  page320_i61
#ISCELL
  standard offpage *
  page320_i62
#ISCELL
  standard offpage *
  page320_i63
#ISCELL
  standard offpage *
  page320_i65
#ISCELL
  standard offpage *
  page320_i67
#ISCELL
  standard offpage *
  page320_i68
#ISCELL
  standard offpage *
  page320_i69
#ISCELL
  standard offpage *
  page320_i7
#ISCELL
  standard offpage *
  page320_i70
#ISCELL
  standard offpage *
  page320_i71
#ISCELL
  standard offpage *
  page320_i72
#ISCELL
  standard offpage *
  page320_i73
#ISCELL
  standard offpage *
  page320_i74
#ISCELL
  standard offpage *
  page320_i75
#CELL
  pure_quanta conn112_10137002101lf *
  page320_i76
#ISCELL
  standard offpage *
  page320_i77
#ISCELL
  standard offpage *
  page320_i78
#ISCELL
  standard offpage *
  page320_i79
#ISCELL
  standard offpage *
  page320_i8
#ISCELL
  standard offpage *
  page320_i80
#ISCELL
  standard offpage *
  page320_i81
#ISCELL
  pure_quanta quanta_title_block_c *
  *
#ISCELL
  standard offpage *
  page319_i1
#ISCELL
  standard offpage *
  page319_i11
#ISCELL
  standard offpage *
  page319_i12
#ISCELL
  standard offpage *
  page319_i13
#ISCELL
  standard offpage *
  page319_i14
#ISCELL
  logical_power universal_gnd *
  page319_i15
#ISCELL
  standard offpage *
  page319_i16
#ISCELL
  standard offpage *
  page319_i17
#ISCELL
  standard offpage *
  page319_i18
#ISCELL
  standard offpage *
  page319_i19
#ISCELL
  standard offpage *
  page319_i2
#ISCELL
  standard offpage *
  page319_i20
#ISCELL
  standard offpage *
  page319_i21
#ISCELL
  standard offpage *
  page319_i22
#ISCELL
  standard offpage *
  page319_i23
#ISCELL
  standard offpage *
  page319_i24
#ISCELL
  standard offpage *
  page319_i25
#ISCELL
  standard offpage *
  page319_i26
#ISCELL
  standard offpage *
  page319_i27
#ISCELL
  standard offpage *
  page319_i3
#ISCELL
  standard offpage *
  page319_i30
#ISCELL
  standard offpage *
  page319_i31
#ISCELL
  standard offpage *
  page319_i32
#ISCELL
  standard offpage *
  page319_i33
#ISCELL
  standard offpage *
  page319_i34
#ISCELL
  standard offpage *
  page319_i35
#ISCELL
  standard offpage *
  page319_i36
#ISCELL
  standard offpage *
  page319_i37
#ISCELL
  standard offpage *
  page319_i38
#ISCELL
  standard offpage *
  page319_i39
#ISCELL
  standard offpage *
  page319_i4
#ISCELL
  standard offpage *
  page319_i40
#ISCELL
  standard offpage *
  page319_i41
#ISCELL
  standard offpage *
  page319_i42
#ISCELL
  standard offpage *
  page319_i43
#ISCELL
  standard offpage *
  page319_i44
#ISCELL
  standard offpage *
  page319_i45
#ISCELL
  standard offpage *
  page319_i47
#ISCELL
  standard offpage *
  page319_i49
#ISCELL
  standard offpage *
  page319_i5
#ISCELL
  standard offpage *
  page319_i50
#ISCELL
  standard offpage *
  page319_i51
#ISCELL
  logical_power universal_gnd *
  page319_i52
#CELL
  pure_quanta conn112_10137002101lf *
  page319_i53
#ISCELL
  standard offpage *
  page319_i54
#ISCELL
  standard offpage *
  page319_i55
#ISCELL
  standard offpage *
  page319_i56
#ISCELL
  standard offpage *
  page319_i57
#ISCELL
  standard offpage *
  page319_i58
#ISCELL
  standard offpage *
  page319_i59
#ISCELL
  standard offpage *
  page319_i6
#ISCELL
  standard offpage *
  page319_i60
#ISCELL
  standard offpage *
  page319_i61
#ISCELL
  standard offpage *
  page319_i62
#ISCELL
  standard offpage *
  page319_i63
#ISCELL
  standard offpage *
  page319_i64
#ISCELL
  standard offpage *
  page319_i65
#ISCELL
  standard offpage *
  page319_i68
#ISCELL
  standard offpage *
  page319_i69
#ISCELL
  standard offpage *
  page319_i7
#ISCELL
  standard offpage *
  page319_i70
#ISCELL
  standard offpage *
  page319_i71
#ISCELL
  standard offpage *
  page319_i72
#ISCELL
  standard offpage *
  page319_i73
#ISCELL
  standard offpage *
  page319_i74
#ISCELL
  standard offpage *
  page319_i75
#CELL
  pure_quanta conn112_10137002101lf *
  page319_i76
#ISCELL
  standard offpage *
  page319_i8
#ISCELL
  standard offpage *
  page319_i83
#ISCELL
  standard offpage *
  page319_i84
#ISCELL
  standard offpage *
  page319_i85
#ISCELL
  standard offpage *
  page319_i86
#ISCELL
  standard offpage *
  page319_i87
#ISCELL
  standard offpage *
  page319_i88
#ISCELL
  standard offpage *
  page319_i89
#ISCELL
  standard offpage *
  page319_i90
#ISCELL
  pure_quanta quanta_title_block_c *
  *
#ISCELL
  standard offpage *
  page318_i1
#ISCELL
  standard offpage *
  page318_i11
#ISCELL
  standard offpage *
  page318_i12
#ISCELL
  standard offpage *
  page318_i13
#ISCELL
  standard offpage *
  page318_i14
#ISCELL
  logical_power universal_gnd *
  page318_i15
#CELL
  pure_quanta conn112_10137002101lf *
  page318_i16
#ISCELL
  standard offpage *
  page318_i17
#ISCELL
  standard offpage *
  page318_i18
#ISCELL
  standard offpage *
  page318_i19
#ISCELL
  standard offpage *
  page318_i2
#ISCELL
  standard offpage *
  page318_i20
#ISCELL
  standard offpage *
  page318_i21
#ISCELL
  standard offpage *
  page318_i22
#ISCELL
  standard offpage *
  page318_i23
#ISCELL
  standard offpage *
  page318_i24
#ISCELL
  standard offpage *
  page318_i25
#ISCELL
  standard offpage *
  page318_i26
#ISCELL
  standard offpage *
  page318_i27
#ISCELL
  standard offpage *
  page318_i28
#ISCELL
  standard offpage *
  page318_i3
#ISCELL
  standard offpage *
  page318_i31
#ISCELL
  standard offpage *
  page318_i32
#ISCELL
  standard offpage *
  page318_i33
#ISCELL
  standard offpage *
  page318_i34
#ISCELL
  standard offpage *
  page318_i35
#ISCELL
  standard offpage *
  page318_i36
#ISCELL
  standard offpage *
  page318_i37
#ISCELL
  standard offpage *
  page318_i38
#ISCELL
  standard offpage *
  page318_i39
#ISCELL
  standard offpage *
  page318_i4
#ISCELL
  standard offpage *
  page318_i40
#ISCELL
  standard offpage *
  page318_i41
#ISCELL
  standard offpage *
  page318_i42
#ISCELL
  standard offpage *
  page318_i43
#ISCELL
  standard offpage *
  page318_i44
#ISCELL
  standard offpage *
  page318_i45
#ISCELL
  standard offpage *
  page318_i46
#ISCELL
  standard offpage *
  page318_i49
#ISCELL
  standard offpage *
  page318_i5
#ISCELL
  standard offpage *
  page318_i50
#ISCELL
  standard offpage *
  page318_i51
#ISCELL
  standard offpage *
  page318_i52
#ISCELL
  logical_power universal_gnd *
  page318_i53
#CELL
  pure_quanta conn112_10137002101lf *
  page318_i54
#ISCELL
  standard offpage *
  page318_i55
#ISCELL
  standard offpage *
  page318_i56
#ISCELL
  standard offpage *
  page318_i57
#ISCELL
  standard offpage *
  page318_i58
#ISCELL
  standard offpage *
  page318_i59
#ISCELL
  standard offpage *
  page318_i6
#ISCELL
  standard offpage *
  page318_i60
#ISCELL
  standard offpage *
  page318_i61
#ISCELL
  standard offpage *
  page318_i62
#ISCELL
  standard offpage *
  page318_i63
#ISCELL
  standard offpage *
  page318_i64
#ISCELL
  standard offpage *
  page318_i65
#ISCELL
  standard offpage *
  page318_i66
#ISCELL
  standard offpage *
  page318_i69
#ISCELL
  standard offpage *
  page318_i7
#ISCELL
  standard offpage *
  page318_i70
#ISCELL
  standard offpage *
  page318_i71
#ISCELL
  standard offpage *
  page318_i72
#ISCELL
  standard offpage *
  page318_i73
#ISCELL
  standard offpage *
  page318_i74
#ISCELL
  standard offpage *
  page318_i75
#ISCELL
  standard offpage *
  page318_i76
#ISCELL
  standard offpage *
  page318_i78
#ISCELL
  standard offpage *
  page318_i79
#ISCELL
  standard offpage *
  page318_i8
#ISCELL
  standard offpage *
  page318_i80
#ISCELL
  standard offpage *
  page318_i81
#ISCELL
  standard offpage *
  page318_i84
#ISCELL
  standard offpage *
  page318_i85
#ISCELL
  standard offpage *
  page318_i86
#ISCELL
  standard offpage *
  page318_i87
#ISCELL
  pure_quanta quanta_title_block_c *
  *
#ISCELL
  standard offpage *
  page148_i1
#ISCELL
  standard offpage *
  page148_i10
#ISCELL
  standard offpage *
  page148_i106
#ISCELL
  standard offpage *
  page148_i107
#ISCELL
  standard offpage *
  page148_i108
#ISCELL
  standard offpage *
  page148_i109
#ISCELL
  standard offpage *
  page148_i11
#ISCELL
  standard offpage *
  page148_i114
#ISCELL
  standard offpage *
  page148_i118
#ISCELL
  standard offpage *
  page148_i12
#ISCELL
  standard offpage *
  page148_i120
#ISCELL
  standard offpage *
  page148_i121
#ISCELL
  standard offpage *
  page148_i13
#ISCELL
  standard offpage *
  page148_i14
#ISCELL
  standard offpage *
  page148_i15
#ISCELL
  standard offpage *
  page148_i16
#ISCELL
  standard offpage *
  page148_i2
#ISCELL
  standard offpage *
  page148_i3
#ISCELL
  standard offpage *
  page148_i34
#ISCELL
  standard offpage *
  page148_i35
#ISCELL
  standard offpage *
  page148_i36
#ISCELL
  standard offpage *
  page148_i37
#ISCELL
  standard offpage *
  page148_i38
#ISCELL
  standard offpage *
  page148_i39
#ISCELL
  standard offpage *
  page148_i4
#ISCELL
  standard offpage *
  page148_i40
#ISCELL
  standard offpage *
  page148_i42
#ISCELL
  standard offpage *
  page148_i43
#ISCELL
  standard offpage *
  page148_i44
#ISCELL
  standard offpage *
  page148_i45
#ISCELL
  standard offpage *
  page148_i46
#ISCELL
  standard offpage *
  page148_i47
#ISCELL
  standard offpage *
  page148_i48
#ISCELL
  standard offpage *
  page148_i49
#ISCELL
  standard offpage *
  page148_i5
#ISCELL
  standard offpage *
  page148_i50
#ISCELL
  standard offpage *
  page148_i51
#ISCELL
  standard offpage *
  page148_i52
#ISCELL
  standard offpage *
  page148_i53
#ISCELL
  standard offpage *
  page148_i54
#ISCELL
  standard offpage *
  page148_i55
#ISCELL
  standard offpage *
  page148_i56
#ISCELL
  standard offpage *
  page148_i57
#ISCELL
  standard offpage *
  page148_i59
#ISCELL
  standard offpage *
  page148_i6
#ISCELL
  standard offpage *
  page148_i60
#ISCELL
  standard offpage *
  page148_i61
#ISCELL
  standard offpage *
  page148_i62
#ISCELL
  standard offpage *
  page148_i63
#ISCELL
  standard offpage *
  page148_i64
#ISCELL
  standard offpage *
  page148_i65
#ISCELL
  standard offpage *
  page148_i66
#ISCELL
  standard offpage *
  page148_i7
#ISCELL
  standard offpage *
  page148_i72
#CELL
  pure_quanta conn112_10137002101lf *
  page148_i74
#CELL
  pure_quanta conn112_10137002101lf *
  page148_i75
#ISCELL
  standard offpage *
  page148_i76
#ISCELL
  standard offpage *
  page148_i77
#ISCELL
  standard offpage *
  page148_i78
#ISCELL
  standard offpage *
  page148_i79
#ISCELL
  standard offpage *
  page148_i8
#ISCELL
  standard offpage *
  page148_i80
#ISCELL
  standard offpage *
  page148_i81
#ISCELL
  standard offpage *
  page148_i82
#ISCELL
  standard offpage *
  page148_i83
#ISCELL
  standard offpage *
  page148_i84
#ISCELL
  standard offpage *
  page148_i85
#ISCELL
  standard offpage *
  page148_i86
#ISCELL
  standard offpage *
  page148_i87
#ISCELL
  standard offpage *
  page148_i88
#ISCELL
  standard offpage *
  page148_i89
#ISCELL
  standard offpage *
  page148_i9
#ISCELL
  standard offpage *
  page148_i90
#ISCELL
  standard offpage *
  page148_i91
#ISCELL
  logical_power universal_gnd *
  page148_i92
#ISCELL
  logical_power universal_gnd *
  page148_i93
#ISCELL
  pure_quanta quanta_title_block_c *
  *
#ISCELL
  standard offpage *
  page149_i216
#ISCELL
  standard offpage *
  page149_i217
#ISCELL
  standard offpage *
  page149_i218
#ISCELL
  standard offpage *
  page149_i219
#ISCELL
  standard offpage *
  page149_i220
#ISCELL
  standard offpage *
  page149_i221
#ISCELL
  standard offpage *
  page149_i222
#ISCELL
  standard offpage *
  page149_i223
#ISCELL
  standard offpage *
  page149_i224
#ISCELL
  standard offpage *
  page149_i225
#ISCELL
  standard offpage *
  page149_i226
#ISCELL
  standard offpage *
  page149_i227
#ISCELL
  standard offpage *
  page149_i228
#ISCELL
  standard offpage *
  page149_i229
#ISCELL
  standard offpage *
  page149_i230
#ISCELL
  standard offpage *
  page149_i231
#ISCELL
  standard offpage *
  page149_i232
#ISCELL
  standard offpage *
  page149_i233
#ISCELL
  standard offpage *
  page149_i234
#ISCELL
  standard offpage *
  page149_i235
#ISCELL
  standard offpage *
  page149_i236
#ISCELL
  standard offpage *
  page149_i237
#ISCELL
  standard offpage *
  page149_i238
#ISCELL
  standard offpage *
  page149_i239
#ISCELL
  standard offpage *
  page149_i240
#ISCELL
  standard offpage *
  page149_i241
#ISCELL
  standard offpage *
  page149_i242
#ISCELL
  standard offpage *
  page149_i243
#ISCELL
  standard offpage *
  page149_i244
#ISCELL
  standard offpage *
  page149_i245
#ISCELL
  standard offpage *
  page149_i246
#ISCELL
  standard offpage *
  page149_i247
#ISCELL
  standard offpage *
  page149_i248
#ISCELL
  standard offpage *
  page149_i249
#ISCELL
  standard offpage *
  page149_i250
#ISCELL
  standard offpage *
  page149_i251
#ISCELL
  standard offpage *
  page149_i252
#ISCELL
  standard offpage *
  page149_i253
#ISCELL
  standard offpage *
  page149_i254
#ISCELL
  standard offpage *
  page149_i255
#ISCELL
  standard offpage *
  page149_i256
#ISCELL
  standard offpage *
  page149_i257
#ISCELL
  standard offpage *
  page149_i258
#ISCELL
  standard offpage *
  page149_i259
#ISCELL
  standard offpage *
  page149_i260
#ISCELL
  standard offpage *
  page149_i261
#ISCELL
  standard offpage *
  page149_i262
#ISCELL
  standard offpage *
  page149_i263
#ISCELL
  standard offpage *
  page149_i264
#ISCELL
  standard offpage *
  page149_i265
#ISCELL
  standard offpage *
  page149_i266
#ISCELL
  standard offpage *
  page149_i267
#ISCELL
  standard offpage *
  page149_i268
#ISCELL
  standard offpage *
  page149_i269
#ISCELL
  standard offpage *
  page149_i270
#ISCELL
  standard offpage *
  page149_i271
#ISCELL
  standard offpage *
  page149_i272
#ISCELL
  standard offpage *
  page149_i273
#ISCELL
  standard offpage *
  page149_i274
#ISCELL
  standard offpage *
  page149_i275
#ISCELL
  standard offpage *
  page149_i276
#ISCELL
  standard offpage *
  page149_i277
#ISCELL
  standard offpage *
  page149_i278
#ISCELL
  standard offpage *
  page149_i279
#ISCELL
  standard offpage *
  page149_i280
#ISCELL
  standard offpage *
  page149_i292
#ISCELL
  standard offpage *
  page149_i293
#ISCELL
  standard offpage *
  page149_i294
#ISCELL
  standard offpage *
  page149_i295
#ISCELL
  standard offpage *
  page149_i298
#ISCELL
  standard offpage *
  page149_i299
#ISCELL
  standard offpage *
  page149_i302
#ISCELL
  standard offpage *
  page149_i304
#ISCELL
  standard offpage *
  page149_i305
#ISCELL
  standard offpage *
  page149_i310
#ISCELL
  standard offpage *
  page149_i311
#ISCELL
  standard offpage *
  page149_i312
#ISCELL
  standard offpage *
  page149_i313
#ISCELL
  standard offpage *
  page149_i318
#ISCELL
  standard offpage *
  page149_i319
#ISCELL
  standard offpage *
  page149_i336
#ISCELL
  standard offpage *
  page149_i337
#ISCELL
  standard offpage *
  page149_i338
#ISCELL
  standard offpage *
  page149_i339
#ISCELL
  standard offpage *
  page149_i340
#ISCELL
  standard offpage *
  page149_i341
#ISCELL
  standard offpage *
  page149_i342
#ISCELL
  standard offpage *
  page149_i343
#ISCELL
  standard offpage *
  page149_i344
#ISCELL
  standard offpage *
  page149_i345
#ISCELL
  standard offpage *
  page149_i346
#ISCELL
  standard offpage *
  page149_i347
#ISCELL
  standard offpage *
  page149_i348
#ISCELL
  standard offpage *
  page149_i349
#ISCELL
  standard offpage *
  page149_i350
#ISCELL
  standard offpage *
  page149_i351
#ISCELL
  standard offpage *
  page149_i352
#ISCELL
  standard offpage *
  page149_i353
#CELL
  pure_quanta conn160_10131762101lf *
  page149_i75
#CELL
  pure_quanta conn160_10131762101lf *
  page149_i76
#ISCELL
  logical_power universal_gnd *
  page149_i77
#ISCELL
  logical_power universal_gnd *
  page149_i78
#ISCELL
  mstr_misc dns *
  *
#ISCELL
  pure_quanta quanta_title_block_c *
  *
#ISCELL
  standard offpage *
  page147_i1
#CELL
  pure_quanta q_res *
  page147_i11
#ISCELL
  logical_power universal_gnd *
  page147_i13
#ISCELL
  standard offpage *
  page147_i14
#CELL
  pure_quanta q_cap *
  page147_i15
#ISCELL
  logical_power universal_gnd *
  page147_i16
#ISCELL
  logical_power universal_power *
  page147_i17
#CELL
  pure_quanta q_res *
  page147_i18
#ISCELL
  logical_power universal_gnd *
  page147_i19
#ISCELL
  standard offpage *
  page147_i2
#CELL
  pure_quanta mosfet_nch_dual *
  page147_i20
#ISCELL
  standard offpage *
  page147_i21
#CELL
  pure_quanta q_cap *
  page147_i22
#ISCELL
  logical_power universal_gnd *
  page147_i23
#ISCELL
  logical_power universal_power *
  page147_i24
#CELL
  pure_quanta q_res *
  page147_i25
#CELL
  pure_quanta mosfet_nch_dual *
  page147_i26
#ISCELL
  logical_power universal_gnd *
  page147_i27
#CELL
  pure_quanta q_res *
  page147_i28
#ISCELL
  logical_power universal_power *
  page147_i29
#ISCELL
  standard offpage *
  page147_i3
#ISCELL
  logical_power universal_gnd *
  page147_i30
#CELL
  pure_quanta mosfet_nch_dual *
  page147_i31
#ISCELL
  logical_power universal_power *
  page147_i32
#CELL
  pure_quanta q_res *
  page147_i33
#CELL
  pure_quanta q_res *
  page147_i34
#ISCELL
  logical_power universal_power *
  page147_i35
#CELL
  pure_quanta q_res *
  page147_i36
#ISCELL
  logical_power universal_gnd *
  page147_i37
#CELL
  pure_quanta mosfet_nch_dual *
  page147_i38
#ISCELL
  logical_power universal_gnd *
  page147_i39
#ISCELL
  standard offpage *
  page147_i4
#ISCELL
  logical_power universal_power *
  page147_i40
#CELL
  pure_quanta q_res *
  page147_i41
#CELL
  pure_quanta q_res *
  page147_i42
#ISCELL
  logical_power universal_gnd *
  page147_i43
#ISCELL
  standard offpage *
  page147_i44
#ISCELL
  standard offpage *
  page147_i45
#ISCELL
  standard offpage *
  page147_i46
#CELL
  pure_quanta q_cap *
  page147_i47
#ISCELL
  logical_power universal_gnd *
  page147_i48
#ISCELL
  logical_power universal_power *
  page147_i49
#CELL
  pure_quanta q_res *
  page147_i5
#CELL
  pure_quanta q_res *
  page147_i50
#CELL
  pure_quanta mosfet_nch_dual *
  page147_i51
#ISCELL
  logical_power universal_gnd *
  page147_i52
#ISCELL
  logical_power universal_power *
  page147_i53
#CELL
  pure_quanta q_res *
  page147_i54
#CELL
  pure_quanta mosfet_nch_dual *
  page147_i55
#ISCELL
  logical_power universal_gnd *
  page147_i56
#ISCELL
  logical_power universal_power *
  page147_i57
#CELL
  pure_quanta q_res *
  page147_i58
#ISCELL
  standard offpage *
  page147_i59
#CELL
  pure_quanta q_res *
  page147_i6
#CELL
  pure_quanta q_res *
  page147_i60
#ISCELL
  logical_power universal_gnd *
  page147_i61
#CELL
  pure_quanta mosfet_nch_dual *
  page147_i62
#ISCELL
  standard offpage *
  page147_i63
#ISCELL
  logical_power universal_power *
  page147_i64
#CELL
  pure_quanta q_res *
  page147_i65
#CELL
  pure_quanta q_cap *
  page147_i66
#ISCELL
  logical_power universal_gnd *
  page147_i67
#ISCELL
  logical_power universal_gnd *
  page147_i68
#ISCELL
  logical_power universal_power *
  page147_i69
#CELL
  pure_quanta q_res *
  page147_i7
#CELL
  pure_quanta q_res *
  page147_i70
#CELL
  pure_quanta mosfet_nch_dual *
  page147_i71
#ISCELL
  logical_power universal_gnd *
  page147_i72
#ISCELL
  logical_power universal_power *
  page147_i74
#CELL
  pure_quanta q_res *
  page147_i75
#CELL
  pure_quanta q_res *
  page147_i76
#ISCELL
  logical_power universal_gnd *
  page147_i77
#ISCELL
  standard offpage *
  page147_i78
#CELL
  pure_quanta q_res *
  page147_i8
#ISCELL
  standard offpage *
  page147_i9
#ISCELL
  mstr_misc dns *
  *
#ISCELL
  pure_quanta quanta_title_block_c *
  *
#ISCELL
  standard offpage *
  page139_i1
#ISCELL
  logical_power universal_power *
  page139_i10
#ISCELL
  logical_power universal_gnd *
  page139_i100
#ISCELL
  logical_power universal_gnd *
  page139_i101
#ISCELL
  logical_power universal_gnd *
  page139_i102
#CELL
  pure_quanta q_res *
  page139_i107
#CELL
  pure_quanta q_res *
  page139_i108
#CELL
  pure_quanta q_res *
  page139_i109
#ISCELL
  logical_power universal_gnd *
  page139_i11
#CELL
  pure_quanta q_res *
  page139_i110
#ISCELL
  standard offpage *
  page139_i12
#CELL
  pure_quanta q_res *
  page139_i13
#CELL
  pure_quanta q_res *
  page139_i14
#ISCELL
  logical_power universal_power *
  page139_i15
#ISCELL
  logical_power universal_gnd *
  page139_i16
#CELL
  pure_quanta mosfet_nch_dual *
  page139_i17
#CELL
  pure_quanta q_res *
  page139_i18
#ISCELL
  logical_power universal_power *
  page139_i19
#CELL
  pure_quanta q_res *
  page139_i2
#ISCELL
  logical_power universal_gnd *
  page139_i20
#CELL
  pure_quanta mosfet_nch_dual *
  page139_i21
#CELL
  pure_quanta mosfet_nch_dual *
  page139_i22
#CELL
  pure_quanta q_res *
  page139_i23
#ISCELL
  logical_power universal_power *
  page139_i24
#CELL
  pure_quanta mosfet_nch_dual *
  page139_i25
#ISCELL
  logical_power universal_gnd *
  page139_i26
#CELL
  pure_quanta q_res *
  page139_i27
#CELL
  pure_quanta mosfet_nch_dual *
  page139_i28
#CELL
  pure_quanta mosfet_nch_dual *
  page139_i29
#ISCELL
  logical_power universal_gnd *
  page139_i3
#ISCELL
  logical_power universal_power *
  page139_i30
#ISCELL
  logical_power universal_gnd *
  page139_i31
#ISCELL
  logical_power universal_gnd *
  page139_i32
#CELL
  pure_quanta q_cap *
  page139_i33
#ISCELL
  logical_power universal_gnd *
  page139_i34
#CELL
  pure_quanta q_res *
  page139_i35
#ISCELL
  logical_power universal_power *
  page139_i36
#ISCELL
  logical_power universal_gnd *
  page139_i37
#ISCELL
  standard offpage *
  page139_i38
#CELL
  pure_quanta q_res *
  page139_i39
#CELL
  pure_quanta q_res *
  page139_i4
#ISCELL
  logical_power universal_power *
  page139_i40
#ISCELL
  logical_power universal_gnd *
  page139_i41
#CELL
  pure_quanta q_cap *
  page139_i42
#ISCELL
  logical_power universal_gnd *
  page139_i43
#CELL
  pure_quanta q_cap *
  page139_i44
#ISCELL
  standard offpage *
  page139_i45
#ISCELL
  standard offpage *
  page139_i46
#CELL
  pure_quanta q_res *
  page139_i47
#ISCELL
  logical_power universal_power *
  page139_i48
#ISCELL
  logical_power universal_power *
  page139_i49
#ISCELL
  standard offpage *
  page139_i5
#CELL
  pure_quanta q_res *
  page139_i50
#ISCELL
  standard offpage *
  page139_i51
#CELL
  pure_quanta q_cap *
  page139_i52
#ISCELL
  logical_power universal_gnd *
  page139_i53
#ISCELL
  logical_power universal_gnd *
  page139_i54
#CELL
  pure_quanta mosfet_nch_dual *
  page139_i55
#ISCELL
  logical_power universal_power *
  page139_i56
#CELL
  pure_quanta q_res *
  page139_i57
#ISCELL
  logical_power universal_power *
  page139_i58
#ISCELL
  logical_power universal_power *
  page139_i6
#ISCELL
  logical_power universal_gnd *
  page139_i60
#CELL
  pure_quanta mosfet_nch_dual *
  page139_i61
#CELL
  pure_quanta q_res *
  page139_i62
#ISCELL
  logical_power universal_gnd *
  page139_i63
#ISCELL
  standard offpage *
  page139_i64
#ISCELL
  logical_power universal_gnd *
  page139_i7
#CELL
  pure_quanta q_res *
  page139_i8
#CELL
  pure_quanta q_res *
  page139_i85
#CELL
  pure_quanta 74lvc2g17gw *
  page139_i86
#CELL
  pure_quanta q_res *
  page139_i87
#ISCELL
  logical_power universal_power *
  page139_i88
#CELL
  pure_quanta q_res *
  page139_i89
#CELL
  pure_quanta q_res *
  page139_i9
#ISCELL
  logical_power universal_gnd *
  page139_i90
#ISCELL
  standard offpage *
  page139_i91
#ISCELL
  logical_power universal_gnd *
  page139_i92
#CELL
  pure_quanta q_cap *
  page139_i93
#ISCELL
  logical_power universal_power *
  page139_i94
#ISCELL
  standard offpage *
  page139_i95
#ISCELL
  logical_power universal_power *
  page139_i96
#CELL
  pure_quanta q_res *
  page139_i98
#CELL
  pure_quanta q_res *
  page139_i99
#ISCELL
  mstr_misc dns *
  *
#ISCELL
  pure_quanta quanta_title_block_c *
  *
#ISCELL
  standard offpage *
  page143_i1
#ISCELL
  logical_power universal_gnd *
  page143_i10
#CELL
  pure_quanta q_res *
  page143_i100
#CELL
  pure_quanta q_res *
  page143_i101
#ISCELL
  standard offpage *
  page143_i102
#ISCELL
  logical_power universal_power *
  page143_i103
#ISCELL
  logical_power universal_gnd *
  page143_i104
#CELL
  pure_quanta q_cap *
  page143_i105
#ISCELL
  logical_power universal_gnd *
  page143_i106
#CELL
  pure_quanta mosfet_nch_dual *
  page143_i107
#ISCELL
  logical_power universal_power *
  page143_i108
#ISCELL
  logical_power universal_gnd *
  page143_i109
#CELL
  pure_quanta mosfet_nch_dual *
  page143_i11
#ISCELL
  logical_power universal_power *
  page143_i110
#ISCELL
  standard offpage *
  page143_i112
#CELL
  pure_quanta q_res *
  page143_i113
#ISCELL
  logical_power universal_gnd *
  page143_i114
#CELL
  pure_quanta q_res *
  page143_i116
#ISCELL
  standard offpage *
  page143_i117
#CELL
  pure_quanta q_cap *
  page143_i118
#ISCELL
  logical_power universal_gnd *
  page143_i119
#ISCELL
  logical_power universal_power *
  page143_i12
#ISCELL
  logical_power universal_power *
  page143_i120
#CELL
  pure_quanta mosfet_nch_dual *
  page143_i121
#ISCELL
  logical_power universal_gnd *
  page143_i122
#ISCELL
  logical_power universal_power *
  page143_i123
#CELL
  pure_quanta q_res *
  page143_i124
#ISCELL
  logical_power universal_gnd *
  page143_i125
#CELL
  pure_quanta mosfet_nch_dual *
  page143_i126
#ISCELL
  logical_power universal_power *
  page143_i127
#CELL
  pure_quanta q_res *
  page143_i129
#CELL
  pure_quanta q_res *
  page143_i13
#ISCELL
  logical_power universal_gnd *
  page143_i130
#ISCELL
  standard offpage *
  page143_i131
#CELL
  pure_quanta q_res *
  page143_i132
#CELL
  pure_quanta q_res *
  page143_i136
#CELL
  pure_quanta q_res *
  page143_i137
#CELL
  pure_quanta q_res *
  page143_i138
#CELL
  pure_quanta q_res *
  page143_i139
#CELL
  pure_quanta q_res *
  page143_i14
#CELL
  pure_quanta q_res *
  page143_i140
#CELL
  pure_quanta q_res *
  page143_i141
#CELL
  pure_quanta q_res *
  page143_i142
#CELL
  pure_quanta q_res *
  page143_i143
#CELL
  pure_quanta q_res *
  page143_i144
#CELL
  pure_quanta q_res *
  page143_i145
#ISCELL
  standard offpage *
  page143_i15
#ISCELL
  logical_power universal_gnd *
  page143_i16
#CELL
  pure_quanta mosfet_nch_dual *
  page143_i19
#CELL
  pure_quanta q_cap *
  page143_i2
#ISCELL
  logical_power universal_power *
  page143_i20
#CELL
  pure_quanta q_res *
  page143_i21
#ISCELL
  standard offpage *
  page143_i22
#CELL
  pure_quanta q_cap *
  page143_i23
#ISCELL
  logical_power universal_gnd *
  page143_i24
#ISCELL
  logical_power universal_gnd *
  page143_i25
#ISCELL
  logical_power universal_power *
  page143_i26
#CELL
  pure_quanta q_res *
  page143_i27
#ISCELL
  logical_power universal_gnd *
  page143_i28
#CELL
  pure_quanta mosfet_nch_dual *
  page143_i29
#ISCELL
  logical_power universal_gnd *
  page143_i3
#ISCELL
  logical_power universal_power *
  page143_i30
#CELL
  pure_quanta q_res *
  page143_i31
#CELL
  pure_quanta q_res *
  page143_i32
#ISCELL
  standard offpage *
  page143_i33
#ISCELL
  logical_power universal_gnd *
  page143_i34
#CELL
  pure_quanta mosfet_nch_dual *
  page143_i35
#CELL
  pure_quanta q_res *
  page143_i36
#ISCELL
  logical_power universal_power *
  page143_i37
#ISCELL
  logical_power universal_power *
  page143_i38
#ISCELL
  standard offpage *
  page143_i39
#ISCELL
  logical_power universal_power *
  page143_i4
#CELL
  pure_quanta q_cap *
  page143_i40
#ISCELL
  logical_power universal_gnd *
  page143_i41
#ISCELL
  logical_power universal_gnd *
  page143_i42
#CELL
  pure_quanta q_res *
  page143_i43
#CELL
  pure_quanta mosfet_nch_dual *
  page143_i44
#ISCELL
  logical_power universal_gnd *
  page143_i45
#ISCELL
  logical_power universal_power *
  page143_i46
#ISCELL
  standard offpage *
  page143_i48
#CELL
  pure_quanta q_res *
  page143_i49
#CELL
  pure_quanta q_res *
  page143_i5
#ISCELL
  logical_power universal_gnd *
  page143_i50
#ISCELL
  logical_power universal_power *
  page143_i51
#CELL
  pure_quanta q_res *
  page143_i52
#ISCELL
  standard offpage *
  page143_i53
#ISCELL
  standard offpage *
  page143_i54
#CELL
  pure_quanta q_cap *
  page143_i55
#ISCELL
  logical_power universal_gnd *
  page143_i56
#CELL
  pure_quanta q_cap *
  page143_i57
#ISCELL
  logical_power universal_gnd *
  page143_i58
#ISCELL
  logical_power universal_power *
  page143_i59
#CELL
  pure_quanta mosfet_nch_dual *
  page143_i6
#CELL
  pure_quanta q_res *
  page143_i60
#ISCELL
  standard offpage *
  page143_i61
#ISCELL
  logical_power universal_power *
  page143_i62
#ISCELL
  logical_power universal_gnd *
  page143_i63
#CELL
  pure_quanta q_res *
  page143_i64
#ISCELL
  logical_power universal_gnd *
  page143_i65
#CELL
  pure_quanta q_cap *
  page143_i66
#ISCELL
  logical_power universal_gnd *
  page143_i67
#ISCELL
  logical_power universal_gnd *
  page143_i68
#ISCELL
  logical_power universal_power *
  page143_i69
#ISCELL
  logical_power universal_gnd *
  page143_i7
#CELL
  pure_quanta mosfet_nch_dual *
  page143_i70
#CELL
  pure_quanta mosfet_nch_dual *
  page143_i71
#CELL
  pure_quanta q_res *
  page143_i72
#ISCELL
  logical_power universal_gnd *
  page143_i73
#CELL
  pure_quanta mosfet_nch_dual *
  page143_i74
#ISCELL
  logical_power universal_power *
  page143_i75
#CELL
  pure_quanta q_res *
  page143_i76
#CELL
  pure_quanta mosfet_nch_dual *
  page143_i77
#CELL
  pure_quanta mosfet_nch_dual *
  page143_i78
#ISCELL
  logical_power universal_gnd *
  page143_i79
#ISCELL
  logical_power universal_power *
  page143_i8
#ISCELL
  logical_power universal_power *
  page143_i80
#CELL
  pure_quanta q_res *
  page143_i81
#ISCELL
  logical_power universal_gnd *
  page143_i82
#CELL
  pure_quanta mosfet_nch_dual *
  page143_i83
#ISCELL
  logical_power universal_power *
  page143_i84
#CELL
  pure_quanta q_res *
  page143_i85
#CELL
  pure_quanta q_res *
  page143_i86
#ISCELL
  standard offpage *
  page143_i87
#ISCELL
  logical_power universal_gnd *
  page143_i88
#ISCELL
  logical_power universal_power *
  page143_i89
#CELL
  pure_quanta q_res *
  page143_i9
#CELL
  pure_quanta q_res *
  page143_i91
#ISCELL
  logical_power universal_gnd *
  page143_i92
#ISCELL
  logical_power universal_power *
  page143_i93
#ISCELL
  standard offpage *
  page143_i94
#CELL
  pure_quanta q_res *
  page143_i95
#CELL
  pure_quanta q_res *
  page143_i96
#ISCELL
  logical_power universal_gnd *
  page143_i97
#ISCELL
  standard offpage *
  page143_i98
#CELL
  pure_quanta mosfet_nch_dual *
  page143_i99
#ISCELL
  mstr_misc dns *
  *
#ISCELL
  pure_quanta quanta_title_block_c *
  *
#ISCELL
  standard offpage *
  page299_i1
#ISCELL
  logical_power universal_power *
  page299_i10
#ISCELL
  logical_power universal_gnd *
  page299_i11
#ISCELL
  standard offpage *
  page299_i12
#CELL
  pure_quanta q_cap *
  page299_i129
#CELL
  pure_quanta q_res *
  page299_i130
#CELL
  pure_quanta q_res *
  page299_i131
#CELL
  pure_quanta q_res *
  page299_i132
#CELL
  pure_quanta q_res *
  page299_i133
#CELL
  pure_quanta q_res *
  page299_i134
#CELL
  pure_quanta mosfet_nch_dual *
  page299_i135
#ISCELL
  logical_power universal_power *
  page299_i138
#ISCELL
  logical_power universal_gnd *
  page299_i139
#ISCELL
  standard offpage *
  page299_i143
#CELL
  pure_quanta q_res *
  page299_i144
#CELL
  pure_quanta q_res *
  page299_i145
#ISCELL
  logical_power universal_gnd *
  page299_i146
#CELL
  pure_quanta q_res *
  page299_i147
#ISCELL
  logical_power universal_gnd *
  page299_i148
#ISCELL
  standard offpage *
  page299_i149
#ISCELL
  logical_power universal_power *
  page299_i15
#ISCELL
  logical_power universal_power *
  page299_i150
#ISCELL
  standard offpage *
  page299_i151
#CELL
  pure_quanta q_cap *
  page299_i152
#ISCELL
  logical_power universal_gnd *
  page299_i153
#CELL
  pure_quanta q_res *
  page299_i154
#ISCELL
  logical_power universal_power *
  page299_i155
#ISCELL
  logical_power universal_gnd *
  page299_i156
#CELL
  pure_quanta mosfet_nch_dual *
  page299_i157
#CELL
  pure_quanta q_res *
  page299_i158
#ISCELL
  logical_power universal_gnd *
  page299_i159
#ISCELL
  logical_power universal_gnd *
  page299_i16
#CELL
  pure_quanta mosfet_nch_dual *
  page299_i160
#ISCELL
  logical_power universal_power *
  page299_i161
#CELL
  pure_quanta q_res *
  page299_i163
#ISCELL
  logical_power universal_gnd *
  page299_i164
#ISCELL
  standard offpage *
  page299_i165
#CELL
  pure_quanta q_res *
  page299_i166
#CELL
  pure_quanta q_res *
  page299_i167
#CELL
  pure_quanta mosfet_nch_dual *
  page299_i168
#CELL
  pure_quanta mosfet_nch_dual *
  page299_i169
#CELL
  pure_quanta q_res *
  page299_i17
#ISCELL
  standard offpage *
  page299_i170
#CELL
  pure_quanta q_cap *
  page299_i171
#ISCELL
  logical_power universal_gnd *
  page299_i172
#ISCELL
  logical_power universal_power *
  page299_i173
#CELL
  pure_quanta q_res *
  page299_i174
#ISCELL
  logical_power universal_gnd *
  page299_i175
#ISCELL
  logical_power universal_power *
  page299_i176
#CELL
  pure_quanta q_res *
  page299_i177
#ISCELL
  logical_power universal_gnd *
  page299_i178
#ISCELL
  logical_power universal_power *
  page299_i179
#ISCELL
  standard offpage *
  page299_i18
#CELL
  pure_quanta q_res *
  page299_i181
#ISCELL
  logical_power universal_gnd *
  page299_i182
#ISCELL
  standard offpage *
  page299_i183
#CELL
  pure_quanta q_res *
  page299_i184
#ISCELL
  standard offpage *
  page299_i185
#ISCELL
  logical_power universal_gnd *
  page299_i2
#ISCELL
  logical_power universal_power *
  page299_i20
#CELL
  pure_quanta mosfet_nch_dual *
  page299_i21
#ISCELL
  logical_power universal_gnd *
  page299_i22
#CELL
  pure_quanta q_res *
  page299_i23
#ISCELL
  logical_power universal_power *
  page299_i24
#ISCELL
  logical_power universal_gnd *
  page299_i25
#CELL
  pure_quanta mosfet_nch_dual *
  page299_i26
#CELL
  pure_quanta q_res *
  page299_i27
#ISCELL
  logical_power universal_power *
  page299_i28
#ISCELL
  logical_power universal_gnd *
  page299_i29
#CELL
  pure_quanta q_res *
  page299_i3
#CELL
  pure_quanta q_cap *
  page299_i30
#ISCELL
  standard offpage *
  page299_i31
#CELL
  pure_quanta mosfet_nch_dual *
  page299_i37
#ISCELL
  logical_power universal_gnd *
  page299_i38
#CELL
  pure_quanta q_res *
  page299_i39
#CELL
  pure_quanta mosfet_nch_dual *
  page299_i40
#ISCELL
  logical_power universal_power *
  page299_i41
#ISCELL
  logical_power universal_gnd *
  page299_i42
#CELL
  pure_quanta mosfet_nch_dual *
  page299_i43
#ISCELL
  logical_power universal_gnd *
  page299_i44
#CELL
  pure_quanta q_res *
  page299_i45
#ISCELL
  logical_power universal_power *
  page299_i46
#ISCELL
  logical_power universal_gnd *
  page299_i47
#CELL
  pure_quanta mosfet_nch_dual *
  page299_i48
#CELL
  pure_quanta q_res *
  page299_i49
#ISCELL
  logical_power universal_power *
  page299_i5
#ISCELL
  logical_power universal_power *
  page299_i50
#ISCELL
  logical_power universal_gnd *
  page299_i51
#CELL
  pure_quanta mosfet_nch_dual *
  page299_i52
#CELL
  pure_quanta q_res *
  page299_i53
#ISCELL
  logical_power universal_power *
  page299_i54
#CELL
  pure_quanta q_res *
  page299_i55
#ISCELL
  logical_power universal_power *
  page299_i56
#CELL
  pure_quanta mosfet_nch_dual *
  page299_i57
#ISCELL
  logical_power universal_gnd *
  page299_i58
#CELL
  pure_quanta q_res *
  page299_i59
#ISCELL
  standard offpage *
  page299_i6
#ISCELL
  logical_power universal_gnd *
  page299_i60
#ISCELL
  logical_power universal_gnd *
  page299_i61
#ISCELL
  standard offpage *
  page299_i62
#ISCELL
  logical_power universal_gnd *
  page299_i7
#CELL
  pure_quanta q_cap *
  page299_i71
#ISCELL
  standard offpage *
  page299_i72
#ISCELL
  logical_power universal_gnd *
  page299_i73
#CELL
  pure_quanta q_cap *
  page299_i74
#ISCELL
  standard offpage *
  page299_i75
#ISCELL
  logical_power universal_power *
  page299_i83
#ISCELL
  mstr_misc dns *
  *
#ISCELL
  pure_quanta quanta_title_block_c *
  *
#ISCELL
  logical_power universal_gnd *
  page145_i10
#CELL
  pure_quanta mosfet_nch_dual *
  page145_i100
#CELL
  pure_quanta q_res *
  page145_i101
#ISCELL
  logical_power universal_power *
  page145_i102
#ISCELL
  logical_power universal_gnd *
  page145_i103
#ISCELL
  logical_power universal_gnd *
  page145_i104
#CELL
  pure_quanta q_cap *
  page145_i105
#ISCELL
  standard offpage *
  page145_i106
#ISCELL
  logical_power universal_gnd *
  page145_i108
#CELL
  pure_quanta q_res *
  page145_i109
#ISCELL
  logical_power universal_gnd *
  page145_i11
#ISCELL
  logical_power universal_power *
  page145_i110
#CELL
  pure_quanta q_cap *
  page145_i111
#ISCELL
  logical_power universal_gnd *
  page145_i112
#ISCELL
  logical_power universal_gnd *
  page145_i113
#CELL
  pure_quanta q_cap *
  page145_i114
#ISCELL
  logical_power universal_gnd *
  page145_i115
#CELL
  pure_quanta q_cap *
  page145_i116
#CELL
  pure_quanta mosfet_nch_dual *
  page145_i117
#CELL
  pure_quanta mosfet_nch_dual *
  page145_i118
#CELL
  pure_quanta mosfet_nch_dual *
  page145_i119
#ISCELL
  logical_power universal_gnd *
  page145_i12
#CELL
  pure_quanta mosfet_nch_dual *
  page145_i120
#CELL
  pure_quanta mosfet_nch_dual *
  page145_i121
#CELL
  pure_quanta mosfet_nch_dual *
  page145_i122
#ISCELL
  logical_power universal_power *
  page145_i123
#ISCELL
  standard offpage *
  page145_i124
#CELL
  pure_quanta q_cap *
  page145_i125
#ISCELL
  logical_power universal_gnd *
  page145_i126
#CELL
  pure_quanta q_res *
  page145_i127
#ISCELL
  logical_power universal_power *
  page145_i128
#CELL
  pure_quanta q_res *
  page145_i129
#ISCELL
  logical_power universal_power *
  page145_i13
#ISCELL
  logical_power universal_gnd *
  page145_i130
#ISCELL
  logical_power universal_gnd *
  page145_i131
#ISCELL
  logical_power universal_power *
  page145_i132
#CELL
  pure_quanta q_res *
  page145_i134
#ISCELL
  logical_power universal_gnd *
  page145_i135
#ISCELL
  standard offpage *
  page145_i136
#ISCELL
  standard offpage *
  page145_i137
#ISCELL
  logical_power universal_gnd *
  page145_i138
#CELL
  pure_quanta q_res *
  page145_i139
#CELL
  pure_quanta q_res *
  page145_i14
#ISCELL
  logical_power universal_power *
  page145_i141
#ISCELL
  logical_power universal_gnd *
  page145_i142
#ISCELL
  logical_power universal_gnd *
  page145_i143
#CELL
  pure_quanta q_res *
  page145_i144
#ISCELL
  logical_power universal_power *
  page145_i145
#CELL
  pure_quanta q_res *
  page145_i146
#ISCELL
  logical_power universal_gnd *
  page145_i147
#CELL
  pure_quanta q_cap *
  page145_i148
#ISCELL
  standard offpage *
  page145_i149
#ISCELL
  logical_power universal_power *
  page145_i150
#CELL
  pure_quanta mosfet_nch_dual *
  page145_i151
#CELL
  pure_quanta mosfet_nch_dual *
  page145_i152
#ISCELL
  logical_power universal_power *
  page145_i153
#CELL
  pure_quanta mosfet_nch_dual *
  page145_i154
#ISCELL
  standard offpage *
  page145_i155
#CELL
  pure_quanta q_cap *
  page145_i156
#ISCELL
  logical_power universal_gnd *
  page145_i157
#CELL
  pure_quanta q_res *
  page145_i158
#CELL
  pure_quanta mosfet_nch_dual *
  page145_i159
#ISCELL
  logical_power universal_power *
  page145_i16
#ISCELL
  logical_power universal_gnd *
  page145_i160
#ISCELL
  logical_power universal_power *
  page145_i161
#CELL
  pure_quanta q_res *
  page145_i162
#ISCELL
  logical_power universal_gnd *
  page145_i163
#ISCELL
  logical_power universal_power *
  page145_i164
#ISCELL
  logical_power universal_gnd *
  page145_i167
#ISCELL
  standard offpage *
  page145_i168
#ISCELL
  standard offpage *
  page145_i169
#CELL
  pure_quanta q_res *
  page145_i171
#CELL
  pure_quanta q_res *
  page145_i172
#CELL
  pure_quanta q_res *
  page145_i173
#CELL
  pure_quanta q_res *
  page145_i174
#CELL
  pure_quanta q_res *
  page145_i175
#CELL
  pure_quanta q_res *
  page145_i176
#CELL
  pure_quanta q_res *
  page145_i18
#CELL
  pure_quanta q_res *
  page145_i19
#ISCELL
  logical_power universal_power *
  page145_i21
#ISCELL
  standard offpage *
  page145_i22
#ISCELL
  logical_power universal_gnd *
  page145_i23
#CELL
  pure_quanta q_res *
  page145_i24
#ISCELL
  logical_power universal_power *
  page145_i25
#ISCELL
  standard offpage *
  page145_i28
#ISCELL
  logical_power universal_gnd *
  page145_i29
#CELL
  pure_quanta q_res *
  page145_i30
#ISCELL
  logical_power universal_power *
  page145_i31
#CELL
  pure_quanta mosfet_nch_dual *
  page145_i33
#CELL
  pure_quanta mosfet_nch_dual *
  page145_i35
#CELL
  pure_quanta mosfet_nch_dual *
  page145_i37
#ISCELL
  logical_power universal_power *
  page145_i46
#ISCELL
  logical_power universal_power *
  page145_i47
#ISCELL
  logical_power universal_power *
  page145_i49
#ISCELL
  logical_power universal_power *
  page145_i51
#ISCELL
  logical_power universal_power *
  page145_i53
#ISCELL
  logical_power universal_gnd *
  page145_i55
#CELL
  pure_quanta q_res *
  page145_i56
#ISCELL
  logical_power universal_gnd *
  page145_i57
#CELL
  pure_quanta q_res *
  page145_i58
#ISCELL
  logical_power universal_gnd *
  page145_i59
#ISCELL
  standard offpage *
  page145_i6
#CELL
  pure_quanta q_res *
  page145_i60
#ISCELL
  logical_power universal_gnd *
  page145_i61
#CELL
  pure_quanta q_res *
  page145_i62
#ISCELL
  logical_power universal_gnd *
  page145_i63
#CELL
  pure_quanta q_res *
  page145_i66
#CELL
  pure_quanta q_res *
  page145_i67
#CELL
  pure_quanta q_res *
  page145_i68
#ISCELL
  standard offpage *
  page145_i7
#ISCELL
  standard offpage *
  page145_i8
#CELL
  pure_quanta q_res *
  page145_i80
#CELL
  pure_quanta mosfet_nch_dual *
  page145_i82
#ISCELL
  logical_power universal_gnd *
  page145_i83
#CELL
  pure_quanta q_res *
  page145_i84
#ISCELL
  logical_power universal_power *
  page145_i85
#ISCELL
  standard offpage *
  page145_i86
#ISCELL
  standard offpage *
  page145_i87
#CELL
  pure_quanta mosfet_nch_dual *
  page145_i88
#ISCELL
  logical_power universal_gnd *
  page145_i89
#ISCELL
  logical_power universal_power *
  page145_i90
#CELL
  pure_quanta q_res *
  page145_i91
#CELL
  pure_quanta q_cap *
  page145_i92
#ISCELL
  logical_power universal_gnd *
  page145_i93
#ISCELL
  standard offpage *
  page145_i94
#ISCELL
  logical_power universal_gnd *
  page145_i96
#CELL
  pure_quanta q_res *
  page145_i97
#ISCELL
  logical_power universal_power *
  page145_i98
#ISCELL
  standard offpage *
  page145_i99
#ISCELL
  mstr_misc dns *
  *
#ISCELL
  pure_quanta quanta_title_block_c *
  *
#CELL
  pure_quanta q_res *
  page160_i123
#CELL
  pure_quanta q_res *
  page160_i124
#ISCELL
  logical_power universal_power *
  page160_i125
#ISCELL
  logical_power universal_gnd *
  page160_i126
#CELL
  pure_quanta q_res *
  page160_i127
#ISCELL
  logical_power universal_gnd *
  page160_i137
#ISCELL
  logical_power universal_gnd *
  page160_i138
#CELL
  pure_quanta q_res *
  page160_i139
#ISCELL
  standard offpage *
  page160_i146
#CELL
  pure_quanta q_cap *
  page160_i148
#ISCELL
  logical_power universal_gnd *
  page160_i149
#CELL
  pure_quanta 74lvc2g17gw *
  page160_i153
#ISCELL
  logical_power universal_power *
  page160_i154
#ISCELL
  logical_power universal_gnd *
  page160_i16
#ISCELL
  standard offpage *
  page160_i161
#ISCELL
  logical_power universal_power *
  page160_i163
#CELL
  pure_quanta q_res *
  page160_i164
#CELL
  pure_quanta q_res *
  page160_i165
#ISCELL
  logical_power universal_gnd *
  page160_i166
#ISCELL
  logical_power universal_power *
  page160_i167
#CELL
  pure_quanta q_res *
  page160_i168
#ISCELL
  standard offpage *
  page160_i169
#CELL
  pure_quanta q_res *
  page160_i170
#ISCELL
  logical_power universal_gnd *
  page160_i171
#ISCELL
  standard offpage *
  page160_i172
#CELL
  pure_quanta 74lvc2g17gw *
  page160_i173
#ISCELL
  logical_power universal_power *
  page160_i174
#CELL
  pure_quanta q_cap *
  page160_i175
#ISCELL
  logical_power universal_gnd *
  page160_i176
#ISCELL
  logical_power universal_gnd *
  page160_i177
#ISCELL
  logical_power universal_gnd *
  page160_i178
#ISCELL
  standard offpage *
  page160_i179
#ISCELL
  standard offpage *
  page160_i18
#CELL
  pure_quanta q_res *
  page160_i181
#ISCELL
  standard offpage *
  page160_i182
#CELL
  pure_quanta q_res *
  page160_i184
#ISCELL
  logical_power universal_gnd *
  page160_i185
#ISCELL
  logical_power universal_power *
  page160_i186
#CELL
  pure_quanta q_res *
  page160_i187
#CELL
  pure_quanta q_res *
  page160_i188
#ISCELL
  logical_power universal_gnd *
  page160_i189
#ISCELL
  standard offpage *
  page160_i190
#ISCELL
  logical_power universal_power *
  page160_i191
#CELL
  pure_quanta q_res *
  page160_i192
#ISCELL
  standard offpage *
  page160_i194
#CELL
  pure_quanta q_res *
  page160_i195
#ISCELL
  logical_power universal_gnd *
  page160_i196
#CELL
  pure_quanta q_res *
  page160_i197
#CELL
  pure_quanta q_res *
  page160_i198
#CELL
  pure_quanta q_res *
  page160_i199
#ISCELL
  logical_power universal_power *
  page160_i20
#CELL
  pure_quanta q_res *
  page160_i200
#CELL
  pure_quanta q_res *
  page160_i201
#CELL
  pure_quanta q_res *
  page160_i202
#CELL
  pure_quanta 74lvc2g17gw *
  page160_i26
#ISCELL
  logical_power universal_gnd *
  page160_i27
#ISCELL
  logical_power universal_gnd *
  page160_i28
#CELL
  pure_quanta q_cap *
  page160_i29
#ISCELL
  logical_power universal_power *
  page160_i30
#ISCELL
  standard offpage *
  page160_i67
#CELL
  pure_quanta q_res *
  page160_i95
#ISCELL
  mstr_misc dns *
  *
#ISCELL
  pure_quanta quanta_title_block_c *
  *
#ISCELL
  logical_power universal_power *
  page296_i11
#ISCELL
  logical_power universal_gnd *
  page296_i12
#CELL
  pure_quanta q_cap *
  page296_i13
#CELL
  pure_quanta 74lvc2g07dw7 *
  page296_i16
#ISCELL
  logical_power universal_gnd *
  page296_i17
#ISCELL
  logical_power universal_power *
  page296_i28
#CELL
  pure_quanta q_res *
  page296_i29
#ISCELL
  logical_power universal_gnd *
  page296_i30
#CELL
  pure_quanta q_res *
  page296_i31
#ISCELL
  standard offpage *
  page296_i32
#CELL
  pure_quanta q_res *
  page296_i33
#ISCELL
  logical_power universal_power *
  page296_i34
#CELL
  pure_quanta q_res *
  page296_i35
#ISCELL
  standard offpage *
  page296_i36
#CELL
  pure_quanta q_res *
  page296_i37
#ISCELL
  logical_power universal_gnd *
  page296_i38
#ISCELL
  logical_power universal_power *
  page296_i39
#CELL
  pure_quanta q_res *
  page296_i40
#ISCELL
  standard offpage *
  page296_i41
#CELL
  pure_quanta q_res *
  page296_i42
#ISCELL
  logical_power universal_gnd *
  page296_i43
#ISCELL
  standard offpage *
  page296_i44
#CELL
  pure_quanta q_res *
  page296_i45
#ISCELL
  logical_power universal_power *
  page296_i46
#CELL
  pure_quanta q_res *
  page296_i47
#CELL
  pure_quanta q_res *
  page296_i48
#ISCELL
  logical_power universal_gnd *
  page296_i49
#CELL
  pure_quanta 74lvc2g07dw7 *
  page296_i50
#ISCELL
  standard offpage *
  page296_i51
#CELL
  pure_quanta q_res *
  page296_i53
#ISCELL
  logical_power universal_power *
  page296_i54
#CELL
  pure_quanta q_res *
  page296_i55
#ISCELL
  logical_power universal_power *
  page296_i56
#CELL
  pure_quanta q_res *
  page296_i57
#ISCELL
  standard offpage *
  page296_i58
#CELL
  pure_quanta q_res *
  page296_i62
#ISCELL
  logical_power universal_gnd *
  page296_i63
#ISCELL
  logical_power universal_power *
  page296_i66
#CELL
  pure_quanta q_cap *
  page296_i67
#ISCELL
  logical_power universal_gnd *
  page296_i68
#ISCELL
  logical_power universal_gnd *
  page296_i69
#CELL
  pure_quanta q_res *
  page296_i70
#ISCELL
  logical_power universal_gnd *
  page296_i74
#ISCELL
  mstr_misc dns *
  *
#ISCELL
  pure_quanta quanta_title_block_c *
  *
#CELL
  pure_quanta q_res *
  page140_i121
#ISCELL
  logical_power universal_gnd *
  page140_i122
#ISCELL
  logical_power universal_gnd *
  page140_i125
#CELL
  pure_quanta 74lvc2g17gw *
  page140_i127
#ISCELL
  standard offpage *
  page140_i129
#ISCELL
  logical_power universal_gnd *
  page140_i132
#ISCELL
  logical_power universal_power *
  page140_i139
#CELL
  pure_quanta q_cap *
  page140_i140
#ISCELL
  logical_power universal_gnd *
  page140_i141
#ISCELL
  logical_power universal_gnd *
  page140_i142
#ISCELL
  standard offpage *
  page140_i146
#CELL
  pure_quanta q_res *
  page140_i147
#ISCELL
  logical_power universal_power *
  page140_i148
#CELL
  pure_quanta q_res *
  page140_i153
#ISCELL
  logical_power universal_gnd *
  page140_i159
#CELL
  pure_quanta q_res *
  page140_i160
#ISCELL
  logical_power universal_power *
  page140_i161
#CELL
  pure_quanta q_res *
  page140_i162
#ISCELL
  logical_power universal_power *
  page140_i165
#CELL
  pure_quanta q_cap *
  page140_i166
#ISCELL
  logical_power universal_gnd *
  page140_i167
#CELL
  pure_quanta q_res *
  page140_i170
#ISCELL
  standard offpage *
  page140_i172
#ISCELL
  standard offpage *
  page140_i173
#ISCELL
  logical_power universal_power *
  page140_i174
#ISCELL
  standard offpage *
  page140_i177
#ISCELL
  logical_power universal_gnd *
  page140_i178
#ISCELL
  standard offpage *
  page140_i180
#ISCELL
  logical_power universal_power *
  page140_i183
#ISCELL
  logical_power universal_gnd *
  page140_i184
#CELL
  pure_quanta q_res *
  page140_i190
#CELL
  pure_quanta q_res *
  page140_i191
#CELL
  pure_quanta q_res *
  page140_i192
#CELL
  pure_quanta q_res *
  page140_i193
#CELL
  pure_quanta q_res *
  page140_i194
#CELL
  pure_quanta 74lvc1g126se7 *
  page140_i195
#ISCELL
  logical_power universal_gnd *
  page140_i196
#CELL
  pure_quanta q_res *
  page140_i197
#CELL
  pure_quanta q_res *
  page140_i198
#ISCELL
  logical_power universal_power *
  page140_i199
#CELL
  pure_quanta q_res *
  page140_i200
#ISCELL
  logical_power universal_power *
  page140_i201
#CELL
  pure_quanta q_res *
  page140_i202
#CELL
  pure_quanta q_res *
  page140_i203
#CELL
  pure_quanta q_res *
  page140_i204
#CELL
  pure_quanta q_res *
  page140_i205
#CELL
  pure_quanta q_res *
  page140_i206
#CELL
  pure_quanta q_res *
  page140_i207
#CELL
  pure_quanta q_res *
  page140_i208
#ISCELL
  standard offpage *
  page140_i209
#CELL
  pure_quanta 74lvc2g17gw *
  page140_i65
#ISCELL
  logical_power universal_power *
  page140_i67
#CELL
  pure_quanta q_res *
  page140_i68
#ISCELL
  logical_power universal_gnd *
  page140_i69
#ISCELL
  standard offpage *
  page140_i70
#ISCELL
  logical_power universal_power *
  page140_i71
#ISCELL
  logical_power universal_gnd *
  page140_i74
#ISCELL
  standard offpage *
  page140_i75
#ISCELL
  logical_power universal_gnd *
  page140_i76
#CELL
  pure_quanta q_res *
  page140_i78
#ISCELL
  standard offpage *
  page140_i79
#ISCELL
  logical_power universal_power *
  page140_i80
#ISCELL
  standard offpage *
  page140_i82
#ISCELL
  logical_power universal_power *
  page140_i83
#ISCELL
  logical_power universal_power *
  page140_i87
#ISCELL
  logical_power universal_gnd *
  page140_i88
#CELL
  pure_quanta q_cap *
  page140_i89
#CELL
  pure_quanta q_res *
  page140_i92
#CELL
  pure_quanta q_res *
  page140_i93
#ISCELL
  logical_power cad_note *
  *
#ISCELL
  mstr_misc dns *
  *
#ISCELL
  pure_quanta quanta_title_block_c *
  *
#CELL
  pure_quanta gl852gohy60 *
  page155_i100
#ISCELL
  logical_power universal_gnd *
  page155_i115
#ISCELL
  logical_power universal_gnd *
  page155_i116
#ISCELL
  logical_power universal_gnd *
  page155_i117
#ISCELL
  logical_power universal_gnd *
  page155_i118
#ISCELL
  logical_power universal_gnd *
  page155_i122
#ISCELL
  standard offpage *
  page155_i133
#ISCELL
  standard offpage *
  page155_i134
#ISCELL
  standard offpage *
  page155_i135
#ISCELL
  standard offpage *
  page155_i136
#CELL
  pure_quanta q_res *
  page155_i137
#CELL
  pure_quanta q_res *
  page155_i138
#CELL
  pure_quanta q_res *
  page155_i139
#ISCELL
  logical_power universal_gnd *
  page155_i140
#CELL
  pure_quanta q_cap *
  page155_i142
#CELL
  pure_quanta q_cap *
  page155_i143
#ISCELL
  logical_power universal_power *
  page155_i144
#CELL
  pure_quanta q_cap *
  page155_i145
#CELL
  pure_quanta q_cap *
  page155_i147
#CELL
  pure_quanta q_cap *
  page155_i148
#ISCELL
  logical_power universal_power *
  page155_i151
#CELL
  pure_quanta q_res *
  page155_i155
#ISCELL
  standard offpage *
  page155_i156
#ISCELL
  logical_power universal_gnd *
  page155_i157
#CELL
  pure_quanta q_cap *
  page155_i158
#CELL
  pure_quanta q_res *
  page155_i159
#CELL
  pure_quanta q_res *
  page155_i161
#CELL
  pure_quanta q_cap *
  page155_i162
#CELL
  pure_quanta q_cap *
  page155_i163
#CELL
  pure_quanta q_cap *
  page155_i164
#ISCELL
  logical_power universal_gnd *
  page155_i165
#ISCELL
  logical_power universal_gnd *
  page155_i166
#CELL
  pure_quanta q_res *
  page155_i167
#ISCELL
  standard offpage *
  page155_i168
#ISCELL
  standard offpage *
  page155_i169
#ISCELL
  standard offpage *
  page155_i170
#ISCELL
  standard offpage *
  page155_i171
#CELL
  pure_quanta q_res *
  page155_i182
#ISCELL
  logical_power universal_gnd *
  page155_i183
#ISCELL
  standard offpage *
  page155_i184
#ISCELL
  logical_power universal_power *
  page155_i185
#CELL
  pure_quanta q_res *
  page155_i186
#CELL
  pure_quanta q_res *
  page155_i187
#ISCELL
  logical_power universal_gnd *
  page155_i188
#ISCELL
  standard offpage *
  page155_i189
#ISCELL
  standard offpage *
  page155_i190
#ISCELL
  standard offpage *
  page155_i191
#ISCELL
  standard offpage *
  page155_i192
#ISCELL
  standard offpage *
  page155_i193
#CELL
  pure_quanta q_res *
  page155_i194
#CELL
  pure_quanta q_res *
  page155_i195
#CELL
  pure_quanta q_res *
  page155_i196
#ISCELL
  logical_power universal_power *
  page155_i197
#CELL
  pure_quanta q_res *
  page155_i198
#CELL
  pure_quanta q_res *
  page155_i199
#CELL
  pure_quanta q_xtal_4p_13bi_24gnd *
  page155_i200
#CELL
  pure_quanta q_res *
  page155_i201
#CELL
  pure_quanta q_res *
  page155_i202
#CELL
  pure_quanta q_res *
  page155_i203
#ISCELL
  logical_power universal_gnd *
  page155_i204
#ISCELL
  logical_power universal_gnd *
  page155_i205
#CELL
  pure_quanta q_res *
  page155_i206
#ISCELL
  logical_power universal_gnd *
  page155_i207
#CELL
  pure_quanta q_res *
  page155_i208
#ISCELL
  logical_power universal_gnd *
  page155_i209
#CELL
  pure_quanta q_cap *
  page155_i210
#CELL
  pure_quanta q_cap *
  page155_i211
#ISCELL
  standard offpage *
  page155_i76
#ISCELL
  standard offpage *
  page155_i77
#CELL
  pure_quanta q_res *
  page155_i78
#CELL
  pure_quanta q_res *
  page155_i79
#ISCELL
  logical_power universal_gnd *
  page155_i80
#CELL
  pure_quanta q_cap *
  page155_i81
#ISCELL
  logical_power universal_gnd *
  page155_i82
#CELL
  pure_quanta q_res *
  page155_i83
#CELL
  pure_quanta tusb211irwbr *
  page155_i84
#ISCELL
  logical_power universal_gnd *
  page155_i85
#ISCELL
  logical_power universal_gnd *
  page155_i86
#CELL
  pure_quanta q_cap *
  page155_i87
#CELL
  pure_quanta q_cap *
  page155_i88
#ISCELL
  logical_power universal_gnd *
  page155_i89
#CELL
  pure_quanta q_res *
  page155_i90
#CELL
  pure_quanta q_res *
  page155_i91
#CELL
  pure_quanta q_cap *
  page155_i92
#ISCELL
  standard offpage *
  page155_i93
#ISCELL
  standard offpage *
  page155_i94
#ISCELL
  logical_power universal_power *
  page155_i95
#CELL
  pure_quanta q_res *
  page155_i96
#CELL
  pure_quanta q_res *
  page155_i97
#CELL
  pure_quanta q_res *
  page155_i98
#CELL
  pure_quanta q_res *
  page155_i99
#ISCELL
  logical_power cad_note *
  *
#ISCELL
  mstr_misc dns *
  *
#ISCELL
  pure_quanta quanta_title_block_c *
  *
#ISCELL
  logical_power universal_gnd *
  page150_i1
#ISCELL
  standard offpage *
  page150_i10
#ISCELL
  standard tap *
  page150_i100
#ISCELL
  standard tap *
  page150_i101
#ISCELL
  standard tap *
  page150_i102
#ISCELL
  standard tap *
  page150_i103
#ISCELL
  standard tap *
  page150_i104
#ISCELL
  standard tap *
  page150_i105
#ISCELL
  standard tap *
  page150_i106
#ISCELL
  standard tap *
  page150_i107
#ISCELL
  standard tap *
  page150_i108
#ISCELL
  standard tap *
  page150_i109
#CELL
  pure_quanta q_cap *
  page150_i110
#CELL
  pure_quanta q_cap *
  page150_i111
#ISCELL
  logical_power universal_gnd *
  page150_i112
#CELL
  pure_quanta q_cap *
  page150_i113
#CELL
  pure_quanta q_cap *
  page150_i114
#CELL
  pure_quanta q_cap *
  page150_i115
#CELL
  pure_quanta q_cap *
  page150_i116
#ISCELL
  standard offpage *
  page150_i117
#CELL
  pure_quanta q_res *
  page150_i118
#CELL
  pure_quanta q_res *
  page150_i119
#ISCELL
  standard offpage *
  page150_i12
#ISCELL
  logical_power universal_power *
  page150_i120
#ISCELL
  standard offpage *
  page150_i121
#ISCELL
  standard offpage *
  page150_i122
#ISCELL
  standard tap *
  page150_i123
#ISCELL
  standard tap *
  page150_i124
#ISCELL
  standard tap *
  page150_i125
#ISCELL
  standard tap *
  page150_i126
#ISCELL
  standard tap *
  page150_i127
#ISCELL
  standard tap *
  page150_i128
#ISCELL
  standard tap *
  page150_i129
#ISCELL
  standard tap *
  page150_i130
#ISCELL
  standard tap *
  page150_i131
#ISCELL
  standard tap *
  page150_i132
#ISCELL
  standard tap *
  page150_i133
#ISCELL
  standard tap *
  page150_i134
#ISCELL
  standard tap *
  page150_i136
#ISCELL
  standard tap *
  page150_i137
#ISCELL
  standard tap *
  page150_i138
#ISCELL
  standard offpage *
  page150_i140
#CELL
  pure_quanta q_res *
  page150_i141
#ISCELL
  standard offpage *
  page150_i142
#ISCELL
  standard offpage *
  page150_i143
#ISCELL
  standard offpage *
  page150_i144
#ISCELL
  standard offpage *
  page150_i145
#ISCELL
  standard offpage *
  page150_i146
#ISCELL
  standard offpage *
  page150_i147
#ISCELL
  logical_power universal_gnd *
  page150_i148
#CELL
  pure_quanta q_res *
  page150_i149
#ISCELL
  standard offpage *
  page150_i15
#ISCELL
  standard offpage *
  page150_i150
#CELL
  pure_quanta q_res *
  page150_i151
#ISCELL
  standard offpage *
  page150_i152
#ISCELL
  standard offpage *
  page150_i153
#ISCELL
  standard offpage *
  page150_i154
#ISCELL
  standard offpage *
  page150_i155
#ISCELL
  standard offpage *
  page150_i156
#ISCELL
  standard offpage *
  page150_i157
#ISCELL
  standard offpage *
  page150_i158
#ISCELL
  standard offpage *
  page150_i159
#ISCELL
  standard offpage *
  page150_i16
#ISCELL
  standard offpage *
  page150_i160
#ISCELL
  standard offpage *
  page150_i161
#ISCELL
  standard offpage *
  page150_i162
#ISCELL
  standard offpage *
  page150_i163
#ISCELL
  standard offpage *
  page150_i164
#ISCELL
  logical_power universal_gnd *
  page150_i167
#CELL
  pure_quanta q_cap *
  page150_i168
#ISCELL
  standard tap *
  page150_i169
#ISCELL
  standard tap *
  page150_i17
#ISCELL
  standard offpage *
  page150_i171
#ISCELL
  logical_power universal_power *
  page150_i173
#ISCELL
  logical_power universal_power *
  page150_i174
#ISCELL
  standard tap *
  page150_i176
#ISCELL
  standard tap *
  page150_i177
#ISCELL
  standard tap *
  page150_i179
#ISCELL
  standard tap *
  page150_i180
#ISCELL
  standard tap *
  page150_i182
#ISCELL
  standard tap *
  page150_i183
#ISCELL
  standard tap *
  page150_i185
#ISCELL
  standard tap *
  page150_i186
#ISCELL
  standard tap *
  page150_i188
#ISCELL
  standard tap *
  page150_i189
#ISCELL
  standard tap *
  page150_i191
#ISCELL
  standard tap *
  page150_i192
#ISCELL
  standard tap *
  page150_i194
#ISCELL
  standard tap *
  page150_i195
#ISCELL
  standard tap *
  page150_i197
#ISCELL
  standard tap *
  page150_i198
#CELL
  pure_quanta sconn168_me1016810202011 *
  page150_i199
#CELL
  pure_quanta q_res *
  page150_i2
#ISCELL
  standard tap *
  page150_i20
#ISCELL
  standard tap *
  page150_i202
#ISCELL
  standard tap *
  page150_i203
#ISCELL
  standard tap *
  page150_i205
#ISCELL
  standard tap *
  page150_i206
#ISCELL
  standard tap *
  page150_i21
#ISCELL
  standard offpage *
  page150_i211
#CELL
  pure_quanta q_res *
  page150_i212
#ISCELL
  standard offpage *
  page150_i213
#CELL
  pure_quanta q_res *
  page150_i215
#CELL
  pure_quanta q_res *
  page150_i217
#CELL
  pure_quanta q_res *
  page150_i218
#ISCELL
  standard offpage *
  page150_i219
#ISCELL
  logical_power universal_gnd *
  page150_i25
#ISCELL
  standard tap *
  page150_i28
#ISCELL
  logical_power universal_gnd *
  page150_i3
#ISCELL
  standard tap *
  page150_i30
#ISCELL
  standard tap *
  page150_i32
#ISCELL
  logical_power universal_gnd *
  page150_i34
#CELL
  pure_quanta q_res *
  page150_i35
#CELL
  pure_quanta q_res *
  page150_i36
#CELL
  pure_quanta q_res *
  page150_i37
#ISCELL
  standard offpage *
  page150_i38
#ISCELL
  standard offpage *
  page150_i39
#CELL
  pure_quanta q_res *
  page150_i4
#ISCELL
  standard offpage *
  page150_i40
#ISCELL
  standard offpage *
  page150_i41
#ISCELL
  standard offpage *
  page150_i42
#ISCELL
  standard offpage *
  page150_i43
#ISCELL
  standard offpage *
  page150_i44
#ISCELL
  standard offpage *
  page150_i45
#ISCELL
  standard offpage *
  page150_i46
#ISCELL
  standard offpage *
  page150_i47
#ISCELL
  standard offpage *
  page150_i48
#CELL
  pure_quanta q_res *
  page150_i5
#ISCELL
  standard offpage *
  page150_i50
#CELL
  pure_quanta q_res *
  page150_i51
#CELL
  pure_quanta q_res *
  page150_i52
#CELL
  pure_quanta q_res *
  page150_i53
#CELL
  pure_quanta q_res *
  page150_i54
#ISCELL
  standard offpage *
  page150_i55
#CELL
  pure_quanta q_res *
  page150_i58
#ISCELL
  standard tap *
  page150_i59
#CELL
  pure_quanta q_res *
  page150_i6
#ISCELL
  standard tap *
  page150_i62
#ISCELL
  standard tap *
  page150_i63
#ISCELL
  standard tap *
  page150_i66
#ISCELL
  standard tap *
  page150_i69
#ISCELL
  logical_power universal_power *
  page150_i7
#ISCELL
  standard tap *
  page150_i70
#ISCELL
  standard tap *
  page150_i73
#ISCELL
  standard offpage *
  page150_i76
#ISCELL
  standard offpage *
  page150_i77
#ISCELL
  standard offpage *
  page150_i78
#ISCELL
  standard offpage *
  page150_i79
#ISCELL
  standard offpage *
  page150_i8
#ISCELL
  standard offpage *
  page150_i80
#ISCELL
  standard offpage *
  page150_i81
#ISCELL
  standard offpage *
  page150_i82
#ISCELL
  standard offpage *
  page150_i83
#ISCELL
  standard offpage *
  page150_i84
#ISCELL
  standard offpage *
  page150_i85
#ISCELL
  logical_power universal_gnd *
  page150_i88
#CELL
  pure_quanta q_cap *
  page150_i89
#ISCELL
  standard offpage *
  page150_i9
#CELL
  pure_quanta q_cap *
  page150_i90
#CELL
  pure_quanta q_cap *
  page150_i91
#ISCELL
  logical_power universal_power *
  page150_i92
#ISCELL
  logical_power universal_power *
  page150_i93
#ISCELL
  logical_power universal_gnd *
  page150_i94
#ISCELL
  standard tap *
  page150_i95
#ISCELL
  standard tap *
  page150_i96
#ISCELL
  standard tap *
  page150_i97
#ISCELL
  standard tap *
  page150_i98
#ISCELL
  standard tap *
  page150_i99
#ISCELL
  mstr_misc dns *
  *
#ISCELL
  pure_quanta quanta_title_block_c *
  *
#ISCELL
  standard offpage *
  page151_i1
#ISCELL
  standard offpage *
  page151_i10
#ISCELL
  logical_power universal_gnd *
  page151_i11
#ISCELL
  logical_power universal_gnd *
  page151_i12
#CELL
  pure_quanta q_res *
  page151_i13
#ISCELL
  standard offpage *
  page151_i14
#CELL
  pure_quanta 74lvc1g126se7 *
  page151_i15
#ISCELL
  logical_power universal_gnd *
  page151_i16
#CELL
  pure_quanta q_res *
  page151_i17
#CELL
  pure_quanta q_res *
  page151_i19
#ISCELL
  standard offpage *
  page151_i2
#ISCELL
  logical_power universal_gnd *
  page151_i20
#CELL
  pure_quanta q_res *
  page151_i21
#CELL
  pure_quanta q_cap *
  page151_i22
#ISCELL
  logical_power universal_gnd *
  page151_i23
#ISCELL
  logical_power universal_power *
  page151_i24
#ISCELL
  standard offpage *
  page151_i25
#ISCELL
  standard offpage *
  page151_i26
#ISCELL
  standard offpage *
  page151_i27
#ISCELL
  standard offpage *
  page151_i28
#ISCELL
  logical_power universal_gnd *
  page151_i29
#CELL
  pure_quanta q_res *
  page151_i3
#CELL
  pure_quanta 74cbtlv3126pw *
  page151_i30
#ISCELL
  logical_power universal_gnd *
  page151_i31
#CELL
  pure_quanta q_cap *
  page151_i32
#ISCELL
  logical_power universal_power *
  page151_i33
#ISCELL
  standard offpage *
  page151_i34
#ISCELL
  standard offpage *
  page151_i35
#ISCELL
  standard offpage *
  page151_i36
#ISCELL
  standard offpage *
  page151_i37
#ISCELL
  logical_power universal_gnd *
  page151_i38
#CELL
  pure_quanta 74cbtlv3126pw *
  page151_i39
#ISCELL
  standard offpage *
  page151_i4
#CELL
  pure_quanta q_cap *
  page151_i40
#ISCELL
  logical_power universal_gnd *
  page151_i41
#ISCELL
  logical_power universal_power *
  page151_i42
#CELL
  pure_quanta q_res *
  page151_i43
#ISCELL
  standard offpage *
  page151_i44
#ISCELL
  standard offpage *
  page151_i45
#ISCELL
  standard offpage *
  page151_i46
#ISCELL
  standard offpage *
  page151_i47
#ISCELL
  standard offpage *
  page151_i48
#ISCELL
  standard offpage *
  page151_i49
#CELL
  pure_quanta q_res *
  page151_i5
#CELL
  pure_quanta q_res *
  page151_i50
#ISCELL
  logical_power universal_gnd *
  page151_i51
#CELL
  pure_quanta q_res *
  page151_i52
#CELL
  pure_quanta q_res *
  page151_i53
#CELL
  pure_quanta q_res *
  page151_i54
#CELL
  pure_quanta q_res *
  page151_i55
#CELL
  pure_quanta q_res *
  page151_i56
#ISCELL
  standard offpage *
  page151_i57
#ISCELL
  standard offpage *
  page151_i58
#ISCELL
  standard offpage *
  page151_i59
#ISCELL
  logical_power universal_gnd *
  page151_i6
#ISCELL
  logical_power universal_gnd *
  page151_i60
#CELL
  pure_quanta q_res *
  page151_i61
#ISCELL
  standard offpage *
  page151_i62
#ISCELL
  standard offpage *
  page151_i63
#ISCELL
  standard offpage *
  page151_i64
#CELL
  pure_quanta q_res *
  page151_i65
#CELL
  pure_quanta q_res *
  page151_i66
#CELL
  pure_quanta q_res *
  page151_i67
#CELL
  pure_quanta q_res *
  page151_i68
#CELL
  pure_quanta q_res *
  page151_i69
#CELL
  pure_quanta 74lvc1g126se7 *
  page151_i7
#ISCELL
  standard offpage *
  page151_i70
#CELL
  pure_quanta q_res *
  page151_i71
#CELL
  pure_quanta q_res *
  page151_i72
#CELL
  pure_quanta q_res *
  page151_i73
#ISCELL
  standard offpage *
  page151_i74
#ISCELL
  standard offpage *
  page151_i75
#ISCELL
  standard offpage *
  page151_i76
#ISCELL
  standard offpage *
  page151_i77
#ISCELL
  standard offpage *
  page151_i78
#ISCELL
  standard offpage *
  page151_i79
#CELL
  pure_quanta q_cap *
  page151_i8
#CELL
  pure_quanta q_res *
  page151_i80
#CELL
  pure_quanta q_res *
  page151_i81
#ISCELL
  standard offpage *
  page151_i82
#CELL
  pure_quanta q_res *
  page151_i83
#ISCELL
  logical_power universal_power *
  page151_i9
#ISCELL
  logical_power cad_note *
  *
#ISCELL
  mstr_misc dns *
  *
#ISCELL
  pure_quanta quanta_title_block_c *
  *
#CELL
  pure_quanta 74lvc1g17gw *
  page152_i1
#CELL
  pure_quanta q_res *
  page152_i10
#ISCELL
  standard offpage *
  page152_i11
#ISCELL
  standard offpage *
  page152_i12
#CELL
  pure_quanta q_res *
  page152_i13
#ISCELL
  logical_power universal_gnd *
  page152_i14
#ISCELL
  standard offpage *
  page152_i2
#ISCELL
  standard offpage *
  page152_i21
#CELL
  pure_quanta q_cap *
  page152_i24
#ISCELL
  logical_power universal_gnd *
  page152_i25
#CELL
  pure_quanta q_res *
  page152_i26
#ISCELL
  standard offpage *
  page152_i29
#ISCELL
  logical_power universal_gnd *
  page152_i3
#ISCELL
  logical_power universal_gnd *
  page152_i32
#ISCELL
  logical_power universal_power *
  page152_i36
#CELL
  pure_quanta q_res *
  page152_i37
#ISCELL
  logical_power universal_power *
  page152_i38
#ISCELL
  standard offpage *
  page152_i39
#CELL
  pure_quanta q_cap *
  page152_i4
#CELL
  pure_quanta q_res *
  page152_i40
#ISCELL
  logical_power universal_power *
  page152_i41
#CELL
  pure_quanta q_res *
  page152_i42
#ISCELL
  logical_power universal_power *
  page152_i43
#CELL
  pure_quanta q_cap *
  page152_i44
#ISCELL
  logical_power universal_gnd *
  page152_i45
#CELL
  pure_quanta pi6cv304le *
  page152_i46
#ISCELL
  logical_power universal_power *
  page152_i47
#ISCELL
  logical_power universal_power *
  page152_i48
#CELL
  pure_quanta q_cap *
  page152_i49
#ISCELL
  logical_power universal_power *
  page152_i5
#ISCELL
  standard offpage *
  page152_i50
#ISCELL
  standard offpage *
  page152_i51
#CELL
  pure_quanta q_res *
  page152_i52
#CELL
  pure_quanta q_res *
  page152_i53
#ISCELL
  logical_power universal_gnd *
  page152_i54
#ISCELL
  logical_power universal_gnd *
  page152_i55
#CELL
  pure_quanta q_res *
  page152_i56
#ISCELL
  logical_power universal_gnd *
  page152_i57
#CELL
  pure_quanta q_cap *
  page152_i59
#CELL
  pure_quanta q_res *
  page152_i6
#ISCELL
  logical_power universal_gnd *
  page152_i60
#CELL
  pure_quanta q_res *
  page152_i61
#CELL
  pure_quanta q_res *
  page152_i62
#CELL
  pure_quanta 74lvc1g07gv *
  page152_i63
#CELL
  pure_quanta 74lvc1g07gv *
  page152_i65
#ISCELL
  logical_power universal_gnd *
  page152_i66
#ISCELL
  logical_power universal_power *
  page152_i67
#CELL
  pure_quanta q_cap *
  page152_i68
#ISCELL
  logical_power universal_gnd *
  page152_i69
#ISCELL
  standard offpage *
  page152_i7
#ISCELL
  standard offpage *
  page152_i70
#CELL
  pure_quanta q_res *
  page152_i71
#ISCELL
  logical_power universal_power *
  page152_i72
#ISCELL
  logical_power universal_power *
  page152_i73
#CELL
  pure_quanta q_res *
  page152_i74
#CELL
  pure_quanta q_res *
  page152_i75
#CELL
  pure_quanta q_osc4p *
  page152_i76
#ISCELL
  standard offpage *
  page152_i77
#CELL
  pure_quanta q_res *
  page152_i78
#CELL
  pure_quanta 74lvc1g126se7 *
  page152_i79
#CELL
  pure_quanta q_res *
  page152_i8
#ISCELL
  logical_power universal_gnd *
  page152_i80
#ISCELL
  standard offpage *
  page152_i83
#ISCELL
  logical_power universal_gnd *
  page152_i84
#ISCELL
  logical_power universal_power *
  page152_i85
#ISCELL
  logical_power universal_gnd *
  page152_i86
#CELL
  pure_quanta q_cap *
  page152_i87
#ISCELL
  standard offpage *
  page152_i88
#ISCELL
  standard offpage *
  page152_i9
#CELL
  pure_quanta q_res *
  page152_i90
#ISCELL
  standard offpage *
  page152_i91
#CELL
  pure_quanta 74lvc1g66gv *
  page152_i92
#ISCELL
  logical_power cad_note *
  *
#ISCELL
  mstr_misc dns *
  *
#ISCELL
  pure_quanta quanta_title_block_c *
  *
#ISCELL
  logical_power universal_gnd *
  page153_i1
#ISCELL
  logical_power gnd *
  page153_i10
#ISCELL
  standard offpage *
  page153_i100
#CELL
  pure_quanta q_cap *
  page153_i101
#CELL
  pure_quanta q_res *
  page153_i102
#CELL
  pure_quanta q_res *
  page153_i103
#CELL
  pure_quanta schottky_ac *
  page153_i104
#CELL
  pure_quanta q_res *
  page153_i105
#ISCELL
  logical_power gnd *
  page153_i106
#CELL
  pure_quanta q_cap *
  page153_i107
#CELL
  pure_quanta q_res *
  page153_i108
#ISCELL
  logical_power vccaux15 *
  page153_i109
#ISCELL
  standard offpage *
  page153_i11
#CELL
  pure_quanta q_res *
  page153_i110
#CELL
  pure_quanta q_cap *
  page153_i111
#ISCELL
  logical_power gnd *
  page153_i112
#CELL
  pure_quanta q_cap *
  page153_i113
#ISCELL
  logical_power universal_power *
  page153_i114
#ISCELL
  standard offpage *
  page153_i115
#ISCELL
  standard offpage *
  page153_i12
#CELL
  pure_quanta q_res *
  page153_i13
#ISCELL
  logical_power universal_power *
  page153_i14
#CELL
  pure_quanta q_res *
  page153_i15
#ISCELL
  logical_power universal_power *
  page153_i16
#CELL
  pure_quanta mosfet_nch_dual *
  page153_i17
#ISCELL
  logical_power gnd *
  page153_i18
#CELL
  pure_quanta q_res *
  page153_i19
#ISCELL
  logical_power universal_gnd *
  page153_i2
#CELL
  pure_quanta q_res *
  page153_i20
#CELL
  pure_quanta mosfet_nch_dual *
  page153_i21
#CELL
  pure_quanta q_res *
  page153_i22
#CELL
  pure_quanta 74lvc2g07dw7 *
  page153_i23
#ISCELL
  logical_power universal_gnd *
  page153_i24
#CELL
  pure_quanta q_res *
  page153_i25
#CELL
  pure_quanta 74lvc2g07dw7 *
  page153_i26
#CELL
  pure_quanta q_cap *
  page153_i27
#ISCELL
  logical_power universal_power *
  page153_i28
#ISCELL
  logical_power universal_gnd *
  page153_i29
#ISCELL
  standard offpage *
  page153_i3
#CELL
  pure_quanta q_cap *
  page153_i30
#ISCELL
  logical_power universal_power *
  page153_i31
#ISCELL
  logical_power gnd *
  page153_i32
#CELL
  pure_quanta q_res *
  page153_i33
#ISCELL
  logical_power gnd *
  page153_i34
#ISCELL
  logical_power gnd *
  page153_i35
#CELL
  pure_quanta mosfet_nch_dual *
  page153_i36
#ISCELL
  logical_power gnd *
  page153_i37
#CELL
  pure_quanta diode_tvs *
  page153_i38
#CELL
  pure_quanta q_res *
  page153_i39
#CELL
  pure_quanta q_res *
  page153_i4
#ISCELL
  logical_power gnd *
  page153_i40
#CELL
  pure_quanta q_res *
  page153_i41
#CELL
  pure_quanta q_res *
  page153_i42
#ISCELL
  logical_power universal_power *
  page153_i43
#CELL
  pure_quanta q_cap *
  page153_i44
#CELL
  pure_quanta q_res *
  page153_i45
#CELL
  pure_quanta q_res *
  page153_i46
#CELL
  pure_quanta q_res *
  page153_i47
#ISCELL
  logical_power gnd *
  page153_i48
#CELL
  pure_quanta q_res *
  page153_i49
#ISCELL
  standard offpage *
  page153_i5
#CELL
  pure_quanta q_res *
  page153_i50
#CELL
  pure_quanta max15090bewit *
  page153_i51
#ISCELL
  logical_power universal_power *
  page153_i52
#ISCELL
  logical_power gnd *
  page153_i53
#CELL
  pure_quanta q_cap *
  page153_i54
#CELL
  pure_quanta q_cap *
  page153_i55
#CELL
  pure_quanta q_res *
  page153_i56
#ISCELL
  logical_power gnd *
  page153_i57
#CELL
  pure_quanta q_res *
  page153_i58
#ISCELL
  logical_power gnd *
  page153_i59
#ISCELL
  standard offpage *
  page153_i6
#CELL
  pure_quanta q_res *
  page153_i60
#CELL
  pure_quanta max15090bewit *
  page153_i61
#CELL
  pure_quanta q_res *
  page153_i62
#ISCELL
  logical_power universal_power *
  page153_i63
#CELL
  pure_quanta q_res *
  page153_i64
#ISCELL
  logical_power gnd *
  page153_i65
#CELL
  pure_quanta q_cap *
  page153_i66
#ISCELL
  logical_power universal_power *
  page153_i67
#CELL
  pure_quanta q_res *
  page153_i68
#ISCELL
  logical_power gnd *
  page153_i69
#CELL
  pure_quanta q_res *
  page153_i7
#CELL
  pure_quanta q_res *
  page153_i70
#CELL
  pure_quanta q_cap *
  page153_i71
#CELL
  pure_quanta q_cap *
  page153_i72
#CELL
  pure_quanta q_res *
  page153_i73
#CELL
  pure_quanta q_res *
  page153_i74
#ISCELL
  standard offpage *
  page153_i75
#CELL
  pure_quanta q_res *
  page153_i76
#ISCELL
  standard offpage *
  page153_i77
#ISCELL
  standard offpage *
  page153_i78
#ISCELL
  logical_power gnd *
  page153_i79
#ISCELL
  logical_power universal_power *
  page153_i8
#CELL
  pure_quanta q_res *
  page153_i80
#CELL
  pure_quanta q_cap *
  page153_i81
#CELL
  pure_quanta q_res *
  page153_i82
#CELL
  pure_quanta q_cap *
  page153_i83
#CELL
  pure_quanta q_res *
  page153_i84
#ISCELL
  logical_power gnd *
  page153_i85
#CELL
  pure_quanta schottky_ac *
  page153_i86
#CELL
  pure_quanta q_res *
  page153_i87
#CELL
  pure_quanta q_res *
  page153_i88
#ISCELL
  logical_power gnd *
  page153_i89
#CELL
  pure_quanta mosfet_nch_dual *
  page153_i9
#CELL
  pure_quanta q_res *
  page153_i90
#ISCELL
  logical_power vccaux15 *
  page153_i91
#CELL
  pure_quanta q_res *
  page153_i92
#CELL
  pure_quanta q_cap *
  page153_i93
#CELL
  pure_quanta q_cap *
  page153_i94
#ISCELL
  logical_power gnd *
  page153_i95
#CELL
  pure_quanta q_cap *
  page153_i96
#ISCELL
  logical_power universal_power *
  page153_i97
#ISCELL
  standard offpage *
  page153_i98
#ISCELL
  standard offpage *
  page153_i99
#ISCELL
  logical_power cad_note *
  *
#ISCELL
  mstr_misc dns *
  *
#ISCELL
  pure_quanta quanta_title_block_c *
  *
#ISCELL
  standard offpage *
  page236_i31
#ISCELL
  logical_power universal_gnd *
  page236_i41
#CELL
  pure_quanta q_cap *
  page236_i42
#CELL
  pure_quanta q_res *
  page236_i43
#ISCELL
  logical_power universal_gnd *
  page236_i44
#CELL
  pure_quanta q_res *
  page236_i45
#CELL
  pure_quanta q_res *
  page236_i46
#ISCELL
  logical_power universal_gnd *
  page236_i47
#ISCELL
  logical_power universal_gnd *
  page236_i48
#CELL
  pure_quanta q_cap *
  page236_i49
#CELL
  pure_quanta mp5016gqhlz *
  page236_i50
#ISCELL
  logical_power universal_gnd *
  page236_i51
#CELL
  pure_quanta q_cap *
  page236_i52
#ISCELL
  logical_power universal_gnd *
  page236_i53
#CELL
  pure_quanta q_cap *
  page236_i54
#CELL
  pure_quanta q_cap *
  page236_i55
#ISCELL
  logical_power universal_power *
  page236_i56
#ISCELL
  logical_power universal_power *
  page236_i57
#ISCELL
  standard offpage *
  page236_i58
#ISCELL
  logical_power gnd *
  page236_i59
#CELL
  pure_quanta q_cap *
  page236_i60
#ISCELL
  logical_power gnd *
  page236_i61
#CELL
  pure_quanta q_res *
  page236_i62
#CELL
  pure_quanta q_cap *
  page236_i63
#ISCELL
  logical_power gnd *
  page236_i64
#CELL
  pure_quanta q_res *
  page236_i65
#ISCELL
  logical_power gnd *
  page236_i66
#ISCELL
  logical_power gnd *
  page236_i67
#CELL
  pure_quanta q_cap *
  page236_i68
#ISCELL
  logical_power gnd *
  page236_i69
#CELL
  pure_quanta rs31312r *
  page236_i70
#ISCELL
  logical_power universal_power *
  page236_i71
#CELL
  pure_quanta q_res *
  page236_i72
#ISCELL
  logical_power gnd *
  page236_i73
#CELL
  pure_quanta q_cap *
  page236_i74
#CELL
  pure_quanta q_res *
  page236_i75
#CELL
  pure_quanta q_res *
  page236_i76
#CELL
  pure_quanta q_res *
  page236_i77
#ISCELL
  standard offpage *
  page236_i78
#ISCELL
  standard offpage *
  page236_i79
#ISCELL
  logical_power vccaux15 *
  page236_i80
#CELL
  pure_quanta q_res *
  page236_i81
#CELL
  pure_quanta q_res *
  page236_i82
#CELL
  pure_quanta q_res *
  page236_i83
#ISCELL
  logical_power gnd *
  page236_i84
#CELL
  pure_quanta q_res *
  page236_i85
#CELL
  pure_quanta q_res *
  page236_i86
#ISCELL
  logical_power vccaux15 *
  page236_i87
#CELL
  pure_quanta q_cap *
  page236_i88
#CELL
  pure_quanta q_res *
  page236_i89
#ISCELL
  logical_power universal_power *
  page236_i90
#CELL
  pure_quanta q_cap *
  page236_i91
#ISCELL
  logical_power gnd *
  page236_i92
#ISCELL
  standard offpage *
  page236_i93
#ISCELL
  logical_power universal_power *
  page236_i94
#ISCELL
  standard offpage *
  page236_i95
#ISCELL
  standard offpage *
  page236_i96
#ISCELL
  mstr_misc dns *
  *
#ISCELL
  pure_quanta quanta_title_block_c *
  *
#ISCELL
  standard offpage *
  page154_i120
#ISCELL
  standard offpage *
  page154_i121
#ISCELL
  logical_power universal_gnd *
  page154_i126
#CELL
  pure_quanta q_res *
  page154_i130
#CELL
  pure_quanta q_res *
  page154_i131
#CELL
  pure_quanta q_res *
  page154_i132
#CELL
  pure_quanta q_res *
  page154_i133
#CELL
  pure_quanta q_res *
  page154_i134
#ISCELL
  standard offpage *
  page154_i135
#ISCELL
  standard offpage *
  page154_i136
#CELL
  pure_quanta q_res *
  page154_i137
#ISCELL
  logical_power universal_gnd *
  page154_i138
#ISCELL
  logical_power universal_gnd *
  page154_i139
#CELL
  pure_quanta q_res *
  page154_i140
#ISCELL
  logical_power universal_power *
  page154_i141
#CELL
  pure_quanta q_res *
  page154_i142
#CELL
  pure_quanta q_res *
  page154_i143
#ISCELL
  logical_power universal_gnd *
  page154_i144
#ISCELL
  logical_power universal_power *
  page154_i145
#ISCELL
  standard offpage *
  page154_i146
#CELL
  pure_quanta q_cap *
  page154_i148
#ISCELL
  logical_power universal_gnd *
  page154_i149
#ISCELL
  logical_power universal_gnd *
  page154_i151
#ISCELL
  standard offpage *
  page154_i156
#ISCELL
  standard offpage *
  page154_i163
#ISCELL
  standard offpage *
  page154_i166
#ISCELL
  standard offpage *
  page154_i167
#ISCELL
  logical_power universal_power *
  page154_i168
#CELL
  pure_quanta q_cap *
  page154_i169
#ISCELL
  logical_power universal_gnd *
  page154_i170
#ISCELL
  logical_power universal_power *
  page154_i171
#CELL
  pure_quanta q_res *
  page154_i172
#ISCELL
  standard offpage *
  page154_i173
#ISCELL
  logical_power universal_gnd *
  page154_i174
#ISCELL
  logical_power universal_gnd *
  page154_i176
#CELL
  pure_quanta mosfet_n *
  page154_i177
#ISCELL
  standard offpage *
  page154_i178
#ISCELL
  standard offpage *
  page154_i179
#CELL
  pure_quanta 74lvc1g08w57 *
  page154_i189
#CELL
  pure_quanta 74lvc1g08w57 *
  page154_i190
#CELL
  pure_quanta q_cap *
  page154_i192
#ISCELL
  logical_power universal_gnd *
  page154_i193
#ISCELL
  logical_power universal_power *
  page154_i194
#ISCELL
  standard offpage *
  page154_i201
#ISCELL
  standard offpage *
  page154_i202
#ISCELL
  standard offpage *
  page154_i203
#ISCELL
  standard offpage *
  page154_i205
#CELL
  pure_quanta pca9555apw *
  page154_i206
#ISCELL
  standard offpage *
  page154_i207
#ISCELL
  standard offpage *
  page154_i208
#CELL
  pure_quanta 74lvc1g08w57 *
  page154_i221
#ISCELL
  logical_power universal_power *
  page154_i222
#CELL
  pure_quanta q_cap *
  page154_i223
#ISCELL
  logical_power universal_gnd *
  page154_i224
#ISCELL
  logical_power universal_gnd *
  page154_i225
#ISCELL
  logical_power universal_gnd *
  page154_i226
#ISCELL
  logical_power universal_power *
  page154_i227
#CELL
  pure_quanta apx80929sag7 *
  page154_i228
#CELL
  pure_quanta q_cap *
  page154_i229
#ISCELL
  logical_power universal_gnd *
  page154_i230
#CELL
  pure_quanta q_res *
  page154_i232
#ISCELL
  standard offpage *
  page154_i233
#CELL
  pure_quanta q_res *
  page154_i235
#ISCELL
  logical_power universal_power *
  page154_i236
#CELL
  pure_quanta q_res *
  page154_i237
#CELL
  pure_quanta q_res *
  page154_i238
#ISCELL
  standard offpage *
  page154_i239
#ISCELL
  logical_power universal_power *
  page154_i240
#CELL
  pure_quanta q_cap *
  page154_i241
#ISCELL
  logical_power universal_gnd *
  page154_i242
#CELL
  pure_quanta 74lvc1g08w57 *
  page154_i243
#ISCELL
  logical_power universal_gnd *
  page154_i244
#CELL
  pure_quanta q_res *
  page154_i245
#ISCELL
  standard offpage *
  page154_i246
#CELL
  pure_quanta q_res *
  page154_i247
#ISCELL
  standard offpage *
  page154_i248
#CELL
  pure_quanta q_res *
  page154_i249
#ISCELL
  standard offpage *
  page154_i250
#CELL
  pure_quanta q_res *
  page154_i253
#CELL
  pure_quanta q_res *
  page154_i254
#ISCELL
  logical_power universal_power *
  page154_i255
#CELL
  pure_quanta q_res *
  page154_i256
#CELL
  pure_quanta q_res *
  page154_i257
#ISCELL
  logical_power universal_power *
  page154_i258
#ISCELL
  logical_power cad_note *
  *
#ISCELL
  mstr_misc dns *
  *
#ISCELL
  pure_quanta quanta_title_block_c *
  *
#ISCELL
  standard offpage *
  page146_i10
#ISCELL
  standard offpage *
  page146_i11
#ISCELL
  standard offpage *
  page146_i12
#ISCELL
  logical_power universal_gnd *
  page146_i124
#ISCELL
  standard offpage *
  page146_i125
#ISCELL
  standard offpage *
  page146_i126
#ISCELL
  standard offpage *
  page146_i127
#ISCELL
  standard offpage *
  page146_i128
#ISCELL
  standard offpage *
  page146_i13
#ISCELL
  standard offpage *
  page146_i134
#ISCELL
  standard offpage *
  page146_i135
#ISCELL
  standard offpage *
  page146_i136
#ISCELL
  standard offpage *
  page146_i137
#ISCELL
  standard offpage *
  page146_i138
#ISCELL
  standard offpage *
  page146_i139
#ISCELL
  standard offpage *
  page146_i14
#ISCELL
  standard offpage *
  page146_i140
#ISCELL
  standard offpage *
  page146_i141
#ISCELL
  standard offpage *
  page146_i142
#ISCELL
  standard offpage *
  page146_i143
#ISCELL
  logical_power universal_gnd *
  page146_i144
#CELL
  pure_quanta q_res *
  page146_i147
#CELL
  pure_quanta q_res *
  page146_i148
#ISCELL
  standard offpage *
  page146_i149
#ISCELL
  standard offpage *
  page146_i15
#ISCELL
  standard offpage *
  page146_i150
#ISCELL
  logical_power universal_gnd *
  page146_i151
#CELL
  pure_quanta q_res *
  page146_i152
#ISCELL
  standard offpage *
  page146_i153
#ISCELL
  standard offpage *
  page146_i156
#ISCELL
  standard offpage *
  page146_i158
#ISCELL
  standard offpage *
  page146_i159
#ISCELL
  logical_power universal_gnd *
  page146_i16
#ISCELL
  logical_power universal_gnd *
  page146_i163
#ISCELL
  logical_power universal_power *
  page146_i164
#CELL
  pure_quanta q_res *
  page146_i165
#CELL
  pure_quanta q_cap *
  page146_i166
#CELL
  pure_quanta q_cap *
  page146_i167
#CELL
  pure_quanta q_cap *
  page146_i168
#CELL
  pure_quanta q_cap *
  page146_i169
#ISCELL
  logical_power universal_power *
  page146_i170
#CELL
  pure_quanta q_cap *
  page146_i171
#ISCELL
  logical_power universal_gnd *
  page146_i172
#CELL
  pure_quanta q_cap *
  page146_i173
#CELL
  pure_quanta q_cap *
  page146_i174
#CELL
  pure_quanta q_cap *
  page146_i175
#ISCELL
  logical_power universal_gnd *
  page146_i176
#CELL
  pure_quanta q_cap *
  page146_i177
#ISCELL
  logical_power universal_power *
  page146_i178
#CELL
  pure_quanta q_cap *
  page146_i179
#CELL
  pure_quanta q_cap *
  page146_i180
#CELL
  pure_quanta q_res *
  page146_i181
#CELL
  pure_quanta q_res *
  page146_i182
#ISCELL
  standard offpage *
  page146_i183
#ISCELL
  standard offpage *
  page146_i184
#ISCELL
  standard offpage *
  page146_i186
#ISCELL
  standard tap *
  page146_i188
#ISCELL
  standard tap *
  page146_i189
#ISCELL
  logical_power universal_gnd *
  page146_i19
#ISCELL
  standard tap *
  page146_i191
#ISCELL
  standard tap *
  page146_i194
#ISCELL
  standard tap *
  page146_i196
#ISCELL
  standard tap *
  page146_i198
#ISCELL
  standard tap *
  page146_i199
#CELL
  pure_quanta q_res *
  page146_i20
#ISCELL
  standard tap *
  page146_i201
#ISCELL
  standard tap *
  page146_i203
#ISCELL
  standard tap *
  page146_i208
#ISCELL
  standard offpage *
  page146_i21
#ISCELL
  standard tap *
  page146_i210
#ISCELL
  standard tap *
  page146_i212
#ISCELL
  standard tap *
  page146_i213
#ISCELL
  standard tap *
  page146_i214
#ISCELL
  standard tap *
  page146_i216
#ISCELL
  standard tap *
  page146_i218
#ISCELL
  standard offpage *
  page146_i22
#ISCELL
  standard offpage *
  page146_i220
#ISCELL
  standard offpage *
  page146_i221
#ISCELL
  standard offpage *
  page146_i222
#ISCELL
  standard offpage *
  page146_i223
#ISCELL
  standard tap *
  page146_i224
#ISCELL
  standard tap *
  page146_i225
#ISCELL
  standard tap *
  page146_i226
#ISCELL
  standard tap *
  page146_i227
#ISCELL
  standard tap *
  page146_i228
#ISCELL
  standard tap *
  page146_i229
#CELL
  pure_quanta q_res *
  page146_i23
#ISCELL
  standard tap *
  page146_i230
#ISCELL
  standard tap *
  page146_i231
#ISCELL
  standard tap *
  page146_i232
#ISCELL
  standard tap *
  page146_i233
#ISCELL
  standard tap *
  page146_i234
#ISCELL
  standard tap *
  page146_i235
#ISCELL
  standard tap *
  page146_i236
#ISCELL
  standard tap *
  page146_i237
#ISCELL
  standard tap *
  page146_i238
#ISCELL
  standard tap *
  page146_i239
#ISCELL
  logical_power universal_power *
  page146_i24
#ISCELL
  standard tap *
  page146_i240
#ISCELL
  standard tap *
  page146_i241
#ISCELL
  standard tap *
  page146_i242
#ISCELL
  standard tap *
  page146_i243
#ISCELL
  standard tap *
  page146_i244
#ISCELL
  standard tap *
  page146_i245
#ISCELL
  standard tap *
  page146_i246
#ISCELL
  standard tap *
  page146_i247
#ISCELL
  standard tap *
  page146_i248
#ISCELL
  standard tap *
  page146_i249
#CELL
  pure_quanta q_res *
  page146_i25
#ISCELL
  standard tap *
  page146_i250
#ISCELL
  standard tap *
  page146_i251
#ISCELL
  standard tap *
  page146_i252
#ISCELL
  standard tap *
  page146_i253
#ISCELL
  standard tap *
  page146_i254
#ISCELL
  standard tap *
  page146_i255
#ISCELL
  logical_power universal_power *
  page146_i257
#CELL
  pure_quanta q_res *
  page146_i26
#ISCELL
  standard offpage *
  page146_i27
#ISCELL
  standard offpage *
  page146_i28
#ISCELL
  standard offpage *
  page146_i29
#ISCELL
  standard offpage *
  page146_i3
#ISCELL
  standard offpage *
  page146_i30
#CELL
  pure_quanta sconn168_me1016810202011 *
  page146_i303
#ISCELL
  standard tap *
  page146_i306
#ISCELL
  standard tap *
  page146_i307
#ISCELL
  standard tap *
  page146_i309
#CELL
  pure_quanta q_res *
  page146_i31
#ISCELL
  standard tap *
  page146_i310
#ISCELL
  standard tap *
  page146_i312
#ISCELL
  standard tap *
  page146_i313
#ISCELL
  standard tap *
  page146_i315
#ISCELL
  standard tap *
  page146_i316
#ISCELL
  standard tap *
  page146_i318
#ISCELL
  standard tap *
  page146_i319
#CELL
  pure_quanta q_res *
  page146_i32
#ISCELL
  standard tap *
  page146_i321
#ISCELL
  standard tap *
  page146_i322
#ISCELL
  standard tap *
  page146_i324
#ISCELL
  standard tap *
  page146_i325
#ISCELL
  standard tap *
  page146_i327
#ISCELL
  standard tap *
  page146_i328
#CELL
  pure_quanta q_res *
  page146_i33
#CELL
  pure_quanta q_res *
  page146_i333
#CELL
  pure_quanta q_res *
  page146_i334
#ISCELL
  standard offpage *
  page146_i335
#CELL
  pure_quanta q_res *
  page146_i336
#ISCELL
  standard offpage *
  page146_i337
#ISCELL
  standard offpage *
  page146_i34
#ISCELL
  standard offpage *
  page146_i35
#CELL
  pure_quanta q_res *
  page146_i36
#CELL
  pure_quanta q_res *
  page146_i37
#CELL
  pure_quanta q_res *
  page146_i38
#ISCELL
  standard offpage *
  page146_i39
#ISCELL
  standard offpage *
  page146_i40
#ISCELL
  standard offpage *
  page146_i41
#ISCELL
  logical_power universal_gnd *
  page146_i42
#CELL
  pure_quanta q_res *
  page146_i43
#ISCELL
  standard offpage *
  page146_i44
#ISCELL
  standard offpage *
  page146_i45
#ISCELL
  standard offpage *
  page146_i46
#ISCELL
  standard offpage *
  page146_i47
#ISCELL
  standard offpage *
  page146_i48
#ISCELL
  standard offpage *
  page146_i49
#CELL
  pure_quanta q_res *
  page146_i5
#ISCELL
  logical_power universal_power *
  page146_i51
#ISCELL
  standard offpage *
  page146_i6
#ISCELL
  standard offpage *
  page146_i7
#ISCELL
  standard offpage *
  page146_i8
#ISCELL
  standard offpage *
  page146_i9
#ISCELL
  mstr_misc dns *
  *
#ISCELL
  pure_quanta quanta_title_block_c *
  *
#CELL
  pure_quanta q_res *
  page307_i12
#ISCELL
  logical_power universal_gnd *
  page307_i14
#CELL
  pure_quanta q_res *
  page307_i15
#CELL
  pure_quanta q_cap *
  page307_i17
#ISCELL
  logical_power universal_gnd *
  page307_i18
#ISCELL
  logical_power universal_power *
  page307_i19
#ISCELL
  standard offpage *
  page307_i20
#ISCELL
  standard offpage *
  page307_i21
#ISCELL
  standard offpage *
  page307_i22
#ISCELL
  standard offpage *
  page307_i23
#ISCELL
  logical_power universal_gnd *
  page307_i24
#ISCELL
  logical_power universal_gnd *
  page307_i25
#ISCELL
  logical_power universal_power *
  page307_i26
#ISCELL
  standard offpage *
  page307_i27
#ISCELL
  standard offpage *
  page307_i28
#ISCELL
  standard offpage *
  page307_i29
#ISCELL
  standard offpage *
  page307_i3
#ISCELL
  standard offpage *
  page307_i30
#ISCELL
  logical_power universal_gnd *
  page307_i31
#CELL
  pure_quanta 74cbtlv3126pw *
  page307_i32
#CELL
  pure_quanta q_cap *
  page307_i33
#ISCELL
  logical_power universal_gnd *
  page307_i34
#ISCELL
  logical_power universal_power *
  page307_i35
#CELL
  pure_quanta q_res *
  page307_i37
#CELL
  pure_quanta q_res *
  page307_i38
#ISCELL
  logical_power universal_gnd *
  page307_i39
#CELL
  pure_quanta q_res *
  page307_i40
#ISCELL
  standard offpage *
  page307_i44
#ISCELL
  standard offpage *
  page307_i45
#ISCELL
  standard offpage *
  page307_i46
#CELL
  pure_quanta q_res *
  page307_i56
#CELL
  pure_quanta q_res *
  page307_i60
#CELL
  pure_quanta q_res *
  page307_i61
#CELL
  pure_quanta q_res *
  page307_i62
#CELL
  pure_quanta q_res *
  page307_i63
#CELL
  pure_quanta q_res *
  page307_i64
#CELL
  pure_quanta q_res *
  page307_i65
#ISCELL
  standard offpage *
  page307_i66
#ISCELL
  standard offpage *
  page307_i67
#ISCELL
  standard offpage *
  page307_i68
#ISCELL
  standard offpage *
  page307_i69
#ISCELL
  standard offpage *
  page307_i73
#ISCELL
  standard offpage *
  page307_i74
#ISCELL
  standard offpage *
  page307_i75
#ISCELL
  standard offpage *
  page307_i76
#CELL
  pure_quanta q_cap *
  page307_i77
#CELL
  pure_quanta 74cbtlv3126pw *
  page307_i78
#CELL
  pure_quanta q_res *
  page307_i79
#CELL
  pure_quanta 74lvc1g126se7 *
  page307_i80
#CELL
  pure_quanta q_res *
  page307_i81
#ISCELL
  standard offpage *
  page307_i82
#ISCELL
  logical_power universal_gnd *
  page307_i83
#ISCELL
  standard offpage *
  page307_i84
#CELL
  pure_quanta q_res *
  page307_i85
#ISCELL
  standard offpage *
  page307_i9
#ISCELL
  logical_power cad_note *
  *
#ISCELL
  mstr_misc dns *
  *
#ISCELL
  pure_quanta quanta_title_block_c *
  *
#ISCELL
  standard offpage *
  page156_i10
#ISCELL
  logical_power universal_gnd *
  page156_i11
#CELL
  pure_quanta q_cap *
  page156_i12
#ISCELL
  logical_power universal_gnd *
  page156_i19
#CELL
  pure_quanta q_res *
  page156_i24
#ISCELL
  logical_power universal_power *
  page156_i25
#ISCELL
  logical_power universal_gnd *
  page156_i26
#CELL
  pure_quanta q_cap *
  page156_i27
#CELL
  pure_quanta q_res *
  page156_i28
#ISCELL
  logical_power universal_power *
  page156_i29
#ISCELL
  logical_power universal_gnd *
  page156_i30
#CELL
  pure_quanta 74lvc1g07gv *
  page156_i31
#ISCELL
  logical_power universal_gnd *
  page156_i32
#CELL
  pure_quanta q_cap *
  page156_i33
#ISCELL
  logical_power universal_gnd *
  page156_i34
#CELL
  pure_quanta 74lvc1g17gw *
  page156_i35
#ISCELL
  logical_power universal_power *
  page156_i36
#ISCELL
  logical_power universal_power *
  page156_i37
#CELL
  pure_quanta q_res *
  page156_i38
#CELL
  pure_quanta q_res *
  page156_i39
#CELL
  pure_quanta q_res *
  page156_i40
#CELL
  pure_quanta q_res *
  page156_i41
#CELL
  pure_quanta q_res *
  page156_i42
#ISCELL
  logical_power universal_power *
  page156_i43
#CELL
  pure_quanta q_res *
  page156_i44
#ISCELL
  logical_power universal_power *
  page156_i45
#ISCELL
  logical_power universal_gnd *
  page156_i46
#CELL
  pure_quanta q_cap *
  page156_i47
#ISCELL
  standard offpage *
  page156_i48
#ISCELL
  standard offpage *
  page156_i49
#ISCELL
  standard offpage *
  page156_i5
#ISCELL
  standard offpage *
  page156_i50
#ISCELL
  standard offpage *
  page156_i51
#ISCELL
  standard offpage *
  page156_i52
#CELL
  pure_quanta q_res *
  page156_i55
#ISCELL
  standard offpage *
  page156_i58
#CELL
  pure_quanta q_res *
  page156_i59
#CELL
  pure_quanta q_res *
  page156_i6
#ISCELL
  logical_power universal_power *
  page156_i60
#CELL
  pure_quanta 74lvc1g07gv *
  page156_i61
#ISCELL
  logical_power universal_gnd *
  page156_i64
#CELL
  pure_quanta q_cap *
  page156_i65
#ISCELL
  logical_power universal_power *
  page156_i69
#CELL
  pure_quanta q_res *
  page156_i7
#CELL
  pure_quanta q_res *
  page156_i70
#ISCELL
  logical_power universal_gnd *
  page156_i71
#CELL
  pure_quanta q_res *
  page156_i72
#ISCELL
  standard offpage *
  page156_i73
#CELL
  pure_quanta 74lvc1g126se7 *
  page156_i74
#CELL
  pure_quanta q_res *
  page156_i75
#ISCELL
  standard offpage *
  page156_i76
#ISCELL
  standard offpage *
  page156_i77
#ISCELL
  logical_power universal_gnd *
  page156_i78
#CELL
  pure_quanta 74lvc1g126se7 *
  page156_i79
#ISCELL
  logical_power universal_power *
  page156_i8
#ISCELL
  logical_power universal_gnd *
  page156_i80
#CELL
  pure_quanta q_cap *
  page156_i81
#ISCELL
  logical_power universal_power *
  page156_i82
#ISCELL
  standard offpage *
  page156_i83
#ISCELL
  logical_power universal_gnd *
  page156_i84
#ISCELL
  logical_power universal_gnd *
  page156_i86
#ISCELL
  standard offpage *
  page156_i87
#ISCELL
  standard offpage *
  page156_i9
#CELL
  pure_quanta q_res *
  page156_i90
#ISCELL
  standard offpage *
  page156_i91
#CELL
  pure_quanta 74lvc1g66gv *
  page156_i92
#ISCELL
  logical_power cad_note *
  *
#ISCELL
  mstr_misc dns *
  *
#ISCELL
  pure_quanta quanta_title_block_c *
  *
#ISCELL
  standard offpage *
  page131_i1
#ISCELL
  logical_power gnd *
  page131_i10
#CELL
  pure_quanta q_cap *
  page131_i100
#ISCELL
  logical_power gnd *
  page131_i101
#CELL
  pure_quanta q_cap *
  page131_i102
#ISCELL
  logical_power universal_power *
  page131_i103
#ISCELL
  logical_power gnd *
  page131_i104
#CELL
  pure_quanta q_cap *
  page131_i105
#CELL
  pure_quanta q_res *
  page131_i106
#CELL
  pure_quanta schottky_ac *
  page131_i107
#CELL
  pure_quanta q_res *
  page131_i108
#CELL
  pure_quanta q_cap *
  page131_i109
#CELL
  pure_quanta q_res *
  page131_i11
#CELL
  pure_quanta q_res *
  page131_i110
#ISCELL
  logical_power vccaux15 *
  page131_i111
#ISCELL
  logical_power gnd *
  page131_i112
#CELL
  pure_quanta q_cap *
  page131_i113
#ISCELL
  logical_power universal_power *
  page131_i114
#ISCELL
  standard offpage *
  page131_i115
#ISCELL
  logical_power universal_power *
  page131_i12
#CELL
  pure_quanta q_res *
  page131_i13
#CELL
  pure_quanta q_res *
  page131_i14
#ISCELL
  logical_power universal_power *
  page131_i15
#CELL
  pure_quanta mosfet_nch_dual *
  page131_i16
#ISCELL
  logical_power gnd *
  page131_i17
#ISCELL
  logical_power universal_gnd *
  page131_i18
#CELL
  pure_quanta 74lvc2g07dw7 *
  page131_i19
#ISCELL
  standard offpage *
  page131_i2
#ISCELL
  logical_power universal_gnd *
  page131_i20
#CELL
  pure_quanta q_cap *
  page131_i21
#ISCELL
  logical_power universal_power *
  page131_i22
#ISCELL
  logical_power universal_gnd *
  page131_i23
#ISCELL
  logical_power universal_gnd *
  page131_i24
#CELL
  pure_quanta 74lvc2g07dw7 *
  page131_i25
#CELL
  pure_quanta q_cap *
  page131_i26
#ISCELL
  logical_power universal_power *
  page131_i27
#ISCELL
  logical_power gnd *
  page131_i28
#CELL
  pure_quanta q_res *
  page131_i29
#CELL
  pure_quanta q_res *
  page131_i3
#CELL
  pure_quanta q_res *
  page131_i30
#ISCELL
  logical_power gnd *
  page131_i31
#CELL
  pure_quanta q_res *
  page131_i32
#CELL
  pure_quanta q_res *
  page131_i33
#ISCELL
  standard offpage *
  page131_i34
#CELL
  pure_quanta q_res *
  page131_i35
#ISCELL
  logical_power gnd *
  page131_i36
#CELL
  pure_quanta q_res *
  page131_i37
#CELL
  pure_quanta mosfet_nch_dual *
  page131_i38
#ISCELL
  logical_power gnd *
  page131_i39
#ISCELL
  logical_power universal_power *
  page131_i4
#CELL
  pure_quanta q_res *
  page131_i40
#ISCELL
  logical_power universal_power *
  page131_i41
#CELL
  pure_quanta mosfet_nch_dual *
  page131_i42
#ISCELL
  logical_power gnd *
  page131_i43
#CELL
  pure_quanta diode_tvs *
  page131_i44
#ISCELL
  logical_power universal_power *
  page131_i45
#CELL
  pure_quanta q_cap *
  page131_i46
#CELL
  pure_quanta q_res *
  page131_i47
#CELL
  pure_quanta q_res *
  page131_i48
#ISCELL
  logical_power gnd *
  page131_i49
#CELL
  pure_quanta q_res *
  page131_i5
#CELL
  pure_quanta q_res *
  page131_i50
#ISCELL
  logical_power gnd *
  page131_i51
#CELL
  pure_quanta q_cap *
  page131_i52
#CELL
  pure_quanta q_res *
  page131_i53
#ISCELL
  logical_power universal_power *
  page131_i54
#CELL
  pure_quanta q_res *
  page131_i55
#CELL
  pure_quanta q_res *
  page131_i56
#CELL
  pure_quanta q_res *
  page131_i57
#ISCELL
  logical_power gnd *
  page131_i58
#CELL
  pure_quanta q_res *
  page131_i59
#CELL
  pure_quanta q_res *
  page131_i6
#ISCELL
  logical_power gnd *
  page131_i60
#CELL
  pure_quanta q_cap *
  page131_i61
#CELL
  pure_quanta q_cap *
  page131_i62
#CELL
  pure_quanta max15090bewit *
  page131_i63
#CELL
  pure_quanta q_res *
  page131_i64
#ISCELL
  logical_power universal_power *
  page131_i65
#CELL
  pure_quanta q_res *
  page131_i66
#ISCELL
  standard offpage *
  page131_i67
#ISCELL
  standard offpage *
  page131_i68
#ISCELL
  standard offpage *
  page131_i69
#CELL
  pure_quanta mosfet_nch_dual *
  page131_i7
#CELL
  pure_quanta q_res *
  page131_i70
#ISCELL
  logical_power gnd *
  page131_i71
#CELL
  pure_quanta q_res *
  page131_i72
#CELL
  pure_quanta q_cap *
  page131_i73
#CELL
  pure_quanta q_res *
  page131_i74
#CELL
  pure_quanta q_res *
  page131_i75
#CELL
  pure_quanta q_cap *
  page131_i76
#CELL
  pure_quanta q_res *
  page131_i77
#CELL
  pure_quanta q_res *
  page131_i78
#ISCELL
  logical_power gnd *
  page131_i79
#ISCELL
  standard offpage *
  page131_i8
#CELL
  pure_quanta q_res *
  page131_i80
#CELL
  pure_quanta q_res *
  page131_i81
#ISCELL
  standard offpage *
  page131_i82
#ISCELL
  standard offpage *
  page131_i83
#ISCELL
  standard offpage *
  page131_i84
#CELL
  pure_quanta q_res *
  page131_i85
#ISCELL
  logical_power gnd *
  page131_i86
#CELL
  pure_quanta q_cap *
  page131_i87
#ISCELL
  logical_power gnd *
  page131_i88
#CELL
  pure_quanta q_res *
  page131_i89
#ISCELL
  standard offpage *
  page131_i9
#CELL
  pure_quanta max15090bewit *
  page131_i90
#CELL
  pure_quanta q_cap *
  page131_i91
#CELL
  pure_quanta q_res *
  page131_i92
#CELL
  pure_quanta schottky_ac *
  page131_i93
#ISCELL
  logical_power gnd *
  page131_i94
#CELL
  pure_quanta q_res *
  page131_i95
#CELL
  pure_quanta q_cap *
  page131_i96
#CELL
  pure_quanta q_res *
  page131_i97
#CELL
  pure_quanta q_cap *
  page131_i98
#ISCELL
  logical_power vccaux15 *
  page131_i99
#ISCELL
  logical_power cad_note *
  *
#ISCELL
  mstr_misc dns *
  *
#ISCELL
  pure_quanta quanta_title_block_c *
  *
#ISCELL
  standard offpage *
  page237_i33
#ISCELL
  logical_power universal_gnd *
  page237_i34
#CELL
  pure_quanta q_cap *
  page237_i35
#CELL
  pure_quanta q_res *
  page237_i43
#CELL
  pure_quanta q_res *
  page237_i44
#ISCELL
  logical_power universal_gnd *
  page237_i45
#CELL
  pure_quanta q_res *
  page237_i46
#ISCELL
  logical_power universal_gnd *
  page237_i47
#CELL
  pure_quanta q_cap *
  page237_i48
#ISCELL
  logical_power universal_gnd *
  page237_i49
#CELL
  pure_quanta q_cap *
  page237_i50
#CELL
  pure_quanta mp5016gqhlz *
  page237_i51
#ISCELL
  logical_power universal_power *
  page237_i52
#ISCELL
  logical_power universal_gnd *
  page237_i53
#CELL
  pure_quanta q_cap *
  page237_i54
#ISCELL
  logical_power universal_gnd *
  page237_i55
#CELL
  pure_quanta q_cap *
  page237_i56
#ISCELL
  logical_power universal_power *
  page237_i57
#ISCELL
  standard offpage *
  page237_i58
#ISCELL
  logical_power gnd *
  page237_i59
#ISCELL
  logical_power gnd *
  page237_i60
#CELL
  pure_quanta q_res *
  page237_i61
#CELL
  pure_quanta q_cap *
  page237_i62
#ISCELL
  logical_power gnd *
  page237_i63
#ISCELL
  logical_power gnd *
  page237_i64
#CELL
  pure_quanta q_cap *
  page237_i65
#CELL
  pure_quanta q_res *
  page237_i66
#ISCELL
  logical_power gnd *
  page237_i67
#CELL
  pure_quanta q_cap *
  page237_i68
#ISCELL
  logical_power gnd *
  page237_i69
#CELL
  pure_quanta rs31312r *
  page237_i70
#ISCELL
  logical_power gnd *
  page237_i71
#CELL
  pure_quanta q_res *
  page237_i72
#CELL
  pure_quanta q_cap *
  page237_i73
#CELL
  pure_quanta q_res *
  page237_i74
#CELL
  pure_quanta q_res *
  page237_i75
#ISCELL
  logical_power vccaux15 *
  page237_i76
#CELL
  pure_quanta q_res *
  page237_i77
#ISCELL
  standard offpage *
  page237_i78
#ISCELL
  logical_power vccaux15 *
  page237_i79
#CELL
  pure_quanta q_res *
  page237_i80
#CELL
  pure_quanta q_res *
  page237_i81
#ISCELL
  logical_power gnd *
  page237_i82
#CELL
  pure_quanta q_res *
  page237_i83
#CELL
  pure_quanta q_res *
  page237_i84
#CELL
  pure_quanta q_res *
  page237_i85
#ISCELL
  logical_power universal_power *
  page237_i86
#CELL
  pure_quanta q_res *
  page237_i87
#ISCELL
  standard offpage *
  page237_i88
#ISCELL
  logical_power universal_power *
  page237_i89
#ISCELL
  logical_power gnd *
  page237_i90
#CELL
  pure_quanta q_cap *
  page237_i91
#ISCELL
  logical_power universal_power *
  page237_i92
#ISCELL
  standard offpage *
  page237_i93
#ISCELL
  standard offpage *
  page237_i94
#CELL
  pure_quanta q_cap *
  page237_i95
#ISCELL
  standard offpage *
  page237_i96
#ISCELL
  mstr_misc dns *
  *
#ISCELL
  pure_quanta quanta_title_block_c *
  *
#ISCELL
  standard offpage *
  page132_i1
#CELL
  pure_quanta q_res *
  page132_i100
#ISCELL
  standard offpage *
  page132_i101
#ISCELL
  standard offpage *
  page132_i102
#CELL
  pure_quanta q_res *
  page132_i103
#CELL
  pure_quanta q_res *
  page132_i104
#CELL
  pure_quanta q_res *
  page132_i105
#ISCELL
  logical_power universal_power *
  page132_i106
#CELL
  pure_quanta q_res *
  page132_i107
#CELL
  pure_quanta 74lvc1g08w57 *
  page132_i108
#ISCELL
  logical_power universal_gnd *
  page132_i109
#CELL
  pure_quanta q_cap *
  page132_i110
#CELL
  pure_quanta q_res *
  page132_i111
#CELL
  pure_quanta q_res *
  page132_i112
#ISCELL
  logical_power universal_power *
  page132_i113
#ISCELL
  standard offpage *
  page132_i115
#ISCELL
  logical_power universal_gnd *
  page132_i116
#ISCELL
  standard offpage *
  page132_i117
#ISCELL
  logical_power universal_power *
  page132_i118
#CELL
  pure_quanta q_res *
  page132_i119
#ISCELL
  logical_power universal_gnd *
  page132_i14
#CELL
  pure_quanta q_cap *
  page132_i15
#ISCELL
  logical_power universal_power *
  page132_i16
#ISCELL
  standard offpage *
  page132_i17
#ISCELL
  standard offpage *
  page132_i18
#ISCELL
  standard offpage *
  page132_i2
#CELL
  pure_quanta q_res *
  page132_i23
#ISCELL
  logical_power universal_gnd *
  page132_i24
#CELL
  pure_quanta q_res *
  page132_i25
#ISCELL
  logical_power universal_gnd *
  page132_i26
#CELL
  pure_quanta q_res *
  page132_i27
#ISCELL
  logical_power universal_gnd *
  page132_i28
#CELL
  pure_quanta q_res *
  page132_i29
#CELL
  pure_quanta mosfet_n *
  page132_i3
#ISCELL
  logical_power universal_power *
  page132_i30
#CELL
  pure_quanta q_res *
  page132_i31
#CELL
  pure_quanta q_res *
  page132_i32
#CELL
  pure_quanta q_res *
  page132_i33
#CELL
  pure_quanta q_res *
  page132_i34
#ISCELL
  standard offpage *
  page132_i37
#ISCELL
  logical_power universal_gnd *
  page132_i38
#CELL
  pure_quanta q_cap *
  page132_i39
#ISCELL
  logical_power universal_gnd *
  page132_i4
#ISCELL
  logical_power universal_power *
  page132_i40
#ISCELL
  logical_power universal_gnd *
  page132_i41
#ISCELL
  standard offpage *
  page132_i42
#ISCELL
  standard offpage *
  page132_i43
#ISCELL
  standard offpage *
  page132_i44
#ISCELL
  standard offpage *
  page132_i45
#ISCELL
  standard offpage *
  page132_i46
#ISCELL
  standard offpage *
  page132_i47
#ISCELL
  logical_power universal_gnd *
  page132_i5
#ISCELL
  standard offpage *
  page132_i50
#ISCELL
  logical_power universal_gnd *
  page132_i55
#CELL
  pure_quanta 74lvc1g08w57 *
  page132_i56
#ISCELL
  logical_power universal_gnd *
  page132_i57
#CELL
  pure_quanta q_cap *
  page132_i58
#ISCELL
  logical_power universal_power *
  page132_i59
#ISCELL
  standard offpage *
  page132_i6
#ISCELL
  standard offpage *
  page132_i60
#ISCELL
  standard offpage *
  page132_i63
#ISCELL
  standard offpage *
  page132_i64
#CELL
  pure_quanta q_res *
  page132_i65
#CELL
  pure_quanta pca9555apw *
  page132_i66
#ISCELL
  standard offpage *
  page132_i67
#ISCELL
  standard offpage *
  page132_i68
#CELL
  pure_quanta q_res *
  page132_i7
#ISCELL
  logical_power universal_power *
  page132_i8
#ISCELL
  logical_power universal_gnd *
  page132_i81
#ISCELL
  logical_power universal_gnd *
  page132_i84
#CELL
  pure_quanta apx80929sag7 *
  page132_i85
#ISCELL
  logical_power universal_power *
  page132_i86
#CELL
  pure_quanta q_cap *
  page132_i87
#ISCELL
  standard offpage *
  page132_i88
#ISCELL
  logical_power universal_power *
  page132_i89
#CELL
  pure_quanta 74lvc1g08w57 *
  page132_i9
#CELL
  pure_quanta q_cap *
  page132_i90
#ISCELL
  logical_power universal_gnd *
  page132_i91
#CELL
  pure_quanta 74lvc1g08w57 *
  page132_i92
#ISCELL
  logical_power universal_gnd *
  page132_i93
#ISCELL
  logical_power universal_power *
  page132_i94
#CELL
  pure_quanta q_res *
  page132_i95
#CELL
  pure_quanta q_res *
  page132_i96
#ISCELL
  standard offpage *
  page132_i98
#CELL
  pure_quanta q_res *
  page132_i99
#ISCELL
  mstr_misc dns *
  *
#ISCELL
  pure_quanta quanta_title_block_c *
  *
#CELL
  pure_quanta 74lvc2g08dp *
  page170_i1
#ISCELL
  standard offpage *
  page170_i10
#CELL
  pure_quanta 74lvc2g08dp *
  page170_i11
#CELL
  pure_quanta 74lvc2g08dp *
  page170_i12
#CELL
  pure_quanta 74lvc2g08dp *
  page170_i13
#CELL
  pure_quanta 74lvc2g08dp *
  page170_i14
#CELL
  pure_quanta nc7sb3157 *
  page170_i15
#CELL
  pure_quanta nc7sb3157 *
  page170_i16
#CELL
  pure_quanta nc7sb3157 *
  page170_i17
#CELL
  pure_quanta nc7sb3157 *
  page170_i18
#ISCELL
  logical_power universal_gnd *
  page170_i19
#CELL
  pure_quanta 74lvc2g08dp *
  page170_i2
#ISCELL
  logical_power universal_power *
  page170_i20
#CELL
  pure_quanta q_cap *
  page170_i21
#CELL
  pure_quanta q_cap *
  page170_i22
#ISCELL
  logical_power universal_power *
  page170_i23
#ISCELL
  logical_power universal_gnd *
  page170_i24
#ISCELL
  logical_power universal_gnd *
  page170_i25
#ISCELL
  logical_power universal_gnd *
  page170_i26
#CELL
  pure_quanta q_cap *
  page170_i27
#ISCELL
  logical_power universal_gnd *
  page170_i28
#ISCELL
  logical_power universal_power *
  page170_i29
#ISCELL
  standard offpage *
  page170_i3
#ISCELL
  logical_power universal_power *
  page170_i30
#CELL
  pure_quanta q_cap *
  page170_i31
#ISCELL
  logical_power universal_gnd *
  page170_i32
#ISCELL
  logical_power universal_power *
  page170_i33
#CELL
  pure_quanta q_cap *
  page170_i34
#ISCELL
  logical_power universal_gnd *
  page170_i35
#ISCELL
  logical_power universal_gnd *
  page170_i36
#CELL
  pure_quanta q_cap *
  page170_i37
#ISCELL
  logical_power universal_power *
  page170_i38
#ISCELL
  logical_power universal_gnd *
  page170_i39
#ISCELL
  standard offpage *
  page170_i4
#ISCELL
  logical_power universal_power *
  page170_i40
#CELL
  pure_quanta q_cap *
  page170_i41
#ISCELL
  logical_power universal_gnd *
  page170_i42
#CELL
  pure_quanta q_res *
  page170_i44
#CELL
  pure_quanta q_res *
  page170_i45
#CELL
  pure_quanta q_res *
  page170_i46
#CELL
  pure_quanta q_res *
  page170_i47
#ISCELL
  standard offpage *
  page170_i48
#ISCELL
  standard offpage *
  page170_i49
#ISCELL
  standard offpage *
  page170_i5
#CELL
  pure_quanta q_res *
  page170_i50
#ISCELL
  standard offpage *
  page170_i51
#CELL
  pure_quanta q_res *
  page170_i52
#ISCELL
  standard offpage *
  page170_i53
#ISCELL
  standard offpage *
  page170_i54
#ISCELL
  standard offpage *
  page170_i56
#ISCELL
  standard offpage *
  page170_i58
#ISCELL
  standard offpage *
  page170_i59
#ISCELL
  standard offpage *
  page170_i6
#ISCELL
  logical_power universal_gnd *
  page170_i60
#ISCELL
  logical_power universal_gnd *
  page170_i61
#ISCELL
  logical_power universal_gnd *
  page170_i62
#ISCELL
  logical_power universal_gnd *
  page170_i63
#ISCELL
  standard offpage *
  page170_i7
#ISCELL
  standard offpage *
  page170_i8
#ISCELL
  standard offpage *
  page170_i9
#ISCELL
  mstr_misc dns *
  *
#ISCELL
  pure_quanta quanta_title_block_c *
  *
#ISCELL
  logical_power universal_gnd *
  page136_i1
#ISCELL
  logical_power universal_power *
  page136_i10
#ISCELL
  logical_power universal_gnd *
  page136_i11
#CELL
  pure_quanta q_res *
  page136_i12
#ISCELL
  logical_power universal_gnd *
  page136_i13
#CELL
  pure_quanta q_res *
  page136_i14
#CELL
  pure_quanta q_res *
  page136_i15
#CELL
  pure_quanta q_res *
  page136_i16
#ISCELL
  logical_power universal_gnd *
  page136_i17
#CELL
  pure_quanta q_res *
  page136_i18
#ISCELL
  logical_power universal_gnd *
  page136_i19
#CELL
  pure_quanta q_res *
  page136_i2
#CELL
  pure_quanta q_res *
  page136_i20
#CELL
  pure_quanta q_res *
  page136_i21
#ISCELL
  logical_power universal_gnd *
  page136_i22
#CELL
  pure_quanta q_res *
  page136_i23
#ISCELL
  logical_power universal_gnd *
  page136_i24
#CELL
  pure_quanta q_res *
  page136_i25
#ISCELL
  logical_power universal_gnd *
  page136_i26
#CELL
  pure_quanta q_res *
  page136_i27
#ISCELL
  standard offpage *
  page136_i28
#ISCELL
  standard offpage *
  page136_i29
#ISCELL
  logical_power universal_gnd *
  page136_i3
#ISCELL
  standard offpage *
  page136_i30
#ISCELL
  standard offpage *
  page136_i31
#CELL
  pure_quanta q_res *
  page136_i32
#ISCELL
  logical_power universal_power *
  page136_i33
#ISCELL
  logical_power universal_power *
  page136_i34
#ISCELL
  standard offpage *
  page136_i35
#ISCELL
  standard offpage *
  page136_i36
#ISCELL
  standard offpage *
  page136_i37
#ISCELL
  standard offpage *
  page136_i38
#ISCELL
  standard offpage *
  page136_i39
#CELL
  pure_quanta q_res *
  page136_i4
#ISCELL
  standard offpage *
  page136_i40
#ISCELL
  standard offpage *
  page136_i41
#ISCELL
  standard offpage *
  page136_i42
#ISCELL
  standard offpage *
  page136_i43
#ISCELL
  standard offpage *
  page136_i44
#ISCELL
  standard offpage *
  page136_i45
#ISCELL
  standard offpage *
  page136_i46
#ISCELL
  logical_power universal_gnd *
  page136_i47
#CELL
  pure_quanta q_cap *
  page136_i48
#CELL
  pure_quanta q_cap *
  page136_i49
#ISCELL
  logical_power universal_gnd *
  page136_i5
#CELL
  pure_quanta pi3eqx12902azlex *
  page136_i50
#CELL
  pure_quanta q_cap *
  page136_i51
#CELL
  pure_quanta q_cap *
  page136_i52
#CELL
  pure_quanta q_cap *
  page136_i53
#ISCELL
  logical_power universal_power *
  page136_i54
#ISCELL
  logical_power universal_gnd *
  page136_i55
#CELL
  pure_quanta q_res *
  page136_i56
#CELL
  pure_quanta q_res *
  page136_i57
#ISCELL
  standard offpage *
  page136_i58
#ISCELL
  standard offpage *
  page136_i59
#CELL
  pure_quanta q_res *
  page136_i6
#ISCELL
  logical_power universal_gnd *
  page136_i60
#CELL
  pure_quanta q_res *
  page136_i61
#ISCELL
  logical_power universal_gnd *
  page136_i62
#CELL
  pure_quanta q_res *
  page136_i63
#CELL
  pure_quanta q_res *
  page136_i64
#ISCELL
  logical_power universal_gnd *
  page136_i65
#CELL
  pure_quanta q_res *
  page136_i66
#ISCELL
  logical_power universal_gnd *
  page136_i67
#CELL
  pure_quanta q_res *
  page136_i68
#CELL
  pure_quanta q_res *
  page136_i69
#ISCELL
  logical_power universal_gnd *
  page136_i7
#ISCELL
  standard offpage *
  page136_i70
#ISCELL
  standard offpage *
  page136_i71
#ISCELL
  logical_power universal_gnd *
  page136_i72
#CELL
  pure_quanta q_res *
  page136_i73
#ISCELL
  logical_power universal_power *
  page136_i74
#ISCELL
  standard offpage *
  page136_i75
#ISCELL
  standard offpage *
  page136_i76
#ISCELL
  standard offpage *
  page136_i77
#ISCELL
  standard offpage *
  page136_i78
#ISCELL
  standard offpage *
  page136_i79
#CELL
  pure_quanta q_res *
  page136_i8
#ISCELL
  standard offpage *
  page136_i80
#ISCELL
  logical_power universal_gnd *
  page136_i81
#CELL
  pure_quanta q_res *
  page136_i82
#ISCELL
  logical_power universal_gnd *
  page136_i83
#CELL
  pure_quanta q_res *
  page136_i84
#CELL
  pure_quanta q_res *
  page136_i85
#ISCELL
  logical_power universal_power *
  page136_i86
#ISCELL
  logical_power universal_gnd *
  page136_i87
#CELL
  pure_quanta q_res *
  page136_i88
#CELL
  pure_quanta q_res *
  page136_i89
#CELL
  pure_quanta q_res *
  page136_i9
#ISCELL
  logical_power universal_power *
  page136_i90
#ISCELL
  standard offpage *
  page136_i91
#ISCELL
  standard offpage *
  page136_i92
#ISCELL
  mstr_misc dns *
  *
#ISCELL
  pure_quanta quanta_title_block_c *
  *
#ISCELL
  logical_power universal_gnd *
  page159_i1
#CELL
  pure_quanta q_res *
  page159_i10
#CELL
  pure_quanta q_cap *
  page159_i100
#ISCELL
  logical_power universal_gnd *
  page159_i101
#CELL
  pure_quanta q_res *
  page159_i102
#ISCELL
  standard offpage *
  page159_i103
#ISCELL
  standard offpage *
  page159_i104
#ISCELL
  standard offpage *
  page159_i105
#ISCELL
  standard offpage *
  page159_i106
#ISCELL
  standard offpage *
  page159_i107
#ISCELL
  standard offpage *
  page159_i108
#ISCELL
  standard offpage *
  page159_i109
#CELL
  pure_quanta q_res *
  page159_i11
#ISCELL
  standard offpage *
  page159_i110
#ISCELL
  standard offpage *
  page159_i111
#ISCELL
  logical_power universal_power *
  page159_i12
#CELL
  pure_quanta q_res *
  page159_i13
#ISCELL
  logical_power universal_gnd *
  page159_i14
#CELL
  pure_quanta q_res *
  page159_i15
#CELL
  pure_quanta q_res *
  page159_i16
#ISCELL
  standard offpage *
  page159_i17
#ISCELL
  standard offpage *
  page159_i18
#ISCELL
  standard offpage *
  page159_i19
#CELL
  pure_quanta q_res *
  page159_i2
#ISCELL
  standard offpage *
  page159_i20
#ISCELL
  standard offpage *
  page159_i21
#ISCELL
  standard offpage *
  page159_i22
#ISCELL
  standard offpage *
  page159_i23
#ISCELL
  standard offpage *
  page159_i24
#ISCELL
  standard offpage *
  page159_i25
#ISCELL
  standard offpage *
  page159_i26
#CELL
  pure_quanta q_cap *
  page159_i27
#CELL
  pure_quanta q_cap *
  page159_i28
#CELL
  pure_quanta q_cap *
  page159_i29
#ISCELL
  logical_power universal_gnd *
  page159_i3
#CELL
  pure_quanta q_cap *
  page159_i30
#CELL
  pure_quanta q_cap *
  page159_i31
#CELL
  pure_quanta q_cap *
  page159_i32
#CELL
  pure_quanta q_cap *
  page159_i33
#CELL
  pure_quanta q_cap *
  page159_i34
#CELL
  pure_quanta q_res *
  page159_i35
#CELL
  pure_quanta q_res *
  page159_i36
#ISCELL
  standard offpage *
  page159_i37
#ISCELL
  standard offpage *
  page159_i38
#ISCELL
  standard offpage *
  page159_i39
#CELL
  pure_quanta q_res *
  page159_i4
#ISCELL
  standard offpage *
  page159_i40
#CELL
  pure_quanta q_res *
  page159_i41
#CELL
  pure_quanta q_res *
  page159_i42
#CELL
  pure_quanta q_res *
  page159_i43
#CELL
  pure_quanta q_res *
  page159_i44
#CELL
  pure_quanta q_res *
  page159_i45
#CELL
  pure_quanta q_res *
  page159_i46
#ISCELL
  standard offpage *
  page159_i47
#ISCELL
  standard offpage *
  page159_i48
#ISCELL
  standard offpage *
  page159_i49
#ISCELL
  standard offpage *
  page159_i5
#ISCELL
  standard offpage *
  page159_i50
#ISCELL
  standard offpage *
  page159_i51
#ISCELL
  logical_power universal_gnd *
  page159_i52
#CELL
  pure_quanta q_res *
  page159_i53
#ISCELL
  standard offpage *
  page159_i54
#ISCELL
  standard offpage *
  page159_i55
#ISCELL
  standard offpage *
  page159_i56
#ISCELL
  standard offpage *
  page159_i57
#ISCELL
  standard offpage *
  page159_i58
#ISCELL
  standard offpage *
  page159_i59
#ISCELL
  standard offpage *
  page159_i6
#ISCELL
  logical_power universal_gnd *
  page159_i60
#CELL
  pure_quanta q_res *
  page159_i61
#CELL
  pure_quanta q_res *
  page159_i62
#ISCELL
  standard offpage *
  page159_i63
#ISCELL
  logical_power universal_gnd *
  page159_i64
#CELL
  pure_quanta q_res *
  page159_i65
#CELL
  pure_quanta q_res *
  page159_i66
#CELL
  pure_quanta q_res *
  page159_i67
#ISCELL
  logical_power universal_gnd *
  page159_i68
#ISCELL
  logical_power universal_power *
  page159_i69
#CELL
  pure_quanta q_res *
  page159_i7
#ISCELL
  logical_power universal_gnd *
  page159_i70
#CELL
  pure_quanta q_res *
  page159_i71
#CELL
  pure_quanta q_res *
  page159_i72
#ISCELL
  logical_power universal_power *
  page159_i73
#CELL
  pure_quanta q_res *
  page159_i74
#ISCELL
  logical_power universal_power *
  page159_i75
#ISCELL
  standard offpage *
  page159_i76
#ISCELL
  standard offpage *
  page159_i77
#ISCELL
  standard offpage *
  page159_i78
#ISCELL
  logical_power universal_gnd *
  page159_i79
#ISCELL
  logical_power universal_power *
  page159_i8
#CELL
  pure_quanta q_res *
  page159_i80
#CELL
  pure_quanta q_res *
  page159_i81
#ISCELL
  standard offpage *
  page159_i82
#ISCELL
  logical_power universal_power *
  page159_i83
#ISCELL
  standard offpage *
  page159_i84
#ISCELL
  standard offpage *
  page159_i85
#ISCELL
  standard offpage *
  page159_i86
#ISCELL
  standard offpage *
  page159_i87
#ISCELL
  standard offpage *
  page159_i88
#ISCELL
  standard offpage *
  page159_i89
#ISCELL
  logical_power universal_gnd *
  page159_i9
#ISCELL
  standard offpage *
  page159_i90
#ISCELL
  standard offpage *
  page159_i91
#ISCELL
  standard offpage *
  page159_i92
#ISCELL
  standard offpage *
  page159_i93
#ISCELL
  logical_power universal_gnd *
  page159_i94
#CELL
  pure_quanta ds125br111rtwr *
  page159_i95
#CELL
  pure_quanta q_cap *
  page159_i96
#ISCELL
  logical_power universal_power *
  page159_i97
#CELL
  pure_quanta q_cap *
  page159_i98
#CELL
  pure_quanta q_cap *
  page159_i99
#ISCELL
  pure_quanta quanta_title_block_c *
  *
#ISCELL
  mstr_misc dns *
  *
#ISCELL
  pure_quanta quanta_title_block_c *
  *
#ISCELL
  logical_power universal_gnd *
  page162_i1
#ISCELL
  logical_power universal_gnd *
  page162_i10
#CELL
  pure_quanta q_res *
  page162_i11
#CELL
  pure_quanta q_res *
  page162_i12
#ISCELL
  logical_power universal_power *
  page162_i13
#ISCELL
  standard offpage *
  page162_i14
#ISCELL
  standard offpage *
  page162_i15
#ISCELL
  logical_power universal_gnd *
  page162_i16
#CELL
  pure_quanta q_res *
  page162_i17
#CELL
  pure_quanta q_res *
  page162_i18
#ISCELL
  standard offpage *
  page162_i19
#CELL
  pure_quanta q_res *
  page162_i2
#ISCELL
  standard offpage *
  page162_i20
#ISCELL
  logical_power universal_gnd *
  page162_i21
#ISCELL
  logical_power universal_gnd *
  page162_i22
#CELL
  pure_quanta q_res *
  page162_i23
#CELL
  pure_quanta q_res *
  page162_i24
#CELL
  pure_quanta q_cap_diffbus *
  page162_i25
#CELL
  pure_quanta q_cap_diffbus *
  page162_i26
#ISCELL
  standard offpage *
  page162_i27
#ISCELL
  standard offpage *
  page162_i28
#ISCELL
  standard offpage *
  page162_i29
#CELL
  pure_quanta q_res *
  page162_i3
#ISCELL
  standard offpage *
  page162_i30
#ISCELL
  standard offpage *
  page162_i31
#ISCELL
  standard offpage *
  page162_i32
#ISCELL
  standard offpage *
  page162_i33
#ISCELL
  standard offpage *
  page162_i34
#CELL
  pure_quanta q_inductor *
  page162_i35
#ISCELL
  logical_power universal_gnd *
  page162_i36
#CELL
  pure_quanta q_cap *
  page162_i37
#ISCELL
  logical_power universal_power *
  page162_i38
#ISCELL
  logical_power universal_gnd *
  page162_i39
#ISCELL
  logical_power universal_power *
  page162_i4
#CELL
  pure_quanta q_res *
  page162_i40
#CELL
  pure_quanta q_res *
  page162_i41
#ISCELL
  logical_power universal_power *
  page162_i42
#CELL
  pure_quanta pi3eqx1002ezrex *
  page162_i43
#CELL
  pure_quanta q_cap *
  page162_i44
#CELL
  pure_quanta q_cap *
  page162_i45
#ISCELL
  logical_power universal_gnd *
  page162_i46
#ISCELL
  logical_power universal_gnd *
  page162_i47
#CELL
  pure_quanta q_res *
  page162_i48
#CELL
  pure_quanta q_res *
  page162_i49
#ISCELL
  logical_power universal_gnd *
  page162_i5
#ISCELL
  standard offpage *
  page162_i50
#ISCELL
  standard offpage *
  page162_i51
#ISCELL
  standard offpage *
  page162_i52
#ISCELL
  standard offpage *
  page162_i53
#CELL
  pure_quanta q_cap *
  page162_i54
#CELL
  pure_quanta q_cap *
  page162_i55
#CELL
  pure_quanta q_cap *
  page162_i56
#CELL
  pure_quanta q_cap *
  page162_i57
#ISCELL
  standard offpage *
  page162_i58
#ISCELL
  standard offpage *
  page162_i59
#CELL
  pure_quanta q_res *
  page162_i6
#ISCELL
  standard offpage *
  page162_i60
#ISCELL
  standard offpage *
  page162_i61
#ISCELL
  logical_power universal_gnd *
  page162_i62
#CELL
  pure_quanta q_res *
  page162_i63
#ISCELL
  standard offpage *
  page162_i64
#CELL
  pure_quanta q_res *
  page162_i65
#ISCELL
  logical_power universal_power *
  page162_i66
#ISCELL
  logical_power universal_gnd *
  page162_i67
#CELL
  pure_quanta q_res *
  page162_i68
#CELL
  pure_quanta q_res *
  page162_i69
#CELL
  pure_quanta q_res *
  page162_i7
#ISCELL
  logical_power universal_power *
  page162_i70
#ISCELL
  standard offpage *
  page162_i71
#ISCELL
  standard offpage *
  page162_i8
#ISCELL
  standard offpage *
  page162_i9
#ISCELL
  mstr_misc dns *
  *
#ISCELL
  pure_quanta quanta_title_block_c *
  *
#ISCELL
  logical_power universal_power *
  page161_i100
#CELL
  pure_quanta q_res *
  page161_i101
#CELL
  pure_quanta q_res *
  page161_i102
#ISCELL
  logical_power universal_gnd *
  page161_i103
#CELL
  pure_quanta q_cap *
  page161_i104
#ISCELL
  logical_power universal_gnd *
  page161_i105
#ISCELL
  logical_power universal_gnd *
  page161_i106
#CELL
  pure_quanta q_res *
  page161_i107
#CELL
  pure_quanta q_res *
  page161_i108
#CELL
  pure_quanta q_res *
  page161_i109
#ISCELL
  standard offpage *
  page161_i110
#ISCELL
  standard offpage *
  page161_i111
#ISCELL
  standard offpage *
  page161_i112
#ISCELL
  standard offpage *
  page161_i113
#CELL
  pure_quanta q_res *
  page161_i114
#CELL
  pure_quanta q_res *
  page161_i115
#CELL
  pure_quanta q_res *
  page161_i116
#ISCELL
  logical_power universal_gnd *
  page161_i117
#ISCELL
  logical_power universal_gnd *
  page161_i118
#CELL
  pure_quanta q_cap *
  page161_i119
#ISCELL
  logical_power universal_gnd *
  page161_i120
#CELL
  pure_quanta q_res *
  page161_i121
#CELL
  pure_quanta q_res *
  page161_i122
#ISCELL
  logical_power universal_power *
  page161_i123
#ISCELL
  logical_power universal_gnd *
  page161_i124
#CELL
  pure_quanta q_res *
  page161_i125
#ISCELL
  logical_power universal_gnd *
  page161_i126
#CELL
  pure_quanta q_res *
  page161_i127
#CELL
  pure_quanta q_res *
  page161_i128
#CELL
  pure_quanta q_res *
  page161_i129
#ISCELL
  logical_power universal_power *
  page161_i130
#ISCELL
  standard offpage *
  page161_i132
#ISCELL
  standard offpage *
  page161_i133
#CELL
  pure_quanta q_res *
  page161_i134
#CELL
  pure_quanta q_res *
  page161_i135
#CELL
  pure_quanta q_res *
  page161_i136
#ISCELL
  logical_power universal_gnd *
  page161_i137
#ISCELL
  logical_power universal_gnd *
  page161_i138
#CELL
  pure_quanta q_cap *
  page161_i139
#ISCELL
  logical_power universal_gnd *
  page161_i140
#CELL
  pure_quanta q_res *
  page161_i141
#CELL
  pure_quanta q_res *
  page161_i142
#ISCELL
  logical_power universal_power *
  page161_i143
#ISCELL
  logical_power universal_gnd *
  page161_i144
#CELL
  pure_quanta q_res *
  page161_i145
#ISCELL
  logical_power universal_gnd *
  page161_i146
#CELL
  pure_quanta q_res *
  page161_i147
#CELL
  pure_quanta q_res *
  page161_i148
#CELL
  pure_quanta q_res *
  page161_i149
#ISCELL
  logical_power universal_power *
  page161_i15
#ISCELL
  logical_power universal_power *
  page161_i150
#ISCELL
  logical_power universal_power *
  page161_i153
#ISCELL
  logical_power universal_power *
  page161_i154
#ISCELL
  logical_power universal_power *
  page161_i156
#ISCELL
  logical_power universal_power *
  page161_i159
#CELL
  pure_quanta q_cap *
  page161_i16
#ISCELL
  standard offpage *
  page161_i160
#ISCELL
  standard offpage *
  page161_i161
#ISCELL
  standard offpage *
  page161_i162
#ISCELL
  standard offpage *
  page161_i163
#CELL
  pure_quanta lm75bd *
  page161_i164
#CELL
  pure_quanta lm75bd *
  page161_i165
#CELL
  pure_quanta lm75bd *
  page161_i166
#CELL
  pure_quanta lm75bd *
  page161_i167
#CELL
  pure_quanta q_res *
  page161_i168
#CELL
  pure_quanta q_res *
  page161_i169
#ISCELL
  logical_power universal_gnd *
  page161_i17
#CELL
  pure_quanta q_res *
  page161_i170
#CELL
  pure_quanta q_res *
  page161_i171
#ISCELL
  logical_power universal_gnd *
  page161_i21
#ISCELL
  standard offpage *
  page161_i75
#ISCELL
  standard offpage *
  page161_i76
#CELL
  pure_quanta q_res *
  page161_i77
#CELL
  pure_quanta q_res *
  page161_i78
#CELL
  pure_quanta q_res *
  page161_i79
#ISCELL
  logical_power universal_gnd *
  page161_i80
#CELL
  pure_quanta q_res *
  page161_i81
#CELL
  pure_quanta q_res *
  page161_i82
#ISCELL
  logical_power universal_power *
  page161_i83
#ISCELL
  logical_power universal_gnd *
  page161_i84
#CELL
  pure_quanta q_res *
  page161_i85
#CELL
  pure_quanta q_res *
  page161_i86
#CELL
  pure_quanta q_res *
  page161_i89
#ISCELL
  logical_power universal_gnd *
  page161_i90
#CELL
  pure_quanta q_res *
  page161_i91
#ISCELL
  logical_power universal_power *
  page161_i93
#CELL
  pure_quanta q_res *
  page161_i94
#CELL
  pure_quanta q_res *
  page161_i95
#CELL
  pure_quanta q_res *
  page161_i96
#ISCELL
  logical_power universal_gnd *
  page161_i97
#CELL
  pure_quanta q_res *
  page161_i98
#ISCELL
  logical_power universal_gnd *
  page161_i99
#ISCELL
  mstr_misc dns *
  *
#ISCELL
  pure_quanta quanta_title_block_c *
  *
#ISCELL
  standard offpage *
  page295_i121
#CELL
  pure_quanta q_res *
  page295_i122
#ISCELL
  logical_power universal_power *
  page295_i123
#ISCELL
  logical_power universal_gnd *
  page295_i124
#CELL
  pure_quanta q_cap *
  page295_i125
#ISCELL
  logical_power universal_gnd *
  page295_i128
#CELL
  pure_quanta ina230airgtr *
  page295_i129
#CELL
  pure_quanta q_res *
  page295_i130
#CELL
  pure_quanta q_res *
  page295_i131
#CELL
  pure_quanta q_res *
  page295_i132
#CELL
  pure_quanta q_cap *
  page295_i133
#CELL
  pure_quanta q_res *
  page295_i134
#CELL
  pure_quanta q_res *
  page295_i135
#CELL
  pure_quanta q_res *
  page295_i136
#ISCELL
  logical_power universal_gnd *
  page295_i137
#ISCELL
  standard offpage *
  page295_i138
#ISCELL
  standard offpage *
  page295_i139
#ISCELL
  logical_power universal_power *
  page295_i140
#CELL
  pure_quanta q_cap *
  page295_i142
#ISCELL
  logical_power universal_gnd *
  page295_i143
#ISCELL
  logical_power universal_power *
  page295_i145
#CELL
  pure_quanta q_res *
  page295_i146
#ISCELL
  logical_power universal_power *
  page295_i147
#ISCELL
  logical_power universal_power *
  page295_i148
#CELL
  pure_quanta q_res *
  page295_i149
#ISCELL
  logical_power universal_power *
  page295_i150
#CELL
  pure_quanta q_res *
  page295_i151
#CELL
  pure_quanta q_res *
  page295_i152
#CELL
  pure_quanta q_res *
  page295_i153
#CELL
  pure_quanta ina230airgtr *
  page295_i30
#CELL
  pure_quanta q_res *
  page295_i31
#ISCELL
  standard offpage *
  page295_i32
#ISCELL
  logical_power universal_power *
  page295_i33
#CELL
  pure_quanta q_cap *
  page295_i34
#CELL
  pure_quanta q_res *
  page295_i35
#ISCELL
  logical_power universal_gnd *
  page295_i36
#ISCELL
  logical_power universal_gnd *
  page295_i37
#CELL
  pure_quanta q_res *
  page295_i38
#CELL
  pure_quanta q_res *
  page295_i39
#CELL
  pure_quanta q_res *
  page295_i40
#CELL
  pure_quanta q_res *
  page295_i41
#CELL
  pure_quanta q_res *
  page295_i43
#ISCELL
  logical_power universal_gnd *
  page295_i45
#ISCELL
  standard offpage *
  page295_i46
#ISCELL
  standard offpage *
  page295_i47
#ISCELL
  logical_power universal_gnd *
  page295_i49
#CELL
  pure_quanta q_cap *
  page295_i50
#CELL
  pure_quanta q_cap *
  page295_i77
#ISCELL
  logical_power universal_power *
  page295_i79
#ISCELL
  logical_power universal_power *
  page295_i80
#ISCELL
  logical_power universal_power *
  page295_i81
#ISCELL
  logical_power universal_power *
  page295_i87
#CELL
  pure_quanta q_res *
  page295_i88
#CELL
  pure_quanta q_res *
  page295_i89
#ISCELL
  mstr_misc dns *
  *
#ISCELL
  pure_quanta quanta_title_block_c *
  *
#CELL
  pure_quanta q_res *
  page163_i100
#CELL
  pure_quanta q_res *
  page163_i101
#CELL
  pure_quanta q_res *
  page163_i102
#CELL
  pure_quanta q_res *
  page163_i103
#CELL
  pure_quanta q_res *
  page163_i104
#ISCELL
  logical_power universal_gnd *
  page163_i105
#ISCELL
  standard offpage *
  page163_i106
#ISCELL
  logical_power universal_gnd *
  page163_i107
#CELL
  pure_quanta q_cap *
  page163_i108
#CELL
  pure_quanta q_res *
  page163_i109
#CELL
  pure_quanta q_res *
  page163_i110
#ISCELL
  standard offpage *
  page163_i111
#ISCELL
  logical_power universal_power *
  page163_i112
#ISCELL
  logical_power universal_power *
  page163_i113
#CELL
  pure_quanta q_cap *
  page163_i114
#ISCELL
  logical_power universal_gnd *
  page163_i115
#ISCELL
  logical_power universal_power *
  page163_i117
#ISCELL
  logical_power universal_power *
  page163_i118
#ISCELL
  logical_power universal_power *
  page163_i119
#ISCELL
  logical_power universal_power *
  page163_i120
#ISCELL
  logical_power universal_power *
  page163_i121
#CELL
  pure_quanta q_res *
  page163_i122
#ISCELL
  logical_power universal_power *
  page163_i123
#CELL
  pure_quanta q_res *
  page163_i124
#ISCELL
  logical_power universal_power *
  page163_i125
#CELL
  pure_quanta q_res *
  page163_i126
#CELL
  pure_quanta q_res *
  page163_i127
#CELL
  pure_quanta q_res *
  page163_i128
#CELL
  pure_quanta q_res *
  page163_i129
#ISCELL
  logical_power universal_power *
  page163_i24
#CELL
  pure_quanta q_cap *
  page163_i26
#ISCELL
  logical_power universal_gnd *
  page163_i27
#ISCELL
  standard offpage *
  page163_i29
#ISCELL
  standard offpage *
  page163_i30
#ISCELL
  logical_power universal_gnd *
  page163_i31
#ISCELL
  logical_power universal_power *
  page163_i32
#CELL
  pure_quanta q_res *
  page163_i33
#CELL
  pure_quanta q_res *
  page163_i35
#CELL
  pure_quanta q_res *
  page163_i36
#CELL
  pure_quanta q_res *
  page163_i37
#CELL
  pure_quanta q_res *
  page163_i38
#ISCELL
  logical_power universal_gnd *
  page163_i39
#ISCELL
  logical_power universal_gnd *
  page163_i40
#CELL
  pure_quanta q_res *
  page163_i41
#CELL
  pure_quanta q_cap *
  page163_i42
#ISCELL
  logical_power universal_power *
  page163_i43
#ISCELL
  standard offpage *
  page163_i44
#CELL
  pure_quanta q_res *
  page163_i45
#CELL
  pure_quanta ina230airgtr *
  page163_i46
#CELL
  pure_quanta q_cap *
  page163_i49
#ISCELL
  logical_power universal_gnd *
  page163_i50
#ISCELL
  standard offpage *
  page163_i52
#ISCELL
  standard offpage *
  page163_i53
#ISCELL
  logical_power universal_gnd *
  page163_i54
#CELL
  pure_quanta q_res *
  page163_i56
#CELL
  pure_quanta q_res *
  page163_i58
#CELL
  pure_quanta q_res *
  page163_i59
#CELL
  pure_quanta q_res *
  page163_i60
#CELL
  pure_quanta q_res *
  page163_i61
#ISCELL
  logical_power universal_gnd *
  page163_i62
#ISCELL
  logical_power universal_gnd *
  page163_i63
#CELL
  pure_quanta q_res *
  page163_i64
#CELL
  pure_quanta q_cap *
  page163_i65
#ISCELL
  logical_power universal_power *
  page163_i66
#ISCELL
  standard offpage *
  page163_i67
#CELL
  pure_quanta q_res *
  page163_i68
#CELL
  pure_quanta ina230airgtr *
  page163_i69
#CELL
  pure_quanta q_cap *
  page163_i71
#CELL
  pure_quanta q_cap *
  page163_i72
#ISCELL
  logical_power universal_power *
  page163_i76
#ISCELL
  logical_power universal_power *
  page163_i85
#CELL
  pure_quanta q_res *
  page163_i86
#CELL
  pure_quanta q_res *
  page163_i87
#ISCELL
  logical_power universal_power *
  page163_i88
#CELL
  pure_quanta q_res *
  page163_i89
#CELL
  pure_quanta q_res *
  page163_i90
#CELL
  pure_quanta ina230airgtr *
  page163_i94
#ISCELL
  standard offpage *
  page163_i95
#CELL
  pure_quanta q_res *
  page163_i96
#ISCELL
  logical_power universal_power *
  page163_i97
#CELL
  pure_quanta q_cap *
  page163_i98
#ISCELL
  logical_power universal_gnd *
  page163_i99
#ISCELL
  pure_quanta quanta_title_block_c *
  *
#ISCELL
  standard offpage *
  page164_i1
#ISCELL
  standard tap *
  page164_i10
#ISCELL
  standard tap *
  page164_i100
#ISCELL
  standard tap *
  page164_i101
#ISCELL
  standard tap *
  page164_i102
#ISCELL
  standard tap *
  page164_i103
#ISCELL
  standard tap *
  page164_i104
#ISCELL
  standard offpage *
  page164_i105
#ISCELL
  standard offpage *
  page164_i106
#ISCELL
  standard offpage *
  page164_i107
#ISCELL
  standard offpage *
  page164_i108
#ISCELL
  standard tap *
  page164_i109
#ISCELL
  standard tap *
  page164_i11
#ISCELL
  standard tap *
  page164_i110
#ISCELL
  standard tap *
  page164_i111
#ISCELL
  standard tap *
  page164_i112
#ISCELL
  standard tap *
  page164_i113
#ISCELL
  standard tap *
  page164_i114
#ISCELL
  standard tap *
  page164_i115
#ISCELL
  standard tap *
  page164_i116
#ISCELL
  standard tap *
  page164_i117
#ISCELL
  standard tap *
  page164_i118
#ISCELL
  standard tap *
  page164_i119
#ISCELL
  standard tap *
  page164_i12
#ISCELL
  standard tap *
  page164_i120
#CELL
  pure_quanta q_cap_diffbus *
  page164_i121
#CELL
  pure_quanta q_cap_diffbus *
  page164_i122
#CELL
  pure_quanta q_cap_diffbus *
  page164_i123
#CELL
  pure_quanta q_cap_diffbus *
  page164_i124
#CELL
  pure_quanta q_cap_diffbus *
  page164_i125
#CELL
  pure_quanta q_cap_diffbus *
  page164_i126
#CELL
  pure_quanta q_cap_diffbus *
  page164_i127
#CELL
  pure_quanta q_cap_diffbus *
  page164_i128
#ISCELL
  standard tap *
  page164_i129
#ISCELL
  standard tap *
  page164_i13
#ISCELL
  standard tap *
  page164_i130
#ISCELL
  standard tap *
  page164_i131
#ISCELL
  standard tap *
  page164_i132
#CELL
  pure_quanta q_cap_diffbus *
  page164_i133
#CELL
  pure_quanta q_cap_diffbus *
  page164_i134
#CELL
  pure_quanta q_cap_diffbus *
  page164_i135
#CELL
  pure_quanta q_cap_diffbus *
  page164_i136
#CELL
  pure_quanta q_cap_diffbus *
  page164_i137
#ISCELL
  standard tap *
  page164_i138
#ISCELL
  standard tap *
  page164_i139
#ISCELL
  standard tap *
  page164_i14
#ISCELL
  standard tap *
  page164_i140
#ISCELL
  standard tap *
  page164_i141
#ISCELL
  standard tap *
  page164_i142
#ISCELL
  standard tap *
  page164_i143
#ISCELL
  standard tap *
  page164_i144
#ISCELL
  standard tap *
  page164_i145
#ISCELL
  standard tap *
  page164_i146
#ISCELL
  standard tap *
  page164_i147
#ISCELL
  standard tap *
  page164_i148
#ISCELL
  standard tap *
  page164_i149
#ISCELL
  standard tap *
  page164_i15
#ISCELL
  standard tap *
  page164_i150
#CELL
  pure_quanta q_cap_diffbus *
  page164_i151
#CELL
  pure_quanta q_cap_diffbus *
  page164_i152
#CELL
  pure_quanta q_cap_diffbus *
  page164_i153
#CELL
  pure_quanta q_cap_diffbus *
  page164_i154
#CELL
  pure_quanta q_cap_diffbus *
  page164_i155
#CELL
  pure_quanta q_cap_diffbus *
  page164_i156
#CELL
  pure_quanta q_cap_diffbus *
  page164_i157
#CELL
  pure_quanta q_cap_diffbus *
  page164_i158
#CELL
  pure_quanta q_cap_diffbus *
  page164_i159
#ISCELL
  standard tap *
  page164_i16
#CELL
  pure_quanta q_cap_diffbus *
  page164_i160
#ISCELL
  standard tap *
  page164_i161
#ISCELL
  standard tap *
  page164_i162
#ISCELL
  standard tap *
  page164_i163
#CELL
  pure_quanta q_cap_diffbus *
  page164_i164
#CELL
  pure_quanta q_cap_diffbus *
  page164_i165
#CELL
  pure_quanta q_cap_diffbus *
  page164_i166
#CELL
  pure_quanta q_cap_diffbus *
  page164_i167
#CELL
  pure_quanta q_cap_diffbus *
  page164_i168
#CELL
  pure_quanta q_cap_diffbus *
  page164_i169
#ISCELL
  standard tap *
  page164_i17
#ISCELL
  standard tap *
  page164_i170
#ISCELL
  standard tap *
  page164_i171
#ISCELL
  standard tap *
  page164_i172
#ISCELL
  standard tap *
  page164_i173
#ISCELL
  standard tap *
  page164_i174
#ISCELL
  standard tap *
  page164_i175
#ISCELL
  standard tap *
  page164_i176
#ISCELL
  standard tap *
  page164_i177
#ISCELL
  standard tap *
  page164_i178
#ISCELL
  standard tap *
  page164_i179
#ISCELL
  standard tap *
  page164_i18
#ISCELL
  standard tap *
  page164_i180
#ISCELL
  standard tap *
  page164_i181
#ISCELL
  standard tap *
  page164_i182
#ISCELL
  standard tap *
  page164_i183
#ISCELL
  standard tap *
  page164_i184
#ISCELL
  standard offpage *
  page164_i185
#ISCELL
  standard offpage *
  page164_i186
#ISCELL
  standard tap *
  page164_i187
#ISCELL
  standard tap *
  page164_i188
#ISCELL
  standard tap *
  page164_i189
#ISCELL
  standard tap *
  page164_i19
#ISCELL
  standard tap *
  page164_i190
#ISCELL
  standard tap *
  page164_i191
#ISCELL
  standard tap *
  page164_i192
#ISCELL
  standard tap *
  page164_i193
#ISCELL
  standard tap *
  page164_i194
#ISCELL
  standard tap *
  page164_i195
#ISCELL
  standard tap *
  page164_i196
#ISCELL
  standard tap *
  page164_i197
#ISCELL
  standard tap *
  page164_i198
#ISCELL
  standard tap *
  page164_i199
#ISCELL
  standard offpage *
  page164_i2
#ISCELL
  standard tap *
  page164_i20
#ISCELL
  standard tap *
  page164_i200
#ISCELL
  standard tap *
  page164_i201
#ISCELL
  standard tap *
  page164_i202
#ISCELL
  standard offpage *
  page164_i203
#ISCELL
  standard offpage *
  page164_i204
#ISCELL
  standard tap *
  page164_i205
#CELL
  pure_quanta q_cap_diffbus *
  page164_i206
#CELL
  pure_quanta q_cap_diffbus *
  page164_i207
#CELL
  pure_quanta q_cap_diffbus *
  page164_i208
#CELL
  pure_quanta q_cap_diffbus *
  page164_i21
#CELL
  pure_quanta q_cap_diffbus *
  page164_i22
#CELL
  pure_quanta q_cap_diffbus *
  page164_i23
#CELL
  pure_quanta q_cap_diffbus *
  page164_i24
#CELL
  pure_quanta q_cap_diffbus *
  page164_i25
#CELL
  pure_quanta q_cap_diffbus *
  page164_i26
#CELL
  pure_quanta q_cap_diffbus *
  page164_i27
#CELL
  pure_quanta q_cap_diffbus *
  page164_i28
#CELL
  pure_quanta q_cap_diffbus *
  page164_i29
#ISCELL
  standard offpage *
  page164_i3
#CELL
  pure_quanta q_cap_diffbus *
  page164_i30
#CELL
  pure_quanta q_cap_diffbus *
  page164_i31
#CELL
  pure_quanta q_cap_diffbus *
  page164_i32
#CELL
  pure_quanta q_cap_diffbus *
  page164_i33
#CELL
  pure_quanta q_cap_diffbus *
  page164_i34
#CELL
  pure_quanta q_cap_diffbus *
  page164_i35
#CELL
  pure_quanta q_cap_diffbus *
  page164_i36
#ISCELL
  standard tap *
  page164_i37
#ISCELL
  standard tap *
  page164_i38
#ISCELL
  standard tap *
  page164_i39
#ISCELL
  standard offpage *
  page164_i4
#ISCELL
  standard tap *
  page164_i40
#ISCELL
  standard tap *
  page164_i41
#ISCELL
  standard tap *
  page164_i42
#ISCELL
  standard tap *
  page164_i43
#ISCELL
  standard tap *
  page164_i44
#ISCELL
  standard tap *
  page164_i45
#ISCELL
  standard tap *
  page164_i46
#ISCELL
  standard tap *
  page164_i47
#ISCELL
  standard tap *
  page164_i48
#ISCELL
  standard tap *
  page164_i49
#ISCELL
  standard tap *
  page164_i5
#ISCELL
  standard tap *
  page164_i50
#ISCELL
  standard tap *
  page164_i51
#ISCELL
  standard tap *
  page164_i52
#CELL
  pure_quanta q_cap_diffbus *
  page164_i53
#CELL
  pure_quanta q_cap_diffbus *
  page164_i54
#CELL
  pure_quanta q_cap_diffbus *
  page164_i55
#CELL
  pure_quanta q_cap_diffbus *
  page164_i56
#CELL
  pure_quanta q_cap_diffbus *
  page164_i57
#CELL
  pure_quanta q_cap_diffbus *
  page164_i58
#CELL
  pure_quanta q_cap_diffbus *
  page164_i59
#ISCELL
  standard tap *
  page164_i6
#CELL
  pure_quanta q_cap_diffbus *
  page164_i60
#CELL
  pure_quanta q_cap_diffbus *
  page164_i61
#CELL
  pure_quanta q_cap_diffbus *
  page164_i62
#CELL
  pure_quanta q_cap_diffbus *
  page164_i63
#CELL
  pure_quanta q_cap_diffbus *
  page164_i64
#CELL
  pure_quanta q_cap_diffbus *
  page164_i65
#CELL
  pure_quanta q_cap_diffbus *
  page164_i66
#CELL
  pure_quanta q_cap_diffbus *
  page164_i67
#CELL
  pure_quanta q_cap_diffbus *
  page164_i68
#ISCELL
  standard tap *
  page164_i69
#ISCELL
  standard tap *
  page164_i7
#ISCELL
  standard tap *
  page164_i70
#ISCELL
  standard tap *
  page164_i71
#ISCELL
  standard tap *
  page164_i72
#ISCELL
  standard tap *
  page164_i73
#ISCELL
  standard tap *
  page164_i74
#ISCELL
  standard tap *
  page164_i75
#ISCELL
  standard tap *
  page164_i76
#ISCELL
  standard tap *
  page164_i77
#ISCELL
  standard tap *
  page164_i78
#ISCELL
  standard tap *
  page164_i79
#ISCELL
  standard tap *
  page164_i8
#ISCELL
  standard tap *
  page164_i80
#ISCELL
  standard tap *
  page164_i81
#ISCELL
  standard tap *
  page164_i82
#ISCELL
  standard tap *
  page164_i83
#ISCELL
  standard tap *
  page164_i84
#ISCELL
  standard tap *
  page164_i85
#ISCELL
  standard tap *
  page164_i86
#ISCELL
  standard tap *
  page164_i87
#ISCELL
  standard tap *
  page164_i88
#ISCELL
  standard tap *
  page164_i89
#ISCELL
  standard tap *
  page164_i9
#ISCELL
  standard tap *
  page164_i90
#ISCELL
  standard tap *
  page164_i91
#ISCELL
  standard tap *
  page164_i92
#ISCELL
  standard offpage *
  page164_i93
#ISCELL
  standard offpage *
  page164_i94
#ISCELL
  standard offpage *
  page164_i95
#ISCELL
  standard offpage *
  page164_i96
#ISCELL
  standard tap *
  page164_i97
#ISCELL
  standard tap *
  page164_i98
#ISCELL
  standard tap *
  page164_i99
#ISCELL
  pure_quanta quanta_title_block_c *
  *
#ISCELL
  standard offpage *
  page165_i1
#ISCELL
  standard tap *
  page165_i10
#ISCELL
  standard tap *
  page165_i100
#ISCELL
  standard tap *
  page165_i101
#ISCELL
  standard tap *
  page165_i102
#ISCELL
  standard tap *
  page165_i103
#ISCELL
  standard tap *
  page165_i104
#ISCELL
  standard offpage *
  page165_i105
#ISCELL
  standard offpage *
  page165_i106
#ISCELL
  standard offpage *
  page165_i107
#ISCELL
  standard offpage *
  page165_i108
#ISCELL
  standard tap *
  page165_i109
#ISCELL
  standard tap *
  page165_i11
#ISCELL
  standard tap *
  page165_i110
#ISCELL
  standard tap *
  page165_i111
#ISCELL
  standard tap *
  page165_i112
#ISCELL
  standard tap *
  page165_i113
#ISCELL
  standard tap *
  page165_i114
#ISCELL
  standard tap *
  page165_i115
#ISCELL
  standard tap *
  page165_i116
#ISCELL
  standard tap *
  page165_i117
#ISCELL
  standard tap *
  page165_i118
#ISCELL
  standard tap *
  page165_i119
#ISCELL
  standard tap *
  page165_i12
#CELL
  pure_quanta q_cap_diffbus *
  page165_i120
#CELL
  pure_quanta q_cap_diffbus *
  page165_i121
#CELL
  pure_quanta q_cap_diffbus *
  page165_i122
#CELL
  pure_quanta q_cap_diffbus *
  page165_i123
#CELL
  pure_quanta q_cap_diffbus *
  page165_i124
#CELL
  pure_quanta q_cap_diffbus *
  page165_i125
#CELL
  pure_quanta q_cap_diffbus *
  page165_i126
#CELL
  pure_quanta q_cap_diffbus *
  page165_i127
#CELL
  pure_quanta q_cap_diffbus *
  page165_i128
#ISCELL
  standard tap *
  page165_i129
#ISCELL
  standard tap *
  page165_i13
#ISCELL
  standard tap *
  page165_i130
#ISCELL
  standard tap *
  page165_i131
#CELL
  pure_quanta q_cap_diffbus *
  page165_i132
#CELL
  pure_quanta q_cap_diffbus *
  page165_i133
#CELL
  pure_quanta q_cap_diffbus *
  page165_i134
#CELL
  pure_quanta q_cap_diffbus *
  page165_i135
#CELL
  pure_quanta q_cap_diffbus *
  page165_i136
#CELL
  pure_quanta q_cap_diffbus *
  page165_i137
#ISCELL
  standard tap *
  page165_i138
#ISCELL
  standard tap *
  page165_i139
#ISCELL
  standard tap *
  page165_i14
#ISCELL
  standard tap *
  page165_i140
#ISCELL
  standard tap *
  page165_i141
#ISCELL
  standard tap *
  page165_i142
#ISCELL
  standard tap *
  page165_i143
#ISCELL
  standard tap *
  page165_i144
#ISCELL
  standard tap *
  page165_i145
#ISCELL
  standard tap *
  page165_i146
#ISCELL
  standard tap *
  page165_i147
#ISCELL
  standard tap *
  page165_i148
#ISCELL
  standard tap *
  page165_i149
#ISCELL
  standard tap *
  page165_i15
#ISCELL
  standard tap *
  page165_i150
#CELL
  pure_quanta q_cap_diffbus *
  page165_i151
#CELL
  pure_quanta q_cap_diffbus *
  page165_i152
#CELL
  pure_quanta q_cap_diffbus *
  page165_i153
#CELL
  pure_quanta q_cap_diffbus *
  page165_i154
#CELL
  pure_quanta q_cap_diffbus *
  page165_i155
#CELL
  pure_quanta q_cap_diffbus *
  page165_i156
#CELL
  pure_quanta q_cap_diffbus *
  page165_i157
#CELL
  pure_quanta q_cap_diffbus *
  page165_i158
#CELL
  pure_quanta q_cap_diffbus *
  page165_i159
#ISCELL
  standard tap *
  page165_i16
#CELL
  pure_quanta q_cap_diffbus *
  page165_i160
#ISCELL
  standard tap *
  page165_i161
#ISCELL
  standard tap *
  page165_i162
#ISCELL
  standard tap *
  page165_i163
#CELL
  pure_quanta q_cap_diffbus *
  page165_i164
#CELL
  pure_quanta q_cap_diffbus *
  page165_i165
#CELL
  pure_quanta q_cap_diffbus *
  page165_i166
#CELL
  pure_quanta q_cap_diffbus *
  page165_i167
#CELL
  pure_quanta q_cap_diffbus *
  page165_i168
#CELL
  pure_quanta q_cap_diffbus *
  page165_i169
#ISCELL
  standard tap *
  page165_i17
#ISCELL
  standard tap *
  page165_i170
#ISCELL
  standard tap *
  page165_i171
#ISCELL
  standard tap *
  page165_i172
#ISCELL
  standard tap *
  page165_i173
#ISCELL
  standard tap *
  page165_i174
#ISCELL
  standard tap *
  page165_i175
#ISCELL
  standard tap *
  page165_i176
#ISCELL
  standard tap *
  page165_i177
#ISCELL
  standard tap *
  page165_i178
#ISCELL
  standard tap *
  page165_i179
#ISCELL
  standard tap *
  page165_i18
#ISCELL
  standard tap *
  page165_i180
#ISCELL
  standard tap *
  page165_i181
#ISCELL
  standard tap *
  page165_i182
#ISCELL
  standard tap *
  page165_i183
#ISCELL
  standard tap *
  page165_i184
#ISCELL
  standard tap *
  page165_i185
#ISCELL
  standard offpage *
  page165_i186
#ISCELL
  standard offpage *
  page165_i187
#ISCELL
  standard tap *
  page165_i188
#ISCELL
  standard tap *
  page165_i189
#ISCELL
  standard tap *
  page165_i19
#ISCELL
  standard tap *
  page165_i190
#ISCELL
  standard tap *
  page165_i191
#ISCELL
  standard tap *
  page165_i192
#ISCELL
  standard tap *
  page165_i193
#ISCELL
  standard tap *
  page165_i194
#ISCELL
  standard tap *
  page165_i195
#ISCELL
  standard tap *
  page165_i196
#ISCELL
  standard tap *
  page165_i197
#ISCELL
  standard tap *
  page165_i198
#ISCELL
  standard tap *
  page165_i199
#ISCELL
  standard offpage *
  page165_i2
#ISCELL
  standard tap *
  page165_i20
#ISCELL
  standard tap *
  page165_i200
#ISCELL
  standard tap *
  page165_i201
#ISCELL
  standard tap *
  page165_i202
#ISCELL
  standard tap *
  page165_i203
#ISCELL
  standard offpage *
  page165_i204
#ISCELL
  standard offpage *
  page165_i205
#CELL
  pure_quanta q_cap_diffbus *
  page165_i206
#ISCELL
  standard tap *
  page165_i207
#ISCELL
  standard tap *
  page165_i208
#CELL
  pure_quanta q_cap_diffbus *
  page165_i21
#CELL
  pure_quanta q_cap_diffbus *
  page165_i22
#CELL
  pure_quanta q_cap_diffbus *
  page165_i23
#CELL
  pure_quanta q_cap_diffbus *
  page165_i24
#CELL
  pure_quanta q_cap_diffbus *
  page165_i25
#CELL
  pure_quanta q_cap_diffbus *
  page165_i26
#CELL
  pure_quanta q_cap_diffbus *
  page165_i27
#CELL
  pure_quanta q_cap_diffbus *
  page165_i28
#CELL
  pure_quanta q_cap_diffbus *
  page165_i29
#ISCELL
  standard offpage *
  page165_i3
#CELL
  pure_quanta q_cap_diffbus *
  page165_i30
#ISCELL
  standard tap *
  page165_i31
#ISCELL
  standard tap *
  page165_i32
#ISCELL
  standard tap *
  page165_i33
#ISCELL
  standard tap *
  page165_i34
#ISCELL
  standard tap *
  page165_i35
#CELL
  pure_quanta q_cap_diffbus *
  page165_i36
#CELL
  pure_quanta q_cap_diffbus *
  page165_i37
#CELL
  pure_quanta q_cap_diffbus *
  page165_i38
#CELL
  pure_quanta q_cap_diffbus *
  page165_i39
#ISCELL
  standard offpage *
  page165_i4
#CELL
  pure_quanta q_cap_diffbus *
  page165_i40
#CELL
  pure_quanta q_cap_diffbus *
  page165_i41
#ISCELL
  standard tap *
  page165_i42
#ISCELL
  standard tap *
  page165_i43
#ISCELL
  standard tap *
  page165_i44
#ISCELL
  standard tap *
  page165_i45
#ISCELL
  standard tap *
  page165_i46
#ISCELL
  standard tap *
  page165_i47
#ISCELL
  standard tap *
  page165_i48
#ISCELL
  standard tap *
  page165_i49
#ISCELL
  standard tap *
  page165_i5
#ISCELL
  standard tap *
  page165_i50
#ISCELL
  standard tap *
  page165_i51
#ISCELL
  standard tap *
  page165_i52
#ISCELL
  standard tap *
  page165_i53
#ISCELL
  standard tap *
  page165_i54
#ISCELL
  standard tap *
  page165_i55
#ISCELL
  standard tap *
  page165_i56
#ISCELL
  standard tap *
  page165_i57
#ISCELL
  standard tap *
  page165_i58
#ISCELL
  standard tap *
  page165_i59
#ISCELL
  standard tap *
  page165_i6
#ISCELL
  standard tap *
  page165_i60
#CELL
  pure_quanta q_cap_diffbus *
  page165_i61
#CELL
  pure_quanta q_cap_diffbus *
  page165_i62
#CELL
  pure_quanta q_cap_diffbus *
  page165_i63
#CELL
  pure_quanta q_cap_diffbus *
  page165_i64
#CELL
  pure_quanta q_cap_diffbus *
  page165_i65
#CELL
  pure_quanta q_cap_diffbus *
  page165_i66
#CELL
  pure_quanta q_cap_diffbus *
  page165_i67
#CELL
  pure_quanta q_cap_diffbus *
  page165_i68
#CELL
  pure_quanta q_cap_diffbus *
  page165_i69
#ISCELL
  standard tap *
  page165_i7
#CELL
  pure_quanta q_cap_diffbus *
  page165_i70
#ISCELL
  standard tap *
  page165_i71
#ISCELL
  standard tap *
  page165_i72
#ISCELL
  standard tap *
  page165_i73
#ISCELL
  standard tap *
  page165_i74
#ISCELL
  standard tap *
  page165_i75
#CELL
  pure_quanta q_cap_diffbus *
  page165_i76
#CELL
  pure_quanta q_cap_diffbus *
  page165_i77
#CELL
  pure_quanta q_cap_diffbus *
  page165_i78
#CELL
  pure_quanta q_cap_diffbus *
  page165_i79
#ISCELL
  standard tap *
  page165_i8
#CELL
  pure_quanta q_cap_diffbus *
  page165_i80
#CELL
  pure_quanta q_cap_diffbus *
  page165_i81
#ISCELL
  standard tap *
  page165_i82
#ISCELL
  standard tap *
  page165_i83
#ISCELL
  standard tap *
  page165_i84
#ISCELL
  standard tap *
  page165_i85
#ISCELL
  standard tap *
  page165_i86
#ISCELL
  standard tap *
  page165_i87
#ISCELL
  standard tap *
  page165_i88
#ISCELL
  standard tap *
  page165_i89
#ISCELL
  standard tap *
  page165_i9
#ISCELL
  standard tap *
  page165_i90
#ISCELL
  standard tap *
  page165_i91
#ISCELL
  standard tap *
  page165_i92
#ISCELL
  standard offpage *
  page165_i93
#ISCELL
  standard offpage *
  page165_i94
#ISCELL
  standard offpage *
  page165_i95
#ISCELL
  standard offpage *
  page165_i96
#ISCELL
  standard tap *
  page165_i97
#ISCELL
  standard tap *
  page165_i98
#ISCELL
  standard tap *
  page165_i99
#ISCELL
  pure_quanta quanta_title_block_c *
  *
#ISCELL
  standard offpage *
  page166_i209
#ISCELL
  standard offpage *
  page166_i210
#ISCELL
  standard offpage *
  page166_i211
#ISCELL
  standard offpage *
  page166_i212
#ISCELL
  standard tap *
  page166_i213
#ISCELL
  standard tap *
  page166_i214
#ISCELL
  standard tap *
  page166_i215
#ISCELL
  standard tap *
  page166_i216
#ISCELL
  standard tap *
  page166_i217
#ISCELL
  standard tap *
  page166_i218
#ISCELL
  standard tap *
  page166_i219
#ISCELL
  standard tap *
  page166_i220
#ISCELL
  standard tap *
  page166_i221
#ISCELL
  standard tap *
  page166_i222
#ISCELL
  standard tap *
  page166_i223
#ISCELL
  standard tap *
  page166_i224
#ISCELL
  standard tap *
  page166_i225
#ISCELL
  standard tap *
  page166_i226
#ISCELL
  standard tap *
  page166_i227
#ISCELL
  standard tap *
  page166_i228
#CELL
  pure_quanta q_cap_diffbus *
  page166_i229
#CELL
  pure_quanta q_cap_diffbus *
  page166_i230
#CELL
  pure_quanta q_cap_diffbus *
  page166_i231
#CELL
  pure_quanta q_cap_diffbus *
  page166_i232
#CELL
  pure_quanta q_cap_diffbus *
  page166_i233
#CELL
  pure_quanta q_cap_diffbus *
  page166_i234
#CELL
  pure_quanta q_cap_diffbus *
  page166_i235
#CELL
  pure_quanta q_cap_diffbus *
  page166_i236
#CELL
  pure_quanta q_cap_diffbus *
  page166_i237
#CELL
  pure_quanta q_cap_diffbus *
  page166_i238
#CELL
  pure_quanta q_cap_diffbus *
  page166_i239
#CELL
  pure_quanta q_cap_diffbus *
  page166_i240
#CELL
  pure_quanta q_cap_diffbus *
  page166_i241
#CELL
  pure_quanta q_cap_diffbus *
  page166_i242
#ISCELL
  standard tap *
  page166_i243
#ISCELL
  standard tap *
  page166_i244
#ISCELL
  standard tap *
  page166_i245
#ISCELL
  standard tap *
  page166_i246
#ISCELL
  standard tap *
  page166_i247
#ISCELL
  standard tap *
  page166_i248
#ISCELL
  standard tap *
  page166_i249
#ISCELL
  standard tap *
  page166_i250
#ISCELL
  standard tap *
  page166_i251
#ISCELL
  standard tap *
  page166_i252
#ISCELL
  standard tap *
  page166_i253
#ISCELL
  standard tap *
  page166_i254
#ISCELL
  standard tap *
  page166_i255
#ISCELL
  standard tap *
  page166_i256
#ISCELL
  standard tap *
  page166_i257
#ISCELL
  standard tap *
  page166_i258
#CELL
  pure_quanta q_cap_diffbus *
  page166_i259
#CELL
  pure_quanta q_cap_diffbus *
  page166_i260
#CELL
  pure_quanta q_cap_diffbus *
  page166_i261
#CELL
  pure_quanta q_cap_diffbus *
  page166_i262
#CELL
  pure_quanta q_cap_diffbus *
  page166_i263
#CELL
  pure_quanta q_cap_diffbus *
  page166_i264
#CELL
  pure_quanta q_cap_diffbus *
  page166_i265
#CELL
  pure_quanta q_cap_diffbus *
  page166_i266
#CELL
  pure_quanta q_cap_diffbus *
  page166_i267
#CELL
  pure_quanta q_cap_diffbus *
  page166_i268
#CELL
  pure_quanta q_cap_diffbus *
  page166_i269
#CELL
  pure_quanta q_cap_diffbus *
  page166_i270
#CELL
  pure_quanta q_cap_diffbus *
  page166_i271
#CELL
  pure_quanta q_cap_diffbus *
  page166_i272
#CELL
  pure_quanta q_cap_diffbus *
  page166_i273
#CELL
  pure_quanta q_cap_diffbus *
  page166_i274
#ISCELL
  standard tap *
  page166_i275
#ISCELL
  standard tap *
  page166_i276
#ISCELL
  standard tap *
  page166_i277
#ISCELL
  standard tap *
  page166_i278
#ISCELL
  standard tap *
  page166_i279
#ISCELL
  standard tap *
  page166_i280
#ISCELL
  standard tap *
  page166_i281
#ISCELL
  standard tap *
  page166_i282
#ISCELL
  standard tap *
  page166_i283
#ISCELL
  standard tap *
  page166_i284
#ISCELL
  standard tap *
  page166_i285
#ISCELL
  standard tap *
  page166_i286
#ISCELL
  standard tap *
  page166_i287
#ISCELL
  standard tap *
  page166_i288
#ISCELL
  standard tap *
  page166_i289
#ISCELL
  standard tap *
  page166_i290
#ISCELL
  standard offpage *
  page166_i291
#ISCELL
  standard offpage *
  page166_i292
#ISCELL
  standard tap *
  page166_i293
#ISCELL
  standard tap *
  page166_i294
#ISCELL
  standard tap *
  page166_i295
#ISCELL
  standard tap *
  page166_i296
#ISCELL
  standard tap *
  page166_i297
#ISCELL
  standard tap *
  page166_i298
#ISCELL
  standard tap *
  page166_i299
#ISCELL
  standard tap *
  page166_i300
#ISCELL
  standard tap *
  page166_i301
#ISCELL
  standard tap *
  page166_i302
#ISCELL
  standard tap *
  page166_i303
#ISCELL
  standard tap *
  page166_i304
#ISCELL
  standard tap *
  page166_i305
#ISCELL
  standard tap *
  page166_i306
#ISCELL
  standard tap *
  page166_i307
#ISCELL
  standard tap *
  page166_i308
#ISCELL
  standard offpage *
  page166_i309
#ISCELL
  standard offpage *
  page166_i310
#CELL
  pure_quanta q_cap_diffbus *
  page166_i311
#CELL
  pure_quanta q_cap_diffbus *
  page166_i312
#ISCELL
  standard offpage *
  page166_i313
#ISCELL
  standard offpage *
  page166_i314
#ISCELL
  standard offpage *
  page166_i315
#ISCELL
  standard offpage *
  page166_i316
#ISCELL
  standard tap *
  page166_i317
#ISCELL
  standard tap *
  page166_i318
#ISCELL
  standard tap *
  page166_i319
#ISCELL
  standard tap *
  page166_i320
#ISCELL
  standard tap *
  page166_i321
#ISCELL
  standard tap *
  page166_i322
#ISCELL
  standard tap *
  page166_i323
#ISCELL
  standard tap *
  page166_i324
#ISCELL
  standard tap *
  page166_i325
#ISCELL
  standard tap *
  page166_i326
#ISCELL
  standard tap *
  page166_i327
#ISCELL
  standard tap *
  page166_i328
#ISCELL
  standard tap *
  page166_i329
#ISCELL
  standard tap *
  page166_i330
#ISCELL
  standard tap *
  page166_i331
#ISCELL
  standard tap *
  page166_i332
#CELL
  pure_quanta q_cap_diffbus *
  page166_i333
#CELL
  pure_quanta q_cap_diffbus *
  page166_i334
#CELL
  pure_quanta q_cap_diffbus *
  page166_i335
#CELL
  pure_quanta q_cap_diffbus *
  page166_i336
#CELL
  pure_quanta q_cap_diffbus *
  page166_i337
#CELL
  pure_quanta q_cap_diffbus *
  page166_i338
#CELL
  pure_quanta q_cap_diffbus *
  page166_i339
#CELL
  pure_quanta q_cap_diffbus *
  page166_i340
#CELL
  pure_quanta q_cap_diffbus *
  page166_i341
#CELL
  pure_quanta q_cap_diffbus *
  page166_i342
#CELL
  pure_quanta q_cap_diffbus *
  page166_i343
#CELL
  pure_quanta q_cap_diffbus *
  page166_i344
#CELL
  pure_quanta q_cap_diffbus *
  page166_i345
#CELL
  pure_quanta q_cap_diffbus *
  page166_i346
#ISCELL
  standard tap *
  page166_i347
#ISCELL
  standard tap *
  page166_i348
#ISCELL
  standard tap *
  page166_i349
#ISCELL
  standard tap *
  page166_i350
#ISCELL
  standard tap *
  page166_i351
#ISCELL
  standard tap *
  page166_i352
#ISCELL
  standard tap *
  page166_i353
#ISCELL
  standard tap *
  page166_i354
#ISCELL
  standard tap *
  page166_i355
#ISCELL
  standard tap *
  page166_i356
#ISCELL
  standard tap *
  page166_i357
#ISCELL
  standard tap *
  page166_i358
#ISCELL
  standard tap *
  page166_i359
#ISCELL
  standard tap *
  page166_i360
#ISCELL
  standard tap *
  page166_i361
#ISCELL
  standard tap *
  page166_i362
#CELL
  pure_quanta q_cap_diffbus *
  page166_i363
#CELL
  pure_quanta q_cap_diffbus *
  page166_i364
#CELL
  pure_quanta q_cap_diffbus *
  page166_i365
#CELL
  pure_quanta q_cap_diffbus *
  page166_i366
#CELL
  pure_quanta q_cap_diffbus *
  page166_i367
#CELL
  pure_quanta q_cap_diffbus *
  page166_i368
#CELL
  pure_quanta q_cap_diffbus *
  page166_i369
#CELL
  pure_quanta q_cap_diffbus *
  page166_i370
#CELL
  pure_quanta q_cap_diffbus *
  page166_i371
#CELL
  pure_quanta q_cap_diffbus *
  page166_i372
#CELL
  pure_quanta q_cap_diffbus *
  page166_i373
#CELL
  pure_quanta q_cap_diffbus *
  page166_i374
#CELL
  pure_quanta q_cap_diffbus *
  page166_i375
#CELL
  pure_quanta q_cap_diffbus *
  page166_i376
#CELL
  pure_quanta q_cap_diffbus *
  page166_i377
#CELL
  pure_quanta q_cap_diffbus *
  page166_i378
#ISCELL
  standard tap *
  page166_i379
#ISCELL
  standard tap *
  page166_i380
#ISCELL
  standard tap *
  page166_i381
#ISCELL
  standard tap *
  page166_i382
#ISCELL
  standard tap *
  page166_i383
#ISCELL
  standard tap *
  page166_i384
#ISCELL
  standard tap *
  page166_i385
#ISCELL
  standard tap *
  page166_i386
#ISCELL
  standard tap *
  page166_i387
#ISCELL
  standard tap *
  page166_i388
#ISCELL
  standard tap *
  page166_i389
#ISCELL
  standard tap *
  page166_i390
#ISCELL
  standard tap *
  page166_i391
#ISCELL
  standard tap *
  page166_i392
#ISCELL
  standard tap *
  page166_i393
#ISCELL
  standard offpage *
  page166_i394
#ISCELL
  standard offpage *
  page166_i395
#ISCELL
  standard tap *
  page166_i396
#ISCELL
  standard tap *
  page166_i397
#ISCELL
  standard tap *
  page166_i398
#ISCELL
  standard tap *
  page166_i399
#ISCELL
  standard tap *
  page166_i400
#ISCELL
  standard tap *
  page166_i401
#ISCELL
  standard tap *
  page166_i402
#ISCELL
  standard tap *
  page166_i403
#ISCELL
  standard tap *
  page166_i404
#ISCELL
  standard tap *
  page166_i405
#ISCELL
  standard tap *
  page166_i406
#ISCELL
  standard tap *
  page166_i407
#ISCELL
  standard tap *
  page166_i408
#ISCELL
  standard tap *
  page166_i409
#ISCELL
  standard tap *
  page166_i410
#ISCELL
  standard tap *
  page166_i411
#ISCELL
  standard offpage *
  page166_i412
#ISCELL
  standard offpage *
  page166_i413
#ISCELL
  standard tap *
  page166_i414
#CELL
  pure_quanta q_cap_diffbus *
  page166_i415
#CELL
  pure_quanta q_cap_diffbus *
  page166_i416
#ISCELL
  pure_quanta quanta_title_block_c *
  *
#ISCELL
  standard offpage *
  page167_i107
#ISCELL
  standard offpage *
  page167_i108
#ISCELL
  standard tap *
  page167_i109
#ISCELL
  standard tap *
  page167_i110
#ISCELL
  standard tap *
  page167_i111
#ISCELL
  standard tap *
  page167_i112
#ISCELL
  standard tap *
  page167_i113
#ISCELL
  standard tap *
  page167_i114
#ISCELL
  standard tap *
  page167_i115
#ISCELL
  standard tap *
  page167_i116
#ISCELL
  standard tap *
  page167_i117
#ISCELL
  standard tap *
  page167_i118
#ISCELL
  standard tap *
  page167_i119
#ISCELL
  standard tap *
  page167_i120
#ISCELL
  standard tap *
  page167_i121
#CELL
  pure_quanta q_cap_diffbus *
  page167_i122
#CELL
  pure_quanta q_cap_diffbus *
  page167_i123
#CELL
  pure_quanta q_cap_diffbus *
  page167_i124
#CELL
  pure_quanta q_cap_diffbus *
  page167_i125
#CELL
  pure_quanta q_cap_diffbus *
  page167_i126
#CELL
  pure_quanta q_cap_diffbus *
  page167_i127
#CELL
  pure_quanta q_cap_diffbus *
  page167_i128
#CELL
  pure_quanta q_cap_diffbus *
  page167_i129
#CELL
  pure_quanta q_cap_diffbus *
  page167_i130
#CELL
  pure_quanta q_cap_diffbus *
  page167_i131
#ISCELL
  standard tap *
  page167_i132
#ISCELL
  standard tap *
  page167_i133
#ISCELL
  standard tap *
  page167_i134
#CELL
  pure_quanta q_cap_diffbus *
  page167_i135
#CELL
  pure_quanta q_cap_diffbus *
  page167_i136
#CELL
  pure_quanta q_cap_diffbus *
  page167_i137
#CELL
  pure_quanta q_cap_diffbus *
  page167_i138
#CELL
  pure_quanta q_cap_diffbus *
  page167_i139
#CELL
  pure_quanta q_cap_diffbus *
  page167_i140
#ISCELL
  standard tap *
  page167_i141
#ISCELL
  standard tap *
  page167_i142
#ISCELL
  standard tap *
  page167_i143
#ISCELL
  standard tap *
  page167_i144
#ISCELL
  standard tap *
  page167_i145
#ISCELL
  standard tap *
  page167_i146
#ISCELL
  standard tap *
  page167_i147
#ISCELL
  standard tap *
  page167_i148
#ISCELL
  standard tap *
  page167_i149
#ISCELL
  standard tap *
  page167_i150
#ISCELL
  standard tap *
  page167_i151
#ISCELL
  standard tap *
  page167_i152
#ISCELL
  standard tap *
  page167_i153
#CELL
  pure_quanta q_cap_diffbus *
  page167_i154
#CELL
  pure_quanta q_cap_diffbus *
  page167_i155
#CELL
  pure_quanta q_cap_diffbus *
  page167_i156
#CELL
  pure_quanta q_cap_diffbus *
  page167_i157
#CELL
  pure_quanta q_cap_diffbus *
  page167_i158
#CELL
  pure_quanta q_cap_diffbus *
  page167_i159
#CELL
  pure_quanta q_cap_diffbus *
  page167_i160
#CELL
  pure_quanta q_cap_diffbus *
  page167_i161
#CELL
  pure_quanta q_cap_diffbus *
  page167_i162
#CELL
  pure_quanta q_cap_diffbus *
  page167_i163
#ISCELL
  standard tap *
  page167_i164
#ISCELL
  standard tap *
  page167_i165
#ISCELL
  standard tap *
  page167_i166
#CELL
  pure_quanta q_cap_diffbus *
  page167_i167
#CELL
  pure_quanta q_cap_diffbus *
  page167_i168
#CELL
  pure_quanta q_cap_diffbus *
  page167_i169
#CELL
  pure_quanta q_cap_diffbus *
  page167_i170
#CELL
  pure_quanta q_cap_diffbus *
  page167_i171
#CELL
  pure_quanta q_cap_diffbus *
  page167_i172
#ISCELL
  standard tap *
  page167_i173
#ISCELL
  standard tap *
  page167_i174
#ISCELL
  standard tap *
  page167_i175
#ISCELL
  standard tap *
  page167_i176
#ISCELL
  standard tap *
  page167_i177
#ISCELL
  standard tap *
  page167_i178
#ISCELL
  standard tap *
  page167_i179
#ISCELL
  standard tap *
  page167_i180
#ISCELL
  standard tap *
  page167_i181
#ISCELL
  standard tap *
  page167_i182
#ISCELL
  standard tap *
  page167_i183
#ISCELL
  standard tap *
  page167_i184
#ISCELL
  standard tap *
  page167_i185
#ISCELL
  standard tap *
  page167_i186
#ISCELL
  standard tap *
  page167_i187
#ISCELL
  standard tap *
  page167_i188
#ISCELL
  standard offpage *
  page167_i189
#ISCELL
  standard offpage *
  page167_i190
#ISCELL
  standard tap *
  page167_i191
#ISCELL
  standard tap *
  page167_i192
#ISCELL
  standard tap *
  page167_i193
#ISCELL
  standard tap *
  page167_i194
#ISCELL
  standard tap *
  page167_i195
#ISCELL
  standard tap *
  page167_i196
#ISCELL
  standard tap *
  page167_i197
#ISCELL
  standard tap *
  page167_i198
#ISCELL
  standard tap *
  page167_i199
#ISCELL
  standard tap *
  page167_i200
#ISCELL
  standard tap *
  page167_i201
#ISCELL
  standard tap *
  page167_i202
#ISCELL
  standard tap *
  page167_i203
#ISCELL
  standard tap *
  page167_i204
#ISCELL
  standard tap *
  page167_i205
#ISCELL
  standard tap *
  page167_i206
#ISCELL
  standard offpage *
  page167_i207
#ISCELL
  standard offpage *
  page167_i208
#ISCELL
  standard offpage *
  page167_i209
#ISCELL
  standard offpage *
  page167_i210
#ISCELL
  standard offpage *
  page167_i211
#ISCELL
  standard offpage *
  page167_i212
#ISCELL
  standard tap *
  page167_i213
#ISCELL
  standard tap *
  page167_i214
#ISCELL
  standard tap *
  page167_i215
#ISCELL
  standard tap *
  page167_i216
#ISCELL
  standard tap *
  page167_i217
#ISCELL
  standard tap *
  page167_i218
#ISCELL
  standard tap *
  page167_i219
#ISCELL
  standard tap *
  page167_i220
#ISCELL
  standard tap *
  page167_i221
#ISCELL
  standard tap *
  page167_i222
#ISCELL
  standard tap *
  page167_i223
#ISCELL
  standard tap *
  page167_i224
#ISCELL
  standard tap *
  page167_i225
#ISCELL
  standard tap *
  page167_i226
#ISCELL
  standard tap *
  page167_i227
#ISCELL
  standard tap *
  page167_i228
#CELL
  pure_quanta q_cap_diffbus *
  page167_i229
#CELL
  pure_quanta q_cap_diffbus *
  page167_i230
#CELL
  pure_quanta q_cap_diffbus *
  page167_i231
#CELL
  pure_quanta q_cap_diffbus *
  page167_i232
#CELL
  pure_quanta q_cap_diffbus *
  page167_i233
#CELL
  pure_quanta q_cap_diffbus *
  page167_i234
#CELL
  pure_quanta q_cap_diffbus *
  page167_i235
#CELL
  pure_quanta q_cap_diffbus *
  page167_i236
#CELL
  pure_quanta q_cap_diffbus *
  page167_i237
#ISCELL
  standard tap *
  page167_i238
#ISCELL
  standard tap *
  page167_i239
#ISCELL
  standard tap *
  page167_i240
#ISCELL
  standard tap *
  page167_i241
#ISCELL
  standard tap *
  page167_i242
#ISCELL
  standard tap *
  page167_i243
#ISCELL
  standard tap *
  page167_i244
#ISCELL
  standard tap *
  page167_i245
#CELL
  pure_quanta q_cap_diffbus *
  page167_i246
#CELL
  pure_quanta q_cap_diffbus *
  page167_i247
#CELL
  pure_quanta q_cap_diffbus *
  page167_i248
#CELL
  pure_quanta q_cap_diffbus *
  page167_i249
#CELL
  pure_quanta q_cap_diffbus *
  page167_i250
#CELL
  pure_quanta q_cap_diffbus *
  page167_i251
#ISCELL
  standard tap *
  page167_i252
#ISCELL
  standard tap *
  page167_i253
#ISCELL
  standard tap *
  page167_i254
#ISCELL
  standard tap *
  page167_i255
#ISCELL
  standard tap *
  page167_i256
#ISCELL
  standard tap *
  page167_i257
#ISCELL
  standard tap *
  page167_i258
#ISCELL
  standard tap *
  page167_i259
#ISCELL
  standard tap *
  page167_i260
#ISCELL
  standard tap *
  page167_i261
#ISCELL
  standard tap *
  page167_i262
#ISCELL
  standard tap *
  page167_i263
#ISCELL
  standard tap *
  page167_i264
#ISCELL
  standard tap *
  page167_i265
#ISCELL
  standard tap *
  page167_i266
#ISCELL
  standard tap *
  page167_i267
#ISCELL
  standard tap *
  page167_i268
#ISCELL
  standard tap *
  page167_i269
#ISCELL
  standard tap *
  page167_i270
#ISCELL
  standard tap *
  page167_i271
#ISCELL
  standard tap *
  page167_i272
#ISCELL
  standard tap *
  page167_i273
#CELL
  pure_quanta q_cap_diffbus *
  page167_i274
#CELL
  pure_quanta q_cap_diffbus *
  page167_i275
#CELL
  pure_quanta q_cap_diffbus *
  page167_i276
#CELL
  pure_quanta q_cap_diffbus *
  page167_i277
#CELL
  pure_quanta q_cap_diffbus *
  page167_i278
#CELL
  pure_quanta q_cap_diffbus *
  page167_i279
#CELL
  pure_quanta q_cap_diffbus *
  page167_i280
#CELL
  pure_quanta q_cap_diffbus *
  page167_i281
#CELL
  pure_quanta q_cap_diffbus *
  page167_i282
#CELL
  pure_quanta q_cap_diffbus *
  page167_i283
#ISCELL
  standard tap *
  page167_i284
#ISCELL
  standard tap *
  page167_i285
#ISCELL
  standard tap *
  page167_i286
#ISCELL
  standard tap *
  page167_i287
#ISCELL
  standard tap *
  page167_i288
#ISCELL
  standard tap *
  page167_i289
#ISCELL
  standard tap *
  page167_i290
#ISCELL
  standard tap *
  page167_i291
#ISCELL
  standard tap *
  page167_i292
#ISCELL
  standard tap *
  page167_i293
#CELL
  pure_quanta q_cap_diffbus *
  page167_i294
#CELL
  pure_quanta q_cap_diffbus *
  page167_i295
#CELL
  pure_quanta q_cap_diffbus *
  page167_i296
#CELL
  pure_quanta q_cap_diffbus *
  page167_i297
#CELL
  pure_quanta q_cap_diffbus *
  page167_i298
#CELL
  pure_quanta q_cap_diffbus *
  page167_i299
#ISCELL
  standard tap *
  page167_i300
#ISCELL
  standard tap *
  page167_i301
#ISCELL
  standard tap *
  page167_i302
#ISCELL
  standard tap *
  page167_i303
#ISCELL
  standard tap *
  page167_i304
#ISCELL
  standard tap *
  page167_i305
#ISCELL
  standard offpage *
  page167_i306
#ISCELL
  standard offpage *
  page167_i307
#ISCELL
  standard offpage *
  page167_i308
#ISCELL
  standard offpage *
  page167_i309
#ISCELL
  standard tap *
  page167_i310
#ISCELL
  standard tap *
  page167_i311
#CELL
  pure_quanta q_cap_diffbus *
  page167_i312
#ISCELL
  standard offpage *
  page167_i95
#ISCELL
  standard offpage *
  page167_i96
#ISCELL
  pure_quanta quanta_title_block_c *
  *
#ISCELL
  standard offpage *
  page168_i103
#ISCELL
  standard offpage *
  page168_i104
#ISCELL
  standard offpage *
  page168_i107
#ISCELL
  standard offpage *
  page168_i108
#ISCELL
  standard tap *
  page168_i109
#ISCELL
  standard tap *
  page168_i110
#ISCELL
  standard tap *
  page168_i111
#ISCELL
  standard tap *
  page168_i112
#ISCELL
  standard tap *
  page168_i113
#ISCELL
  standard tap *
  page168_i114
#ISCELL
  standard tap *
  page168_i115
#ISCELL
  standard tap *
  page168_i116
#ISCELL
  standard tap *
  page168_i117
#ISCELL
  standard tap *
  page168_i118
#ISCELL
  standard tap *
  page168_i119
#ISCELL
  standard tap *
  page168_i120
#ISCELL
  standard tap *
  page168_i121
#ISCELL
  standard tap *
  page168_i122
#ISCELL
  standard tap *
  page168_i123
#ISCELL
  standard tap *
  page168_i124
#CELL
  pure_quanta q_cap_diffbus *
  page168_i125
#CELL
  pure_quanta q_cap_diffbus *
  page168_i126
#CELL
  pure_quanta q_cap_diffbus *
  page168_i127
#CELL
  pure_quanta q_cap_diffbus *
  page168_i128
#CELL
  pure_quanta q_cap_diffbus *
  page168_i129
#CELL
  pure_quanta q_cap_diffbus *
  page168_i130
#CELL
  pure_quanta q_cap_diffbus *
  page168_i131
#CELL
  pure_quanta q_cap_diffbus *
  page168_i132
#CELL
  pure_quanta q_cap_diffbus *
  page168_i133
#CELL
  pure_quanta q_cap_diffbus *
  page168_i134
#CELL
  pure_quanta q_cap_diffbus *
  page168_i135
#CELL
  pure_quanta q_cap_diffbus *
  page168_i136
#CELL
  pure_quanta q_cap_diffbus *
  page168_i137
#CELL
  pure_quanta q_cap_diffbus *
  page168_i138
#CELL
  pure_quanta q_cap_diffbus *
  page168_i139
#CELL
  pure_quanta q_cap_diffbus *
  page168_i140
#ISCELL
  standard tap *
  page168_i141
#ISCELL
  standard tap *
  page168_i142
#ISCELL
  standard tap *
  page168_i143
#ISCELL
  standard tap *
  page168_i144
#ISCELL
  standard tap *
  page168_i145
#ISCELL
  standard tap *
  page168_i146
#ISCELL
  standard tap *
  page168_i147
#ISCELL
  standard tap *
  page168_i148
#ISCELL
  standard tap *
  page168_i149
#ISCELL
  standard tap *
  page168_i150
#ISCELL
  standard tap *
  page168_i151
#ISCELL
  standard tap *
  page168_i152
#ISCELL
  standard tap *
  page168_i153
#ISCELL
  standard tap *
  page168_i154
#ISCELL
  standard tap *
  page168_i155
#ISCELL
  standard tap *
  page168_i156
#CELL
  pure_quanta q_cap_diffbus *
  page168_i157
#CELL
  pure_quanta q_cap_diffbus *
  page168_i158
#CELL
  pure_quanta q_cap_diffbus *
  page168_i159
#CELL
  pure_quanta q_cap_diffbus *
  page168_i160
#CELL
  pure_quanta q_cap_diffbus *
  page168_i161
#CELL
  pure_quanta q_cap_diffbus *
  page168_i162
#CELL
  pure_quanta q_cap_diffbus *
  page168_i163
#CELL
  pure_quanta q_cap_diffbus *
  page168_i164
#CELL
  pure_quanta q_cap_diffbus *
  page168_i165
#CELL
  pure_quanta q_cap_diffbus *
  page168_i166
#CELL
  pure_quanta q_cap_diffbus *
  page168_i167
#CELL
  pure_quanta q_cap_diffbus *
  page168_i168
#CELL
  pure_quanta q_cap_diffbus *
  page168_i169
#CELL
  pure_quanta q_cap_diffbus *
  page168_i170
#CELL
  pure_quanta q_cap_diffbus *
  page168_i171
#CELL
  pure_quanta q_cap_diffbus *
  page168_i172
#ISCELL
  standard tap *
  page168_i173
#ISCELL
  standard tap *
  page168_i174
#ISCELL
  standard tap *
  page168_i175
#ISCELL
  standard tap *
  page168_i176
#ISCELL
  standard tap *
  page168_i177
#ISCELL
  standard tap *
  page168_i178
#ISCELL
  standard tap *
  page168_i179
#ISCELL
  standard tap *
  page168_i180
#ISCELL
  standard tap *
  page168_i181
#ISCELL
  standard tap *
  page168_i182
#ISCELL
  standard tap *
  page168_i183
#ISCELL
  standard tap *
  page168_i184
#ISCELL
  standard tap *
  page168_i185
#ISCELL
  standard tap *
  page168_i186
#ISCELL
  standard tap *
  page168_i187
#ISCELL
  standard tap *
  page168_i188
#ISCELL
  standard offpage *
  page168_i189
#ISCELL
  standard offpage *
  page168_i190
#ISCELL
  standard tap *
  page168_i191
#ISCELL
  standard tap *
  page168_i192
#ISCELL
  standard tap *
  page168_i193
#ISCELL
  standard tap *
  page168_i194
#ISCELL
  standard tap *
  page168_i195
#ISCELL
  standard tap *
  page168_i196
#ISCELL
  standard tap *
  page168_i197
#ISCELL
  standard tap *
  page168_i198
#ISCELL
  standard tap *
  page168_i199
#ISCELL
  standard tap *
  page168_i200
#ISCELL
  standard tap *
  page168_i201
#ISCELL
  standard tap *
  page168_i202
#ISCELL
  standard tap *
  page168_i203
#ISCELL
  standard tap *
  page168_i204
#ISCELL
  standard tap *
  page168_i205
#ISCELL
  standard tap *
  page168_i206
#ISCELL
  standard offpage *
  page168_i207
#ISCELL
  standard offpage *
  page168_i208
#ISCELL
  standard offpage *
  page168_i209
#ISCELL
  standard offpage *
  page168_i210
#ISCELL
  standard offpage *
  page168_i211
#ISCELL
  standard offpage *
  page168_i212
#ISCELL
  standard tap *
  page168_i213
#ISCELL
  standard tap *
  page168_i214
#ISCELL
  standard tap *
  page168_i215
#ISCELL
  standard tap *
  page168_i216
#ISCELL
  standard tap *
  page168_i217
#ISCELL
  standard tap *
  page168_i218
#ISCELL
  standard tap *
  page168_i219
#ISCELL
  standard tap *
  page168_i220
#ISCELL
  standard tap *
  page168_i221
#ISCELL
  standard tap *
  page168_i222
#ISCELL
  standard tap *
  page168_i223
#ISCELL
  standard tap *
  page168_i224
#ISCELL
  standard tap *
  page168_i225
#ISCELL
  standard tap *
  page168_i226
#ISCELL
  standard tap *
  page168_i227
#ISCELL
  standard tap *
  page168_i228
#CELL
  pure_quanta q_cap_diffbus *
  page168_i229
#CELL
  pure_quanta q_cap_diffbus *
  page168_i230
#CELL
  pure_quanta q_cap_diffbus *
  page168_i231
#CELL
  pure_quanta q_cap_diffbus *
  page168_i232
#CELL
  pure_quanta q_cap_diffbus *
  page168_i233
#CELL
  pure_quanta q_cap_diffbus *
  page168_i234
#CELL
  pure_quanta q_cap_diffbus *
  page168_i235
#CELL
  pure_quanta q_cap_diffbus *
  page168_i236
#CELL
  pure_quanta q_cap_diffbus *
  page168_i237
#CELL
  pure_quanta q_cap_diffbus *
  page168_i238
#ISCELL
  standard tap *
  page168_i239
#ISCELL
  standard tap *
  page168_i240
#ISCELL
  standard tap *
  page168_i241
#ISCELL
  standard tap *
  page168_i242
#ISCELL
  standard tap *
  page168_i243
#ISCELL
  standard tap *
  page168_i244
#ISCELL
  standard tap *
  page168_i245
#ISCELL
  standard tap *
  page168_i246
#ISCELL
  standard tap *
  page168_i247
#ISCELL
  standard tap *
  page168_i248
#CELL
  pure_quanta q_cap_diffbus *
  page168_i249
#CELL
  pure_quanta q_cap_diffbus *
  page168_i250
#CELL
  pure_quanta q_cap_diffbus *
  page168_i251
#CELL
  pure_quanta q_cap_diffbus *
  page168_i252
#CELL
  pure_quanta q_cap_diffbus *
  page168_i253
#CELL
  pure_quanta q_cap_diffbus *
  page168_i254
#ISCELL
  standard tap *
  page168_i255
#ISCELL
  standard tap *
  page168_i256
#ISCELL
  standard tap *
  page168_i257
#ISCELL
  standard tap *
  page168_i258
#ISCELL
  standard tap *
  page168_i259
#ISCELL
  standard tap *
  page168_i260
#ISCELL
  standard tap *
  page168_i261
#ISCELL
  standard tap *
  page168_i262
#ISCELL
  standard tap *
  page168_i263
#ISCELL
  standard tap *
  page168_i264
#ISCELL
  standard tap *
  page168_i265
#ISCELL
  standard tap *
  page168_i266
#ISCELL
  standard tap *
  page168_i267
#ISCELL
  standard tap *
  page168_i268
#ISCELL
  standard tap *
  page168_i269
#ISCELL
  standard tap *
  page168_i270
#ISCELL
  standard tap *
  page168_i271
#ISCELL
  standard tap *
  page168_i272
#ISCELL
  standard tap *
  page168_i273
#ISCELL
  standard tap *
  page168_i274
#ISCELL
  standard tap *
  page168_i275
#ISCELL
  standard tap *
  page168_i276
#CELL
  pure_quanta q_cap_diffbus *
  page168_i277
#CELL
  pure_quanta q_cap_diffbus *
  page168_i278
#CELL
  pure_quanta q_cap_diffbus *
  page168_i279
#CELL
  pure_quanta q_cap_diffbus *
  page168_i280
#CELL
  pure_quanta q_cap_diffbus *
  page168_i281
#CELL
  pure_quanta q_cap_diffbus *
  page168_i282
#CELL
  pure_quanta q_cap_diffbus *
  page168_i283
#CELL
  pure_quanta q_cap_diffbus *
  page168_i284
#CELL
  pure_quanta q_cap_diffbus *
  page168_i285
#CELL
  pure_quanta q_cap_diffbus *
  page168_i286
#ISCELL
  standard tap *
  page168_i287
#ISCELL
  standard tap *
  page168_i288
#ISCELL
  standard tap *
  page168_i289
#ISCELL
  standard tap *
  page168_i290
#ISCELL
  standard tap *
  page168_i291
#ISCELL
  standard tap *
  page168_i292
#ISCELL
  standard tap *
  page168_i293
#ISCELL
  standard tap *
  page168_i294
#ISCELL
  standard tap *
  page168_i295
#ISCELL
  standard tap *
  page168_i296
#CELL
  pure_quanta q_cap_diffbus *
  page168_i297
#CELL
  pure_quanta q_cap_diffbus *
  page168_i298
#CELL
  pure_quanta q_cap_diffbus *
  page168_i299
#CELL
  pure_quanta q_cap_diffbus *
  page168_i300
#CELL
  pure_quanta q_cap_diffbus *
  page168_i301
#CELL
  pure_quanta q_cap_diffbus *
  page168_i302
#ISCELL
  standard tap *
  page168_i303
#ISCELL
  standard tap *
  page168_i304
#ISCELL
  standard tap *
  page168_i305
#ISCELL
  standard tap *
  page168_i306
#ISCELL
  standard tap *
  page168_i307
#ISCELL
  standard tap *
  page168_i308
#ISCELL
  standard offpage *
  page168_i309
#ISCELL
  standard offpage *
  page168_i310
#ISCELL
  standard offpage *
  page168_i311
#ISCELL
  standard offpage *
  page168_i312
#ISCELL
  pure_quanta quanta_title_block_c *
  *
#ISCELL
  standard offpage *
  page169_i1
#ISCELL
  standard tap *
  page169_i10
#ISCELL
  standard tap *
  page169_i100
#ISCELL
  standard tap *
  page169_i101
#ISCELL
  standard tap *
  page169_i102
#ISCELL
  standard tap *
  page169_i103
#ISCELL
  standard tap *
  page169_i104
#ISCELL
  standard tap *
  page169_i105
#ISCELL
  standard tap *
  page169_i106
#ISCELL
  standard tap *
  page169_i107
#ISCELL
  standard tap *
  page169_i108
#ISCELL
  standard tap *
  page169_i109
#ISCELL
  standard tap *
  page169_i11
#ISCELL
  standard tap *
  page169_i110
#ISCELL
  standard tap *
  page169_i111
#ISCELL
  standard tap *
  page169_i112
#CELL
  pure_quanta q_cap_diffbus *
  page169_i113
#CELL
  pure_quanta q_cap_diffbus *
  page169_i114
#CELL
  pure_quanta q_cap_diffbus *
  page169_i115
#CELL
  pure_quanta q_cap_diffbus *
  page169_i116
#CELL
  pure_quanta q_cap_diffbus *
  page169_i117
#CELL
  pure_quanta q_cap_diffbus *
  page169_i118
#CELL
  pure_quanta q_cap_diffbus *
  page169_i119
#ISCELL
  standard tap *
  page169_i12
#CELL
  pure_quanta q_cap_diffbus *
  page169_i120
#CELL
  pure_quanta q_cap_diffbus *
  page169_i121
#CELL
  pure_quanta q_cap_diffbus *
  page169_i122
#CELL
  pure_quanta q_cap_diffbus *
  page169_i123
#CELL
  pure_quanta q_cap_diffbus *
  page169_i124
#CELL
  pure_quanta q_cap_diffbus *
  page169_i125
#CELL
  pure_quanta q_cap_diffbus *
  page169_i126
#CELL
  pure_quanta q_cap_diffbus *
  page169_i127
#CELL
  pure_quanta q_cap_diffbus *
  page169_i128
#ISCELL
  standard tap *
  page169_i129
#ISCELL
  standard tap *
  page169_i13
#ISCELL
  standard tap *
  page169_i130
#ISCELL
  standard tap *
  page169_i131
#ISCELL
  standard tap *
  page169_i132
#ISCELL
  standard tap *
  page169_i133
#ISCELL
  standard tap *
  page169_i134
#ISCELL
  standard tap *
  page169_i135
#ISCELL
  standard tap *
  page169_i136
#ISCELL
  standard tap *
  page169_i137
#ISCELL
  standard tap *
  page169_i138
#ISCELL
  standard tap *
  page169_i139
#ISCELL
  standard tap *
  page169_i14
#ISCELL
  standard tap *
  page169_i140
#ISCELL
  standard tap *
  page169_i141
#ISCELL
  standard tap *
  page169_i142
#ISCELL
  standard tap *
  page169_i143
#ISCELL
  standard tap *
  page169_i144
#ISCELL
  standard offpage *
  page169_i145
#ISCELL
  standard offpage *
  page169_i146
#ISCELL
  standard tap *
  page169_i15
#ISCELL
  standard tap *
  page169_i16
#ISCELL
  standard tap *
  page169_i17
#ISCELL
  standard tap *
  page169_i18
#ISCELL
  standard tap *
  page169_i19
#ISCELL
  standard offpage *
  page169_i2
#ISCELL
  standard tap *
  page169_i20
#CELL
  pure_quanta q_cap_diffbus *
  page169_i21
#CELL
  pure_quanta q_cap_diffbus *
  page169_i22
#CELL
  pure_quanta q_cap_diffbus *
  page169_i23
#CELL
  pure_quanta q_cap_diffbus *
  page169_i24
#CELL
  pure_quanta q_cap_diffbus *
  page169_i25
#CELL
  pure_quanta q_cap_diffbus *
  page169_i26
#CELL
  pure_quanta q_cap_diffbus *
  page169_i27
#CELL
  pure_quanta q_cap_diffbus *
  page169_i28
#CELL
  pure_quanta q_cap_diffbus *
  page169_i29
#CELL
  pure_quanta q_cap_diffbus *
  page169_i30
#CELL
  pure_quanta q_cap_diffbus *
  page169_i31
#CELL
  pure_quanta q_cap_diffbus *
  page169_i32
#CELL
  pure_quanta q_cap_diffbus *
  page169_i33
#CELL
  pure_quanta q_cap_diffbus *
  page169_i34
#CELL
  pure_quanta q_cap_diffbus *
  page169_i35
#CELL
  pure_quanta q_cap_diffbus *
  page169_i36
#ISCELL
  standard tap *
  page169_i5
#ISCELL
  standard tap *
  page169_i6
#ISCELL
  standard tap *
  page169_i7
#ISCELL
  standard tap *
  page169_i76
#ISCELL
  standard tap *
  page169_i77
#ISCELL
  standard tap *
  page169_i78
#ISCELL
  standard tap *
  page169_i79
#ISCELL
  standard tap *
  page169_i8
#ISCELL
  standard tap *
  page169_i80
#ISCELL
  standard tap *
  page169_i81
#ISCELL
  standard tap *
  page169_i82
#ISCELL
  standard tap *
  page169_i83
#ISCELL
  standard tap *
  page169_i85
#ISCELL
  standard tap *
  page169_i86
#ISCELL
  standard tap *
  page169_i87
#ISCELL
  standard tap *
  page169_i88
#ISCELL
  standard tap *
  page169_i89
#ISCELL
  standard tap *
  page169_i9
#ISCELL
  standard tap *
  page169_i90
#ISCELL
  standard tap *
  page169_i91
#ISCELL
  standard tap *
  page169_i92
#ISCELL
  standard offpage *
  page169_i93
#ISCELL
  standard offpage *
  page169_i94
#ISCELL
  standard tap *
  page169_i95
#ISCELL
  standard tap *
  page169_i96
#ISCELL
  standard offpage *
  page169_i97
#ISCELL
  standard offpage *
  page169_i98
#ISCELL
  standard tap *
  page169_i99
#ISCELL
  logical_power bom_note *
  *
#ISCELL
  logical_power cad_note *
  *
#ISCELL
  mstr_misc dns *
  *
#ISCELL
  pure_quanta quanta_title_block_c *
  *
#ISCELL
  logical_power universal_gnd *
  page171_i1
#CELL
  pure_quanta q_cap *
  page171_i10
#ISCELL
  standard offpage *
  page171_i100
#CELL
  pure_quanta q_res *
  page171_i103
#CELL
  pure_quanta q_res *
  page171_i104
#ISCELL
  standard offpage *
  page171_i107
#ISCELL
  standard offpage *
  page171_i108
#ISCELL
  standard offpage *
  page171_i109
#CELL
  pure_quanta q_crystal *
  page171_i11
#ISCELL
  standard offpage *
  page171_i110
#ISCELL
  standard offpage *
  page171_i111
#ISCELL
  standard offpage *
  page171_i112
#ISCELL
  standard offpage *
  page171_i114
#CELL
  pure_quanta q_res *
  page171_i116
#CELL
  pure_quanta q_res *
  page171_i117
#ISCELL
  standard offpage *
  page171_i118
#ISCELL
  standard offpage *
  page171_i119
#ISCELL
  standard offpage *
  page171_i120
#CELL
  pure_quanta q_res *
  page171_i121
#CELL
  pure_quanta q_res *
  page171_i122
#ISCELL
  standard offpage *
  page171_i14
#ISCELL
  standard offpage *
  page171_i15
#ISCELL
  logical_power universal_gnd *
  page171_i16
#CELL
  pure_quanta q_cap *
  page171_i17
#ISCELL
  standard offpage *
  page171_i18
#ISCELL
  standard offpage *
  page171_i19
#ISCELL
  logical_power universal_gnd *
  page171_i5
#ISCELL
  standard offpage *
  page171_i63
#ISCELL
  standard offpage *
  page171_i64
#ISCELL
  standard offpage *
  page171_i66
#ISCELL
  standard offpage *
  page171_i67
#ISCELL
  standard offpage *
  page171_i68
#CELL
  pure_quanta q_res *
  page171_i69
#ISCELL
  logical_power universal_gnd *
  page171_i7
#CELL
  pure_quanta q_res *
  page171_i74
#CELL
  pure_quanta q_xtal_4p_13bi_24gnd *
  page171_i75
#CELL
  pure_quanta q_cap *
  page171_i76
#CELL
  pure_quanta q_cap *
  page171_i77
#CELL
  pure_quanta emmitsburg_rev0p9 *
  page171_i78
#ISCELL
  standard offpage *
  page171_i83
#ISCELL
  standard offpage *
  page171_i84
#ISCELL
  standard offpage *
  page171_i85
#ISCELL
  standard offpage *
  page171_i86
#ISCELL
  standard offpage *
  page171_i87
#ISCELL
  standard offpage *
  page171_i88
#CELL
  pure_quanta q_cap *
  page171_i89
#ISCELL
  logical_power universal_gnd *
  page171_i9
#ISCELL
  logical_power universal_gnd *
  page171_i90
#ISCELL
  standard offpage *
  page171_i91
#CELL
  pure_quanta q_res *
  page171_i92
#ISCELL
  standard offpage *
  page171_i97
#ISCELL
  standard offpage *
  page171_i98
#ISCELL
  standard offpage *
  page171_i99
#ISCELL
  logical_power cad_note *
  *
#ISCELL
  logical_power design_note *
  *
#ISCELL
  pure_quanta quanta_title_block_c *
  *
#CELL
  pure_quanta q_res *
  page172_i10
#CELL
  pure_quanta emmitsburg_rev0p9 *
  page172_i11
#ISCELL
  standard offpage *
  page172_i12
#ISCELL
  standard offpage *
  page172_i13
#ISCELL
  standard offpage *
  page172_i20
#ISCELL
  standard offpage *
  page172_i21
#ISCELL
  standard offpage *
  page172_i24
#ISCELL
  standard offpage *
  page172_i25
#ISCELL
  standard offpage *
  page172_i32
#ISCELL
  standard offpage *
  page172_i33
#ISCELL
  standard offpage *
  page172_i34
#ISCELL
  standard offpage *
  page172_i35
#ISCELL
  logical_power universal_gnd *
  page172_i9
#ISCELL
  logical_power cad_note *
  *
#ISCELL
  pure_quanta quanta_title_block_c *
  *
#CELL
  pure_quanta q_res *
  page173_i1
#ISCELL
  standard offpage *
  page173_i10
#ISCELL
  standard offpage *
  page173_i100
#ISCELL
  standard offpage *
  page173_i101
#ISCELL
  standard offpage *
  page173_i102
#ISCELL
  standard offpage *
  page173_i103
#ISCELL
  standard offpage *
  page173_i104
#ISCELL
  standard offpage *
  page173_i105
#ISCELL
  standard offpage *
  page173_i106
#ISCELL
  standard offpage *
  page173_i107
#ISCELL
  standard offpage *
  page173_i108
#ISCELL
  standard offpage *
  page173_i109
#ISCELL
  standard offpage *
  page173_i11
#CELL
  pure_quanta emmitsburg_rev0p9 *
  page173_i110
#ISCELL
  standard offpage *
  page173_i12
#ISCELL
  standard offpage *
  page173_i13
#ISCELL
  standard offpage *
  page173_i14
#ISCELL
  standard offpage *
  page173_i15
#ISCELL
  standard offpage *
  page173_i16
#ISCELL
  standard offpage *
  page173_i17
#ISCELL
  standard offpage *
  page173_i18
#ISCELL
  standard offpage *
  page173_i19
#ISCELL
  standard offpage *
  page173_i2
#ISCELL
  standard offpage *
  page173_i20
#ISCELL
  standard offpage *
  page173_i21
#ISCELL
  standard offpage *
  page173_i22
#ISCELL
  standard offpage *
  page173_i23
#ISCELL
  standard offpage *
  page173_i24
#ISCELL
  standard offpage *
  page173_i25
#ISCELL
  standard tap *
  page173_i26
#ISCELL
  standard tap *
  page173_i27
#ISCELL
  standard tap *
  page173_i28
#ISCELL
  standard offpage *
  page173_i29
#ISCELL
  standard offpage *
  page173_i3
#ISCELL
  standard offpage *
  page173_i30
#ISCELL
  standard tap *
  page173_i31
#ISCELL
  standard tap *
  page173_i32
#ISCELL
  standard tap *
  page173_i33
#ISCELL
  standard tap *
  page173_i34
#ISCELL
  standard tap *
  page173_i35
#ISCELL
  standard tap *
  page173_i36
#ISCELL
  standard tap *
  page173_i37
#ISCELL
  standard tap *
  page173_i38
#ISCELL
  standard tap *
  page173_i39
#ISCELL
  standard offpage *
  page173_i4
#ISCELL
  standard tap *
  page173_i40
#ISCELL
  standard tap *
  page173_i41
#ISCELL
  standard tap *
  page173_i42
#ISCELL
  standard tap *
  page173_i43
#ISCELL
  standard tap *
  page173_i44
#ISCELL
  standard tap *
  page173_i45
#ISCELL
  standard tap *
  page173_i46
#ISCELL
  standard tap *
  page173_i47
#ISCELL
  standard tap *
  page173_i48
#ISCELL
  standard tap *
  page173_i49
#ISCELL
  standard offpage *
  page173_i5
#ISCELL
  standard tap *
  page173_i50
#ISCELL
  standard tap *
  page173_i51
#ISCELL
  standard tap *
  page173_i52
#ISCELL
  standard tap *
  page173_i53
#ISCELL
  standard tap *
  page173_i54
#ISCELL
  standard tap *
  page173_i55
#ISCELL
  standard tap *
  page173_i56
#ISCELL
  standard tap *
  page173_i57
#ISCELL
  standard tap *
  page173_i58
#ISCELL
  standard tap *
  page173_i59
#ISCELL
  standard offpage *
  page173_i6
#CELL
  pure_quanta q_cap_diffbus *
  page173_i60
#CELL
  pure_quanta q_cap_diffbus *
  page173_i61
#CELL
  pure_quanta q_cap_diffbus *
  page173_i62
#CELL
  pure_quanta q_cap_diffbus *
  page173_i63
#CELL
  pure_quanta q_cap_diffbus *
  page173_i64
#CELL
  pure_quanta q_cap_diffbus *
  page173_i65
#CELL
  pure_quanta q_cap_diffbus *
  page173_i66
#CELL
  pure_quanta q_cap_diffbus *
  page173_i67
#CELL
  pure_quanta q_cap_diffbus *
  page173_i68
#CELL
  pure_quanta q_cap_diffbus *
  page173_i69
#ISCELL
  standard offpage *
  page173_i7
#CELL
  pure_quanta q_cap_diffbus *
  page173_i70
#CELL
  pure_quanta q_cap_diffbus *
  page173_i71
#CELL
  pure_quanta q_cap_diffbus *
  page173_i72
#CELL
  pure_quanta q_cap_diffbus *
  page173_i73
#CELL
  pure_quanta q_cap_diffbus *
  page173_i74
#CELL
  pure_quanta q_cap_diffbus *
  page173_i75
#CELL
  pure_quanta q_cap_diffbus *
  page173_i76
#CELL
  pure_quanta q_cap_diffbus *
  page173_i77
#CELL
  pure_quanta q_cap *
  page173_i78
#CELL
  pure_quanta q_cap_diffbus *
  page173_i79
#ISCELL
  standard offpage *
  page173_i8
#CELL
  pure_quanta q_cap *
  page173_i80
#CELL
  pure_quanta q_cap_diffbus *
  page173_i81
#CELL
  pure_quanta q_cap_diffbus *
  page173_i82
#CELL
  pure_quanta q_cap_diffbus *
  page173_i83
#ISCELL
  standard offpage *
  page173_i84
#ISCELL
  standard offpage *
  page173_i85
#ISCELL
  standard offpage *
  page173_i86
#ISCELL
  standard offpage *
  page173_i87
#ISCELL
  standard offpage *
  page173_i88
#ISCELL
  standard offpage *
  page173_i89
#ISCELL
  standard offpage *
  page173_i9
#ISCELL
  standard offpage *
  page173_i90
#ISCELL
  standard offpage *
  page173_i91
#ISCELL
  standard offpage *
  page173_i92
#ISCELL
  standard offpage *
  page173_i93
#ISCELL
  standard offpage *
  page173_i94
#ISCELL
  standard offpage *
  page173_i95
#ISCELL
  standard offpage *
  page173_i96
#ISCELL
  standard offpage *
  page173_i97
#ISCELL
  standard offpage *
  page173_i98
#ISCELL
  standard offpage *
  page173_i99
#ISCELL
  mstr_misc dns *
  *
#ISCELL
  pure_quanta quanta_title_block_c *
  *
#ISCELL
  standard offpage *
  page174_i10
#ISCELL
  standard offpage *
  page174_i11
#ISCELL
  standard offpage *
  page174_i12
#ISCELL
  standard offpage *
  page174_i17
#ISCELL
  standard offpage *
  page174_i19
#ISCELL
  standard offpage *
  page174_i20
#ISCELL
  standard offpage *
  page174_i21
#ISCELL
  standard offpage *
  page174_i22
#ISCELL
  standard offpage *
  page174_i23
#ISCELL
  standard offpage *
  page174_i24
#ISCELL
  standard offpage *
  page174_i25
#ISCELL
  standard offpage *
  page174_i26
#ISCELL
  standard offpage *
  page174_i27
#ISCELL
  standard offpage *
  page174_i28
#ISCELL
  standard offpage *
  page174_i29
#ISCELL
  standard offpage *
  page174_i3
#ISCELL
  standard offpage *
  page174_i31
#ISCELL
  standard offpage *
  page174_i32
#ISCELL
  standard offpage *
  page174_i33
#ISCELL
  standard offpage *
  page174_i34
#ISCELL
  standard offpage *
  page174_i35
#CELL
  pure_quanta emmitsburg_rev0p9 *
  page174_i36
#CELL
  pure_quanta q_res *
  page174_i37
#CELL
  pure_quanta q_res *
  page174_i38
#ISCELL
  logical_power universal_power *
  page174_i39
#ISCELL
  logical_power universal_gnd *
  page174_i40
#CELL
  pure_quanta q_res *
  page174_i41
#ISCELL
  logical_power universal_gnd *
  page174_i42
#CELL
  pure_quanta q_res *
  page174_i48
#ISCELL
  logical_power universal_power *
  page174_i49
#ISCELL
  logical_power universal_power *
  page174_i5
#CELL
  pure_quanta q_res *
  page174_i50
#ISCELL
  logical_power universal_gnd *
  page174_i51
#ISCELL
  standard offpage *
  page174_i53
#ISCELL
  standard offpage *
  page174_i54
#ISCELL
  standard offpage *
  page174_i55
#ISCELL
  standard offpage *
  page174_i56
#ISCELL
  standard offpage *
  page174_i57
#CELL
  pure_quanta q_res *
  page174_i58
#ISCELL
  standard offpage *
  page174_i59
#CELL
  pure_quanta q_res *
  page174_i60
#ISCELL
  standard offpage *
  page174_i61
#ISCELL
  standard offpage *
  page174_i62
#CELL
  pure_quanta q_res *
  page174_i63
#ISCELL
  standard offpage *
  page174_i64
#ISCELL
  standard offpage *
  page174_i65
#CELL
  pure_quanta q_res *
  page174_i66
#ISCELL
  standard offpage *
  page174_i73
#CELL
  pure_quanta q_res *
  page174_i74
#CELL
  pure_quanta q_res *
  page174_i75
#ISCELL
  logical_power universal_power *
  page174_i76
#CELL
  pure_quanta q_res *
  page174_i77
#ISCELL
  logical_power universal_power *
  page174_i78
#ISCELL
  standard offpage *
  page174_i8
#ISCELL
  logical_power universal_power *
  page174_i80
#ISCELL
  standard offpage *
  page174_i81
#CELL
  pure_quanta q_res *
  page174_i82
#ISCELL
  standard offpage *
  page174_i9
#ISCELL
  standard offpage *
  page174_i90
#ISCELL
  standard offpage *
  page174_i91
#ISCELL
  standard offpage *
  page174_i92
#ISCELL
  standard offpage *
  page174_i93
#CELL
  pure_quanta q_res *
  page174_i94
#ISCELL
  logical_power universal_gnd *
  page174_i95
#CELL
  pure_quanta q_res *
  page174_i96
#ISCELL
  logical_power universal_power *
  page174_i97
#CELL
  pure_quanta q_res *
  page174_i98
#CELL
  pure_quanta q_res *
  page174_i99
#ISCELL
  logical_power design_note *
  *
#ISCELL
  mstr_misc dns *
  *
#ISCELL
  pure_quanta quanta_title_block_c *
  *
#ISCELL
  standard offpage *
  page175_i101
#CELL
  pure_quanta q_res *
  page175_i102
#CELL
  pure_quanta q_res *
  page175_i109
#ISCELL
  standard offpage *
  page175_i110
#ISCELL
  logical_power universal_power *
  page175_i111
#CELL
  pure_quanta q_res *
  page175_i112
#ISCELL
  standard offpage *
  page175_i113
#ISCELL
  standard offpage *
  page175_i118
#ISCELL
  standard offpage *
  page175_i119
#CELL
  pure_quanta q_res *
  page175_i120
#CELL
  pure_quanta q_res *
  page175_i121
#CELL
  pure_quanta q_res *
  page175_i125
#ISCELL
  logical_power universal_gnd *
  page175_i126
#ISCELL
  standard offpage *
  page175_i131
#ISCELL
  standard offpage *
  page175_i132
#ISCELL
  standard offpage *
  page175_i134
#ISCELL
  standard offpage *
  page175_i135
#ISCELL
  standard offpage *
  page175_i136
#CELL
  pure_quanta q_res *
  page175_i137
#CELL
  pure_quanta q_res *
  page175_i138
#ISCELL
  standard offpage *
  page175_i139
#ISCELL
  standard offpage *
  page175_i140
#CELL
  pure_quanta q_res *
  page175_i141
#CELL
  pure_quanta q_res *
  page175_i142
#ISCELL
  standard offpage *
  page175_i143
#CELL
  pure_quanta q_res *
  page175_i144
#ISCELL
  standard offpage *
  page175_i145
#ISCELL
  standard offpage *
  page175_i147
#CELL
  pure_quanta q_res *
  page175_i148
#ISCELL
  standard offpage *
  page175_i15
#ISCELL
  standard offpage *
  page175_i150
#CELL
  pure_quanta q_res *
  page175_i151
#ISCELL
  standard offpage *
  page175_i16
#ISCELL
  standard offpage *
  page175_i17
#ISCELL
  standard offpage *
  page175_i175
#ISCELL
  standard offpage *
  page175_i177
#CELL
  pure_quanta q_res *
  page175_i178
#ISCELL
  standard offpage *
  page175_i18
#CELL
  pure_quanta q_res *
  page175_i180
#CELL
  pure_quanta q_res *
  page175_i181
#ISCELL
  standard offpage *
  page175_i182
#ISCELL
  standard offpage *
  page175_i183
#CELL
  pure_quanta q_res *
  page175_i188
#ISCELL
  standard offpage *
  page175_i189
#ISCELL
  standard offpage *
  page175_i19
#CELL
  pure_quanta q_res *
  page175_i193
#ISCELL
  standard offpage *
  page175_i194
#ISCELL
  standard offpage *
  page175_i195
#ISCELL
  standard offpage *
  page175_i20
#ISCELL
  standard offpage *
  page175_i209
#ISCELL
  standard offpage *
  page175_i21
#ISCELL
  standard offpage *
  page175_i210
#ISCELL
  standard offpage *
  page175_i212
#CELL
  pure_quanta q_res *
  page175_i213
#ISCELL
  standard offpage *
  page175_i22
#CELL
  pure_quanta q_res *
  page175_i222
#ISCELL
  standard offpage *
  page175_i223
#ISCELL
  logical_power universal_gnd *
  page175_i224
#CELL
  pure_quanta q_res *
  page175_i225
#ISCELL
  standard offpage *
  page175_i227
#ISCELL
  standard offpage *
  page175_i228
#ISCELL
  standard offpage *
  page175_i229
#ISCELL
  standard offpage *
  page175_i23
#ISCELL
  standard offpage *
  page175_i230
#CELL
  pure_quanta q_res *
  page175_i234
#ISCELL
  standard offpage *
  page175_i235
#CELL
  pure_quanta q_res *
  page175_i236
#ISCELL
  standard offpage *
  page175_i237
#ISCELL
  standard offpage *
  page175_i238
#CELL
  pure_quanta q_res *
  page175_i239
#ISCELL
  standard offpage *
  page175_i24
#ISCELL
  standard offpage *
  page175_i240
#CELL
  pure_quanta q_res *
  page175_i241
#ISCELL
  standard offpage *
  page175_i246
#ISCELL
  standard offpage *
  page175_i247
#ISCELL
  standard offpage *
  page175_i248
#ISCELL
  standard offpage *
  page175_i249
#ISCELL
  standard offpage *
  page175_i25
#ISCELL
  standard offpage *
  page175_i250
#ISCELL
  standard offpage *
  page175_i252
#CELL
  pure_quanta q_res *
  page175_i253
#CELL
  pure_quanta conn3_210hp1030br1 *
  page175_i256
#ISCELL
  logical_power universal_gnd *
  page175_i257
#ISCELL
  standard offpage *
  page175_i258
#ISCELL
  standard offpage *
  page175_i259
#ISCELL
  standard offpage *
  page175_i26
#ISCELL
  logical_power universal_gnd *
  page175_i260
#ISCELL
  standard offpage *
  page175_i261
#ISCELL
  standard offpage *
  page175_i262
#CELL
  pure_quanta conn3_210hp1030br1 *
  page175_i263
#ISCELL
  standard offpage *
  page175_i268
#ISCELL
  standard offpage *
  page175_i269
#ISCELL
  standard offpage *
  page175_i27
#ISCELL
  standard offpage *
  page175_i271
#CELL
  pure_quanta q_res *
  page175_i272
#ISCELL
  standard offpage *
  page175_i273
#CELL
  pure_quanta q_res *
  page175_i274
#CELL
  pure_quanta q_res *
  page175_i275
#ISCELL
  standard offpage *
  page175_i276
#ISCELL
  standard offpage *
  page175_i277
#ISCELL
  standard offpage *
  page175_i278
#ISCELL
  standard offpage *
  page175_i279
#ISCELL
  standard offpage *
  page175_i28
#ISCELL
  standard offpage *
  page175_i280
#ISCELL
  standard offpage *
  page175_i281
#ISCELL
  standard offpage *
  page175_i282
#CELL
  pure_quanta q_res *
  page175_i284
#CELL
  pure_quanta q_res *
  page175_i285
#CELL
  pure_quanta q_res *
  page175_i286
#CELL
  pure_quanta q_res *
  page175_i287
#CELL
  pure_quanta q_res *
  page175_i288
#ISCELL
  logical_power universal_gnd *
  page175_i289
#ISCELL
  standard offpage *
  page175_i29
#ISCELL
  standard offpage *
  page175_i290
#ISCELL
  standard offpage *
  page175_i291
#ISCELL
  standard offpage *
  page175_i292
#ISCELL
  standard offpage *
  page175_i293
#ISCELL
  standard offpage *
  page175_i294
#ISCELL
  standard offpage *
  page175_i295
#ISCELL
  standard offpage *
  page175_i296
#ISCELL
  standard offpage *
  page175_i297
#CELL
  pure_quanta q_res *
  page175_i298
#CELL
  pure_quanta q_res *
  page175_i299
#ISCELL
  standard offpage *
  page175_i30
#CELL
  pure_quanta q_res *
  page175_i300
#ISCELL
  standard offpage *
  page175_i302
#ISCELL
  standard offpage *
  page175_i303
#ISCELL
  standard offpage *
  page175_i304
#CELL
  pure_quanta q_res *
  page175_i305
#ISCELL
  standard offpage *
  page175_i306
#ISCELL
  standard offpage *
  page175_i307
#CELL
  pure_quanta q_res *
  page175_i308
#ISCELL
  standard offpage *
  page175_i309
#ISCELL
  standard offpage *
  page175_i31
#ISCELL
  standard offpage *
  page175_i310
#ISCELL
  standard offpage *
  page175_i311
#ISCELL
  standard offpage *
  page175_i312
#CELL
  pure_quanta q_res *
  page175_i314
#CELL
  pure_quanta q_res *
  page175_i315
#ISCELL
  standard offpage *
  page175_i317
#ISCELL
  standard offpage *
  page175_i32
#ISCELL
  standard offpage *
  page175_i33
#ISCELL
  standard offpage *
  page175_i36
#ISCELL
  standard offpage *
  page175_i37
#ISCELL
  standard offpage *
  page175_i38
#ISCELL
  standard offpage *
  page175_i39
#ISCELL
  standard offpage *
  page175_i40
#ISCELL
  standard offpage *
  page175_i41
#ISCELL
  standard offpage *
  page175_i42
#ISCELL
  standard offpage *
  page175_i43
#ISCELL
  standard offpage *
  page175_i44
#ISCELL
  standard offpage *
  page175_i45
#ISCELL
  standard offpage *
  page175_i46
#ISCELL
  standard offpage *
  page175_i49
#ISCELL
  standard offpage *
  page175_i50
#ISCELL
  standard offpage *
  page175_i51
#ISCELL
  standard offpage *
  page175_i53
#ISCELL
  standard offpage *
  page175_i56
#ISCELL
  standard offpage *
  page175_i57
#ISCELL
  standard offpage *
  page175_i58
#ISCELL
  standard offpage *
  page175_i60
#ISCELL
  standard offpage *
  page175_i62
#ISCELL
  standard offpage *
  page175_i67
#ISCELL
  standard offpage *
  page175_i68
#ISCELL
  standard offpage *
  page175_i70
#ISCELL
  standard offpage *
  page175_i71
#ISCELL
  standard offpage *
  page175_i72
#ISCELL
  standard offpage *
  page175_i73
#ISCELL
  standard offpage *
  page175_i74
#ISCELL
  standard offpage *
  page175_i75
#ISCELL
  standard offpage *
  page175_i76
#ISCELL
  standard offpage *
  page175_i77
#ISCELL
  standard offpage *
  page175_i78
#ISCELL
  standard offpage *
  page175_i79
#ISCELL
  standard offpage *
  page175_i80
#ISCELL
  standard offpage *
  page175_i81
#ISCELL
  standard offpage *
  page175_i83
#ISCELL
  standard offpage *
  page175_i85
#ISCELL
  standard offpage *
  page175_i86
#ISCELL
  standard offpage *
  page175_i87
#ISCELL
  standard offpage *
  page175_i88
#ISCELL
  standard offpage *
  page175_i89
#ISCELL
  standard offpage *
  page175_i90
#ISCELL
  standard offpage *
  page175_i91
#ISCELL
  standard offpage *
  page175_i92
#CELL
  pure_quanta emmitsburg_rev0p9 *
  page175_i93
#ISCELL
  standard offpage *
  page175_i99
#ISCELL
  logical_power design_note *
  *
#ISCELL
  mstr_misc dns *
  *
#ISCELL
  pure_quanta quanta_title_block_c *
  *
#ISCELL
  standard offpage *
  page176_i10
#ISCELL
  standard offpage *
  page176_i11
#ISCELL
  standard offpage *
  page176_i118
#ISCELL
  standard offpage *
  page176_i119
#ISCELL
  standard offpage *
  page176_i155
#ISCELL
  standard offpage *
  page176_i156
#ISCELL
  standard offpage *
  page176_i157
#ISCELL
  standard offpage *
  page176_i16
#ISCELL
  logical_power universal_gnd *
  page176_i161
#ISCELL
  logical_power universal_gnd *
  page176_i163
#ISCELL
  logical_power universal_power *
  page176_i168
#ISCELL
  standard offpage *
  page176_i17
#ISCELL
  standard offpage *
  page176_i171
#ISCELL
  standard offpage *
  page176_i172
#CELL
  pure_quanta q_res *
  page176_i173
#CELL
  pure_quanta q_res *
  page176_i174
#CELL
  pure_quanta q_res *
  page176_i175
#CELL
  pure_quanta q_res *
  page176_i176
#ISCELL
  standard offpage *
  page176_i177
#ISCELL
  standard offpage *
  page176_i179
#ISCELL
  standard offpage *
  page176_i180
#ISCELL
  standard offpage *
  page176_i181
#CELL
  pure_quanta q_res *
  page176_i183
#CELL
  pure_quanta q_res *
  page176_i184
#CELL
  pure_quanta q_res *
  page176_i185
#CELL
  pure_quanta q_res *
  page176_i186
#ISCELL
  standard offpage *
  page176_i188
#ISCELL
  standard offpage *
  page176_i189
#ISCELL
  standard offpage *
  page176_i190
#ISCELL
  standard offpage *
  page176_i191
#CELL
  pure_quanta q_res *
  page176_i195
#CELL
  pure_quanta q_res *
  page176_i196
#CELL
  pure_quanta q_res *
  page176_i197
#ISCELL
  standard offpage *
  page176_i198
#ISCELL
  standard offpage *
  page176_i199
#ISCELL
  standard offpage *
  page176_i2
#ISCELL
  standard offpage *
  page176_i20
#ISCELL
  standard offpage *
  page176_i200
#CELL
  pure_quanta q_res *
  page176_i201
#CELL
  pure_quanta q_res *
  page176_i202
#CELL
  pure_quanta q_res *
  page176_i203
#CELL
  pure_quanta q_res *
  page176_i204
#CELL
  pure_quanta q_res *
  page176_i205
#CELL
  pure_quanta q_res *
  page176_i206
#CELL
  pure_quanta q_res *
  page176_i207
#ISCELL
  logical_power universal_gnd *
  page176_i208
#CELL
  pure_quanta q_res *
  page176_i209
#ISCELL
  standard offpage *
  page176_i21
#ISCELL
  standard offpage *
  page176_i210
#ISCELL
  standard offpage *
  page176_i211
#ISCELL
  standard offpage *
  page176_i212
#ISCELL
  standard offpage *
  page176_i213
#ISCELL
  standard offpage *
  page176_i214
#ISCELL
  standard offpage *
  page176_i215
#ISCELL
  standard offpage *
  page176_i216
#ISCELL
  standard offpage *
  page176_i217
#CELL
  pure_quanta emmitsburg_rev0p9 *
  page176_i22
#ISCELL
  standard offpage *
  page176_i225
#ISCELL
  standard offpage *
  page176_i226
#ISCELL
  standard offpage *
  page176_i227
#ISCELL
  standard offpage *
  page176_i228
#ISCELL
  standard offpage *
  page176_i229
#ISCELL
  standard offpage *
  page176_i23
#ISCELL
  standard offpage *
  page176_i230
#ISCELL
  standard offpage *
  page176_i231
#ISCELL
  standard offpage *
  page176_i232
#ISCELL
  standard offpage *
  page176_i233
#ISCELL
  standard offpage *
  page176_i234
#ISCELL
  standard offpage *
  page176_i235
#ISCELL
  standard offpage *
  page176_i237
#ISCELL
  standard offpage *
  page176_i238
#CELL
  pure_quanta q_res *
  page176_i239
#ISCELL
  standard offpage *
  page176_i24
#CELL
  pure_quanta q_res *
  page176_i240
#ISCELL
  standard offpage *
  page176_i243
#ISCELL
  standard offpage *
  page176_i244
#ISCELL
  standard offpage *
  page176_i245
#CELL
  pure_quanta q_res *
  page176_i246
#ISCELL
  logical_power universal_power *
  page176_i247
#ISCELL
  standard offpage *
  page176_i248
#ISCELL
  standard offpage *
  page176_i25
#ISCELL
  standard offpage *
  page176_i26
#ISCELL
  standard offpage *
  page176_i31
#ISCELL
  standard offpage *
  page176_i32
#ISCELL
  standard offpage *
  page176_i34
#ISCELL
  standard offpage *
  page176_i39
#ISCELL
  standard offpage *
  page176_i40
#ISCELL
  standard offpage *
  page176_i41
#ISCELL
  standard offpage *
  page176_i42
#ISCELL
  standard offpage *
  page176_i43
#ISCELL
  standard offpage *
  page176_i44
#ISCELL
  standard offpage *
  page176_i46
#ISCELL
  standard offpage *
  page176_i47
#ISCELL
  standard offpage *
  page176_i48
#ISCELL
  standard offpage *
  page176_i53
#ISCELL
  standard offpage *
  page176_i75
#ISCELL
  standard offpage *
  page176_i76
#ISCELL
  standard offpage *
  page176_i94
#ISCELL
  standard offpage *
  page176_i95
#ISCELL
  mstr_misc dns *
  *
#ISCELL
  pure_quanta quanta_title_block_c *
  *
#CELL
  pure_quanta q_res *
  page177_i100
#CELL
  pure_quanta q_res *
  page177_i102
#CELL
  pure_quanta q_res *
  page177_i106
#ISCELL
  standard offpage *
  page177_i108
#ISCELL
  standard offpage *
  page177_i110
#ISCELL
  standard offpage *
  page177_i111
#ISCELL
  standard offpage *
  page177_i112
#ISCELL
  standard offpage *
  page177_i113
#ISCELL
  standard offpage *
  page177_i114
#ISCELL
  standard offpage *
  page177_i115
#ISCELL
  logical_power universal_power *
  page177_i116
#ISCELL
  standard offpage *
  page177_i117
#CELL
  pure_quanta q_res *
  page177_i118
#CELL
  pure_quanta q_res *
  page177_i119
#ISCELL
  standard offpage *
  page177_i12
#CELL
  pure_quanta q_res *
  page177_i120
#CELL
  pure_quanta q_res *
  page177_i121
#ISCELL
  standard offpage *
  page177_i122
#CELL
  pure_quanta mosfet_nch_gds_esd_protected *
  page177_i123
#CELL
  pure_quanta mosfet_nch_gds_esd_protected *
  page177_i124
#CELL
  pure_quanta q_res *
  page177_i125
#ISCELL
  logical_power universal_gnd *
  page177_i126
#CELL
  pure_quanta q_res *
  page177_i127
#ISCELL
  logical_power universal_gnd *
  page177_i128
#ISCELL
  standard offpage *
  page177_i13
#ISCELL
  standard offpage *
  page177_i15
#ISCELL
  standard offpage *
  page177_i16
#ISCELL
  standard offpage *
  page177_i18
#ISCELL
  standard offpage *
  page177_i19
#ISCELL
  standard offpage *
  page177_i2
#ISCELL
  standard offpage *
  page177_i21
#ISCELL
  standard offpage *
  page177_i22
#ISCELL
  standard offpage *
  page177_i23
#CELL
  pure_quanta q_res *
  page177_i24
#ISCELL
  logical_power universal_power *
  page177_i25
#CELL
  pure_quanta emmitsburg_rev0p9 *
  page177_i27
#ISCELL
  standard offpage *
  page177_i3
#ISCELL
  standard offpage *
  page177_i33
#ISCELL
  standard offpage *
  page177_i34
#ISCELL
  standard offpage *
  page177_i35
#ISCELL
  standard offpage *
  page177_i39
#ISCELL
  logical_power universal_power *
  page177_i53
#ISCELL
  logical_power universal_power *
  page177_i56
#ISCELL
  standard offpage *
  page177_i57
#ISCELL
  logical_power universal_power *
  page177_i59
#CELL
  pure_quanta q_res *
  page177_i62
#CELL
  pure_quanta conn2_aaabat029y19 *
  page177_i63
#CELL
  pure_quanta bas70057f *
  page177_i64
#CELL
  pure_quanta q_cap *
  page177_i65
#ISCELL
  logical_power universal_gnd *
  page177_i66
#ISCELL
  logical_power universal_gnd *
  page177_i67
#CELL
  pure_quanta q_cap *
  page177_i68
#ISCELL
  logical_power universal_gnd *
  page177_i69
#CELL
  pure_quanta q_res *
  page177_i70
#ISCELL
  standard offpage *
  page177_i71
#ISCELL
  standard offpage *
  page177_i73
#ISCELL
  standard offpage *
  page177_i74
#ISCELL
  standard offpage *
  page177_i75
#ISCELL
  standard offpage *
  page177_i76
#ISCELL
  standard offpage *
  page177_i78
#ISCELL
  standard offpage *
  page177_i79
#CELL
  pure_quanta q_res *
  page177_i80
#ISCELL
  standard offpage *
  page177_i82
#ISCELL
  logical_power universal_gnd *
  page177_i83
#ISCELL
  standard offpage *
  page177_i84
#CELL
  pure_quanta q_res *
  page177_i85
#ISCELL
  standard offpage *
  page177_i87
#ISCELL
  logical_power universal_gnd *
  page177_i88
#CELL
  pure_quanta q_res *
  page177_i89
#ISCELL
  standard offpage *
  page177_i90
#ISCELL
  standard offpage *
  page177_i92
#ISCELL
  standard offpage *
  page177_i93
#ISCELL
  standard offpage *
  page177_i95
#ISCELL
  standard offpage *
  page177_i96
#ISCELL
  standard offpage *
  page177_i97
#ISCELL
  standard offpage *
  page177_i98
#ISCELL
  standard offpage *
  page177_i99
#ISCELL
  pure_quanta quanta_title_block_c *
  *
#ISCELL
  logical_power universal_power *
  page178_i10
#CELL
  pure_quanta emmitsburg_rev0p9 *
  page178_i11
#ISCELL
  logical_power universal_power *
  page178_i17
#ISCELL
  logical_power universal_gnd *
  page178_i18
#ISCELL
  logical_power universal_power *
  page178_i2
#ISCELL
  logical_power universal_power *
  page178_i5
#ISCELL
  logical_power universal_power *
  page178_i6
#ISCELL
  logical_power universal_power *
  page178_i7
#ISCELL
  logical_power universal_power *
  page178_i8
#ISCELL
  logical_power universal_power *
  page178_i9
#ISCELL
  pure_quanta quanta_title_block_c *
  *
#CELL
  pure_quanta q_res *
  page179_i2
#ISCELL
  logical_power universal_gnd *
  page179_i3
#CELL
  pure_quanta emmitsburg_rev0p9 *
  page179_i4
#ISCELL
  pure_quanta quanta_title_block_c *
  *
#ISCELL
  logical_power universal_gnd *
  page180_i10
#ISCELL
  logical_power universal_gnd *
  page180_i2
#ISCELL
  logical_power universal_gnd *
  page180_i5
#CELL
  pure_quanta emmitsburg_rev0p9 *
  page180_i7
#ISCELL
  logical_power universal_gnd *
  page180_i8
#CELL
  pure_quanta emmitsburg_rev0p9 *
  page180_i9
#ISCELL
  mstr_misc dns *
  *
#ISCELL
  pure_quanta quanta_title_block_c *
  *
#ISCELL
  logical_power universal_power *
  page181_i103
#CELL
  pure_quanta q_cap *
  page181_i104
#ISCELL
  logical_power universal_gnd *
  page181_i106
#ISCELL
  logical_power universal_power *
  page181_i108
#ISCELL
  logical_power universal_power *
  page181_i11
#CELL
  pure_quanta q_cap *
  page181_i110
#CELL
  pure_quanta q_cap *
  page181_i111
#ISCELL
  logical_power universal_gnd *
  page181_i113
#ISCELL
  logical_power universal_gnd *
  page181_i114
#ISCELL
  logical_power universal_power *
  page181_i115
#ISCELL
  logical_power universal_gnd *
  page181_i117
#ISCELL
  logical_power universal_power *
  page181_i118
#CELL
  pure_quanta q_cap *
  page181_i119
#CELL
  pure_quanta q_cap *
  page181_i12
#ISCELL
  logical_power universal_gnd *
  page181_i122
#CELL
  pure_quanta q_cap *
  page181_i123
#ISCELL
  logical_power universal_power *
  page181_i124
#CELL
  pure_quanta q_cap *
  page181_i125
#ISCELL
  logical_power universal_gnd *
  page181_i126
#CELL
  pure_quanta q_cap *
  page181_i127
#ISCELL
  logical_power universal_power *
  page181_i128
#CELL
  pure_quanta q_res *
  page181_i129
#CELL
  pure_quanta q_cap *
  page181_i13
#ISCELL
  logical_power universal_power *
  page181_i130
#CELL
  pure_quanta q_cap *
  page181_i131
#ISCELL
  logical_power universal_gnd *
  page181_i132
#CELL
  pure_quanta q_cap *
  page181_i133
#ISCELL
  logical_power universal_gnd *
  page181_i134
#CELL
  pure_quanta q_cap *
  page181_i136
#CELL
  pure_quanta q_cap *
  page181_i137
#ISCELL
  logical_power universal_power *
  page181_i138
#ISCELL
  logical_power universal_power *
  page181_i139
#ISCELL
  logical_power universal_gnd *
  page181_i14
#CELL
  pure_quanta q_cap *
  page181_i140
#ISCELL
  logical_power universal_gnd *
  page181_i141
#CELL
  pure_quanta q_cap *
  page181_i142
#ISCELL
  logical_power universal_gnd *
  page181_i143
#CELL
  pure_quanta q_res *
  page181_i144
#CELL
  pure_quanta q_inductor *
  page181_i145
#CELL
  pure_quanta q_cap *
  page181_i146
#CELL
  pure_quanta q_cap *
  page181_i147
#ISCELL
  logical_power universal_power *
  page181_i148
#ISCELL
  logical_power universal_power *
  page181_i149
#ISCELL
  logical_power universal_power *
  page181_i150
#CELL
  pure_quanta q_cap *
  page181_i151
#CELL
  pure_quanta q_cap *
  page181_i152
#CELL
  pure_quanta q_cap *
  page181_i153
#CELL
  pure_quanta q_cap *
  page181_i154
#CELL
  pure_quanta q_cap *
  page181_i155
#CELL
  pure_quanta q_cap *
  page181_i156
#CELL
  pure_quanta q_cap *
  page181_i157
#CELL
  pure_quanta q_cap *
  page181_i158
#CELL
  pure_quanta q_cap *
  page181_i159
#CELL
  pure_quanta q_cap *
  page181_i162
#CELL
  pure_quanta q_cap *
  page181_i163
#CELL
  pure_quanta q_inductor *
  page181_i164
#CELL
  pure_quanta q_res *
  page181_i165
#ISCELL
  logical_power universal_gnd *
  page181_i18
#ISCELL
  logical_power universal_power *
  page181_i20
#CELL
  pure_quanta q_cap *
  page181_i25
#ISCELL
  logical_power universal_power *
  page181_i26
#CELL
  pure_quanta q_cap *
  page181_i27
#ISCELL
  logical_power universal_gnd *
  page181_i28
#CELL
  pure_quanta q_cap *
  page181_i29
#CELL
  pure_quanta q_cap *
  page181_i30
#ISCELL
  logical_power universal_power *
  page181_i31
#CELL
  pure_quanta q_cap *
  page181_i32
#ISCELL
  logical_power universal_gnd *
  page181_i33
#ISCELL
  logical_power universal_power *
  page181_i4
#CELL
  pure_quanta q_cap *
  page181_i40
#ISCELL
  logical_power universal_power *
  page181_i41
#CELL
  pure_quanta q_cap *
  page181_i42
#CELL
  pure_quanta q_cap *
  page181_i43
#ISCELL
  logical_power universal_gnd *
  page181_i44
#CELL
  pure_quanta q_cap *
  page181_i45
#CELL
  pure_quanta q_cap *
  page181_i48
#CELL
  pure_quanta q_cap *
  page181_i49
#ISCELL
  logical_power universal_gnd *
  page181_i5
#ISCELL
  logical_power universal_gnd *
  page181_i50
#CELL
  pure_quanta q_cap *
  page181_i51
#CELL
  pure_quanta q_cap *
  page181_i58
#CELL
  pure_quanta q_cap *
  page181_i59
#CELL
  pure_quanta q_cap *
  page181_i6
#CELL
  pure_quanta q_cap *
  page181_i60
#CELL
  pure_quanta q_cap *
  page181_i61
#CELL
  pure_quanta q_cap *
  page181_i63
#ISCELL
  logical_power universal_gnd *
  page181_i64
#ISCELL
  logical_power universal_gnd *
  page181_i68
#CELL
  pure_quanta q_cap *
  page181_i7
#CELL
  pure_quanta q_cap *
  page181_i78
#CELL
  pure_quanta q_cap *
  page181_i8
#CELL
  pure_quanta q_cap *
  page181_i87
#ISCELL
  logical_power universal_gnd *
  page181_i88
#CELL
  pure_quanta q_cap *
  page181_i89
#ISCELL
  logical_power universal_power *
  page181_i90
#CELL
  pure_quanta q_cap *
  page181_i91
#ISCELL
  logical_power universal_gnd *
  page181_i92
#ISCELL
  logical_power universal_gnd *
  page181_i93
#ISCELL
  logical_power universal_power *
  page181_i94
#ISCELL
  logical_power universal_power *
  page181_i95
#ISCELL
  logical_power universal_power *
  page181_i99
#ISCELL
  logical_power bom_note *
  *
#ISCELL
  logical_power design_note *
  *
#ISCELL
  mstr_misc dns *
  *
#ISCELL
  pure_quanta quanta_title_block_c *
  *
#CELL
  pure_quanta q_cap *
  page182_i100
#CELL
  pure_quanta q_res *
  page182_i105
#ISCELL
  logical_power universal_gnd *
  page182_i106
#ISCELL
  standard offpage *
  page182_i107
#ISCELL
  standard offpage *
  page182_i108
#ISCELL
  standard offpage *
  page182_i120
#ISCELL
  standard offpage *
  page182_i123
#ISCELL
  standard offpage *
  page182_i124
#ISCELL
  standard offpage *
  page182_i125
#ISCELL
  standard tap *
  page182_i136
#ISCELL
  standard tap *
  page182_i137
#ISCELL
  standard tap *
  page182_i146
#ISCELL
  standard tap *
  page182_i147
#ISCELL
  standard tap *
  page182_i150
#ISCELL
  standard tap *
  page182_i151
#ISCELL
  standard offpage *
  page182_i154
#ISCELL
  standard offpage *
  page182_i155
#ISCELL
  standard offpage *
  page182_i158
#ISCELL
  standard offpage *
  page182_i159
#ISCELL
  standard offpage *
  page182_i160
#ISCELL
  standard offpage *
  page182_i161
#CELL
  pure_quanta q_res *
  page182_i162
#ISCELL
  standard offpage *
  page182_i163
#CELL
  pure_quanta q_res *
  page182_i164
#ISCELL
  logical_power universal_gnd *
  page182_i165
#CELL
  pure_quanta q_res *
  page182_i167
#ISCELL
  logical_power universal_gnd *
  page182_i172
#CELL
  pure_quanta q_res *
  page182_i173
#ISCELL
  logical_power universal_power *
  page182_i174
#ISCELL
  standard offpage *
  page182_i175
#CELL
  pure_quanta q_res *
  page182_i176
#ISCELL
  logical_power universal_power *
  page182_i177
#CELL
  pure_quanta sconn75k_apci0155p004a *
  page182_i178
#ISCELL
  standard offpage *
  page182_i231
#ISCELL
  standard tap *
  page182_i233
#ISCELL
  standard tap *
  page182_i234
#ISCELL
  standard tap *
  page182_i235
#ISCELL
  standard tap *
  page182_i236
#ISCELL
  standard tap *
  page182_i237
#ISCELL
  standard tap *
  page182_i238
#ISCELL
  standard offpage *
  page182_i244
#ISCELL
  standard offpage *
  page182_i245
#CELL
  pure_quanta q_res *
  page182_i247
#ISCELL
  standard offpage *
  page182_i248
#ISCELL
  logical_power universal_power *
  page182_i249
#ISCELL
  standard offpage *
  page182_i250
#ISCELL
  standard offpage *
  page182_i296
#CELL
  pure_quanta q_res *
  page182_i299
#ISCELL
  logical_power universal_power *
  page182_i300
#ISCELL
  logical_power universal_gnd *
  page182_i301
#ISCELL
  standard offpage *
  page182_i302
#CELL
  pure_quanta q_res *
  page182_i303
#ISCELL
  logical_power universal_gnd *
  page182_i304
#ISCELL
  logical_power universal_power *
  page182_i305
#CELL
  pure_quanta q_res *
  page182_i306
#ISCELL
  logical_power universal_power *
  page182_i307
#CELL
  pure_quanta q_cap *
  page182_i308
#ISCELL
  logical_power universal_gnd *
  page182_i309
#ISCELL
  logical_power universal_gnd *
  page182_i310
#ISCELL
  standard offpage *
  page182_i311
#CELL
  pure_quanta q_res *
  page182_i312
#ISCELL
  logical_power universal_gnd *
  page182_i313
#CELL
  pure_quanta 74lvc1g126se7 *
  page182_i315
#CELL
  pure_quanta q_res *
  page182_i317
#ISCELL
  standard offpage *
  page182_i318
#CELL
  pure_quanta q_res *
  page182_i320
#ISCELL
  standard offpage *
  page182_i322
#ISCELL
  logical_power universal_power *
  page182_i323
#CELL
  pure_quanta q_res *
  page182_i324
#ISCELL
  logical_power universal_power *
  page182_i325
#CELL
  pure_quanta q_cap *
  page182_i326
#CELL
  pure_quanta sn74lvc2g07dckr *
  page182_i327
#ISCELL
  logical_power universal_gnd *
  page182_i328
#ISCELL
  standard offpage *
  page182_i329
#ISCELL
  standard offpage *
  page182_i336
#CELL
  pure_quanta q_res *
  page182_i337
#ISCELL
  logical_power universal_power *
  page182_i338
#ISCELL
  standard offpage *
  page182_i340
#ISCELL
  logical_power universal_power *
  page182_i341
#CELL
  pure_quanta mosfet_nch_dual *
  page182_i342
#CELL
  pure_quanta mosfet_nch_dual *
  page182_i343
#CELL
  pure_quanta q_res *
  page182_i344
#CELL
  pure_quanta q_cap *
  page182_i88
#ISCELL
  logical_power universal_power *
  page182_i89
#CELL
  pure_quanta q_cap *
  page182_i90
#CELL
  pure_quanta q_cap *
  page182_i96
#CELL
  pure_quanta q_cap *
  page182_i97
#CELL
  pure_quanta q_cap *
  page182_i98
#ISCELL
  logical_power universal_gnd *
  page182_i99
#ISCELL
  logical_power cad_note *
  *
#ISCELL
  logical_power design_note *
  *
#ISCELL
  mstr_misc dns *
  *
#ISCELL
  pure_quanta quanta_title_block_c *
  *
#ISCELL
  standard offpage *
  page297_i156
#CELL
  pure_quanta q_res *
  page297_i157
#ISCELL
  standard offpage *
  page297_i158
#CELL
  pure_quanta q_res *
  page297_i159
#ISCELL
  logical_power universal_power *
  page297_i160
#CELL
  pure_quanta 74lvc1g126se7 *
  page297_i163
#ISCELL
  logical_power universal_gnd *
  page297_i164
#CELL
  pure_quanta q_res *
  page297_i165
#ISCELL
  logical_power universal_gnd *
  page297_i166
#ISCELL
  standard offpage *
  page297_i167
#ISCELL
  logical_power universal_power *
  page297_i168
#CELL
  pure_quanta q_res *
  page297_i169
#CELL
  pure_quanta q_cap *
  page297_i170
#ISCELL
  logical_power universal_gnd *
  page297_i171
#ISCELL
  logical_power universal_power *
  page297_i172
#CELL
  pure_quanta q_cap *
  page297_i237
#ISCELL
  logical_power universal_power *
  page297_i238
#ISCELL
  standard offpage *
  page297_i240
#ISCELL
  standard offpage *
  page297_i241
#ISCELL
  logical_power universal_power *
  page297_i242
#ISCELL
  standard offpage *
  page297_i244
#CELL
  pure_quanta q_cap *
  page297_i245
#ISCELL
  logical_power universal_power *
  page297_i246
#CELL
  pure_quanta q_cap *
  page297_i247
#ISCELL
  logical_power universal_gnd *
  page297_i248
#ISCELL
  logical_power universal_gnd *
  page297_i250
#ISCELL
  standard offpage *
  page297_i251
#CELL
  pure_quanta q_cap *
  page297_i252
#ISCELL
  logical_power universal_gnd *
  page297_i253
#ISCELL
  standard offpage *
  page297_i254
#ISCELL
  standard offpage *
  page297_i255
#ISCELL
  standard offpage *
  page297_i256
#ISCELL
  standard offpage *
  page297_i257
#CELL
  pure_quanta q_cap *
  page297_i258
#ISCELL
  logical_power universal_power *
  page297_i259
#CELL
  pure_quanta q_cap *
  page297_i260
#ISCELL
  logical_power universal_power *
  page297_i261
#ISCELL
  logical_power universal_power *
  page297_i262
#ISCELL
  logical_power universal_power *
  page297_i263
#CELL
  pure_quanta q_res *
  page297_i264
#ISCELL
  standard tap *
  page297_i267
#ISCELL
  standard tap *
  page297_i268
#ISCELL
  standard tap *
  page297_i269
#ISCELL
  standard tap *
  page297_i270
#ISCELL
  standard tap *
  page297_i271
#ISCELL
  standard tap *
  page297_i272
#ISCELL
  logical_power universal_gnd *
  page297_i273
#ISCELL
  logical_power universal_gnd *
  page297_i275
#ISCELL
  standard tap *
  page297_i278
#ISCELL
  standard tap *
  page297_i280
#ISCELL
  standard tap *
  page297_i281
#ISCELL
  standard tap *
  page297_i283
#ISCELL
  standard offpage *
  page297_i285
#ISCELL
  standard offpage *
  page297_i286
#ISCELL
  standard offpage *
  page297_i287
#ISCELL
  standard offpage *
  page297_i288
#ISCELL
  standard offpage *
  page297_i289
#ISCELL
  logical_power universal_power *
  page297_i290
#CELL
  pure_quanta q_res *
  page297_i291
#ISCELL
  standard offpage *
  page297_i292
#CELL
  pure_quanta q_res *
  page297_i293
#ISCELL
  logical_power universal_gnd *
  page297_i294
#ISCELL
  logical_power universal_power *
  page297_i295
#CELL
  pure_quanta q_res *
  page297_i296
#ISCELL
  standard offpage *
  page297_i297
#ISCELL
  standard offpage *
  page297_i298
#CELL
  pure_quanta q_res *
  page297_i299
#ISCELL
  logical_power universal_power *
  page297_i300
#CELL
  pure_quanta q_res *
  page297_i301
#CELL
  pure_quanta q_res *
  page297_i302
#ISCELL
  logical_power universal_gnd *
  page297_i303
#CELL
  pure_quanta q_cap *
  page297_i304
#CELL
  pure_quanta 74lvc2g07dw7 *
  page297_i305
#ISCELL
  logical_power universal_gnd *
  page297_i306
#CELL
  pure_quanta q_res *
  page297_i307
#ISCELL
  standard offpage *
  page297_i308
#CELL
  pure_quanta q_res *
  page297_i309
#ISCELL
  standard offpage *
  page297_i310
#CELL
  pure_quanta q_res *
  page297_i311
#CELL
  pure_quanta q_res *
  page297_i312
#CELL
  pure_quanta q_res *
  page297_i313
#CELL
  pure_quanta mosfet_nch_gds_esd_protected *
  page297_i316
#ISCELL
  logical_power universal_gnd *
  page297_i317
#CELL
  pure_quanta sconn56_123276793 *
  page297_i318
#ISCELL
  standard tap *
  page297_i319
#ISCELL
  standard tap *
  page297_i320
#ISCELL
  standard tap *
  page297_i321
#ISCELL
  standard tap *
  page297_i322
#ISCELL
  standard tap *
  page297_i324
#ISCELL
  standard tap *
  page297_i325
#ISCELL
  logical_power universal_gnd *
  page297_i326
#CELL
  pure_quanta q_cap *
  page297_i327
#ISCELL
  logical_power universal_power *
  page297_i328
#CELL
  pure_quanta apx80929sag7 *
  page297_i329
#ISCELL
  logical_power universal_gnd *
  page297_i330
#CELL
  pure_quanta q_res *
  page297_i331
#ISCELL
  standard offpage *
  page297_i332
#ISCELL
  logical_power cad_note *
  *
#ISCELL
  mstr_misc dns *
  *
#ISCELL
  pure_quanta quanta_title_block_c *
  *
#CELL
  pure_quanta q_res *
  page324_i1
#CELL
  pure_quanta mosfet_nch_dual *
  page324_i10
#ISCELL
  logical_power gnd *
  page324_i11
#ISCELL
  logical_power gnd *
  page324_i12
#CELL
  pure_quanta q_res *
  page324_i13
#CELL
  pure_quanta q_res *
  page324_i14
#CELL
  pure_quanta q_res *
  page324_i15
#ISCELL
  logical_power gnd *
  page324_i16
#CELL
  pure_quanta q_cap *
  page324_i17
#CELL
  pure_quanta q_res *
  page324_i18
#ISCELL
  logical_power universal_power *
  page324_i19
#ISCELL
  logical_power gnd *
  page324_i2
#ISCELL
  standard offpage *
  page324_i20
#CELL
  pure_quanta q_res *
  page324_i21
#CELL
  pure_quanta q_res *
  page324_i22
#ISCELL
  logical_power universal_power *
  page324_i23
#CELL
  pure_quanta mosfet_nch_dual *
  page324_i24
#ISCELL
  logical_power gnd *
  page324_i25
#CELL
  pure_quanta q_res *
  page324_i26
#ISCELL
  logical_power gnd *
  page324_i27
#CELL
  pure_quanta q_res *
  page324_i28
#ISCELL
  logical_power gnd *
  page324_i29
#CELL
  pure_quanta mosfet_nch_dual *
  page324_i3
#ISCELL
  logical_power universal_power *
  page324_i30
#CELL
  pure_quanta q_cap *
  page324_i31
#CELL
  pure_quanta q_res *
  page324_i32
#ISCELL
  logical_power gnd *
  page324_i33
#CELL
  pure_quanta q_res *
  page324_i34
#CELL
  pure_quanta max15090bewit *
  page324_i35
#ISCELL
  logical_power gnd *
  page324_i36
#CELL
  pure_quanta q_cap *
  page324_i37
#CELL
  pure_quanta q_cap *
  page324_i38
#CELL
  pure_quanta q_res *
  page324_i39
#CELL
  pure_quanta mosfet_nch_dual *
  page324_i4
#ISCELL
  logical_power gnd *
  page324_i40
#CELL
  pure_quanta q_res *
  page324_i41
#CELL
  pure_quanta q_cap *
  page324_i42
#CELL
  pure_quanta q_res *
  page324_i43
#CELL
  pure_quanta q_res *
  page324_i44
#CELL
  pure_quanta q_cap *
  page324_i45
#CELL
  pure_quanta schottky_ac *
  page324_i46
#ISCELL
  logical_power gnd *
  page324_i47
#CELL
  pure_quanta q_res *
  page324_i48
#ISCELL
  logical_power vccaux15 *
  page324_i49
#ISCELL
  logical_power gnd *
  page324_i5
#CELL
  pure_quanta q_res *
  page324_i50
#ISCELL
  logical_power gnd *
  page324_i51
#CELL
  pure_quanta q_cap *
  page324_i52
#CELL
  pure_quanta q_cap *
  page324_i53
#ISCELL
  logical_power universal_power *
  page324_i54
#ISCELL
  logical_power universal_power *
  page324_i55
#ISCELL
  logical_power gnd *
  page324_i56
#CELL
  pure_quanta q_cap *
  page324_i57
#ISCELL
  logical_power gnd *
  page324_i58
#CELL
  pure_quanta q_res *
  page324_i59
#CELL
  pure_quanta q_res *
  page324_i6
#CELL
  pure_quanta q_cap *
  page324_i60
#CELL
  pure_quanta q_res *
  page324_i61
#CELL
  pure_quanta max15090bewit *
  page324_i62
#ISCELL
  logical_power gnd *
  page324_i63
#CELL
  pure_quanta q_res *
  page324_i64
#CELL
  pure_quanta q_res *
  page324_i65
#CELL
  pure_quanta q_cap *
  page324_i66
#CELL
  pure_quanta q_res *
  page324_i67
#CELL
  pure_quanta q_res *
  page324_i68
#CELL
  pure_quanta q_cap *
  page324_i69
#ISCELL
  logical_power universal_power *
  page324_i7
#CELL
  pure_quanta q_res *
  page324_i70
#CELL
  pure_quanta schottky_ac *
  page324_i71
#ISCELL
  logical_power gnd *
  page324_i72
#CELL
  pure_quanta q_res *
  page324_i73
#ISCELL
  logical_power vccaux15 *
  page324_i74
#CELL
  pure_quanta q_cap *
  page324_i75
#CELL
  pure_quanta q_res *
  page324_i76
#ISCELL
  logical_power gnd *
  page324_i77
#CELL
  pure_quanta q_cap *
  page324_i78
#CELL
  pure_quanta q_cap *
  page324_i79
#ISCELL
  logical_power gnd *
  page324_i8
#ISCELL
  logical_power universal_power *
  page324_i80
#ISCELL
  standard offpage *
  page324_i81
#ISCELL
  standard offpage *
  page324_i82
#ISCELL
  standard offpage *
  page324_i83
#CELL
  pure_quanta diode_tvs *
  page324_i84
#CELL
  pure_quanta q_res *
  page324_i85
#CELL
  pure_quanta q_res *
  page324_i9
#ISCELL
  logical_power cad_note *
  *
#ISCELL
  mstr_misc dns *
  *
#ISCELL
  pure_quanta quanta_title_block_c *
  *
#ISCELL
  standard offpage *
  page323_i1
#ISCELL
  logical_power universal_power *
  page323_i10
#ISCELL
  logical_power universal_gnd *
  page323_i2
#ISCELL
  logical_power universal_gnd *
  page323_i28
#ISCELL
  logical_power universal_gnd *
  page323_i29
#CELL
  pure_quanta q_cap *
  page323_i3
#CELL
  pure_quanta q_cap *
  page323_i30
#CELL
  pure_quanta mp5016gqhlz *
  page323_i31
#CELL
  pure_quanta q_cap *
  page323_i32
#ISCELL
  logical_power universal_gnd *
  page323_i33
#CELL
  pure_quanta q_cap *
  page323_i34
#ISCELL
  logical_power universal_power *
  page323_i35
#ISCELL
  logical_power gnd *
  page323_i36
#CELL
  pure_quanta q_cap *
  page323_i37
#ISCELL
  standard offpage *
  page323_i38
#ISCELL
  logical_power gnd *
  page323_i39
#CELL
  pure_quanta q_res *
  page323_i4
#CELL
  pure_quanta q_res *
  page323_i40
#ISCELL
  logical_power gnd *
  page323_i41
#CELL
  pure_quanta q_cap *
  page323_i42
#CELL
  pure_quanta q_res *
  page323_i43
#ISCELL
  logical_power gnd *
  page323_i44
#CELL
  pure_quanta q_res *
  page323_i45
#ISCELL
  logical_power gnd *
  page323_i46
#CELL
  pure_quanta q_cap *
  page323_i47
#ISCELL
  logical_power gnd *
  page323_i48
#CELL
  pure_quanta rs31312r *
  page323_i49
#CELL
  pure_quanta q_res *
  page323_i5
#ISCELL
  logical_power gnd *
  page323_i50
#CELL
  pure_quanta q_cap *
  page323_i51
#ISCELL
  logical_power universal_power *
  page323_i52
#CELL
  pure_quanta q_res *
  page323_i53
#CELL
  pure_quanta q_res *
  page323_i54
#CELL
  pure_quanta q_res *
  page323_i55
#CELL
  pure_quanta q_cap *
  page323_i56
#ISCELL
  logical_power gnd *
  page323_i57
#CELL
  pure_quanta q_res *
  page323_i58
#ISCELL
  standard offpage *
  page323_i59
#CELL
  pure_quanta q_res *
  page323_i6
#ISCELL
  standard offpage *
  page323_i60
#ISCELL
  logical_power vccaux15 *
  page323_i61
#CELL
  pure_quanta q_res *
  page323_i62
#CELL
  pure_quanta q_res *
  page323_i63
#CELL
  pure_quanta q_res *
  page323_i64
#ISCELL
  logical_power vccaux15 *
  page323_i65
#CELL
  pure_quanta q_res *
  page323_i66
#CELL
  pure_quanta q_res *
  page323_i67
#ISCELL
  logical_power gnd *
  page323_i68
#CELL
  pure_quanta q_cap *
  page323_i69
#ISCELL
  logical_power universal_gnd *
  page323_i7
#CELL
  pure_quanta q_res *
  page323_i70
#ISCELL
  logical_power universal_power *
  page323_i71
#ISCELL
  logical_power gnd *
  page323_i72
#CELL
  pure_quanta q_cap *
  page323_i73
#ISCELL
  standard offpage *
  page323_i74
#ISCELL
  standard offpage *
  page323_i75
#ISCELL
  standard offpage *
  page323_i76
#ISCELL
  logical_power universal_power *
  page323_i77
#ISCELL
  logical_power universal_gnd *
  page323_i8
#CELL
  pure_quanta q_cap *
  page323_i9
#ISCELL
  mstr_misc dns *
  *
#ISCELL
  pure_quanta quanta_title_block_c *
  *
#CELL
  pure_quanta pca9306dp1 *
  page183_i27
#CELL
  pure_quanta q_cap *
  page183_i28
#ISCELL
  logical_power universal_power *
  page183_i29
#ISCELL
  logical_power universal_power *
  page183_i3
#ISCELL
  logical_power universal_gnd *
  page183_i30
#ISCELL
  logical_power universal_gnd *
  page183_i38
#CELL
  pure_quanta q_res *
  page183_i43
#CELL
  pure_quanta q_res *
  page183_i45
#ISCELL
  logical_power universal_power *
  page183_i47
#CELL
  pure_quanta q_res *
  page183_i5
#ISCELL
  logical_power universal_power *
  page183_i51
#CELL
  pure_quanta q_cap *
  page183_i52
#ISCELL
  logical_power universal_gnd *
  page183_i53
#ISCELL
  standard offpage *
  page183_i54
#ISCELL
  standard offpage *
  page183_i55
#CELL
  pure_quanta q_res *
  page183_i65
#CELL
  pure_quanta q_res *
  page183_i66
#ISCELL
  standard offpage *
  page183_i67
#ISCELL
  standard offpage *
  page183_i68
#ISCELL
  standard offpage *
  page183_i7
#CELL
  pure_quanta q_res *
  page183_i70
#ISCELL
  standard offpage *
  page183_i71
#CELL
  pure_quanta q_res *
  page183_i72
#ISCELL
  standard offpage *
  page183_i73
#ISCELL
  standard offpage *
  page183_i74
#CELL
  pure_quanta q_res *
  page183_i76
#CELL
  pure_quanta q_res *
  page183_i77
#CELL
  pure_quanta q_res *
  page183_i78
#CELL
  pure_quanta q_res *
  page183_i80
#CELL
  pure_quanta q_cap *
  page183_i82
#ISCELL
  logical_power universal_gnd *
  page183_i84
#ISCELL
  logical_power universal_power *
  page183_i87
#CELL
  pure_quanta q_cap *
  page183_i89
#ISCELL
  logical_power universal_gnd *
  page183_i90
#ISCELL
  standard offpage *
  page183_i91
#ISCELL
  standard offpage *
  page183_i92
#CELL
  pure_quanta pca9617adp *
  page183_i93
#ISCELL
  standard offpage *
  page183_i94
#ISCELL
  logical_power universal_gnd *
  page183_i95
#CELL
  pure_quanta q_res *
  page183_i96
#ISCELL
  logical_power universal_power *
  page183_i97
#ISCELL
  logical_power universal_power *
  page183_i98
#CELL
  pure_quanta q_res *
  page183_i99
#ISCELL
  logical_power design_note *
  *
#ISCELL
  mstr_misc dns *
  *
#ISCELL
  pure_quanta quanta_title_block_c *
  *
#CELL
  pure_quanta q_res *
  page184_i1
#ISCELL
  logical_power universal_gnd *
  page184_i10
#CELL
  pure_quanta q_res *
  page184_i11
#CELL
  pure_quanta q_res *
  page184_i12
#CELL
  pure_quanta q_res *
  page184_i13
#ISCELL
  logical_power universal_power *
  page184_i14
#ISCELL
  logical_power universal_gnd *
  page184_i15
#CELL
  pure_quanta q_res *
  page184_i16
#ISCELL
  logical_power universal_gnd *
  page184_i17
#CELL
  pure_quanta q_res *
  page184_i18
#ISCELL
  logical_power universal_gnd *
  page184_i19
#ISCELL
  logical_power universal_gnd *
  page184_i2
#CELL
  pure_quanta q_res *
  page184_i20
#ISCELL
  standard offpage *
  page184_i21
#CELL
  pure_quanta q_res *
  page184_i22
#CELL
  pure_quanta q_res *
  page184_i23
#CELL
  pure_quanta q_res *
  page184_i24
#ISCELL
  logical_power universal_gnd *
  page184_i25
#CELL
  pure_quanta q_res *
  page184_i26
#ISCELL
  logical_power universal_gnd *
  page184_i27
#CELL
  pure_quanta q_res *
  page184_i28
#ISCELL
  logical_power universal_gnd *
  page184_i29
#ISCELL
  logical_power universal_gnd *
  page184_i3
#CELL
  pure_quanta q_res *
  page184_i30
#ISCELL
  standard offpage *
  page184_i31
#ISCELL
  standard offpage *
  page184_i32
#ISCELL
  standard offpage *
  page184_i33
#ISCELL
  standard offpage *
  page184_i34
#CELL
  pure_quanta q_res *
  page184_i4
#CELL
  pure_quanta q_res *
  page184_i48
#CELL
  pure_quanta q_res *
  page184_i49
#CELL
  pure_quanta q_res *
  page184_i5
#CELL
  pure_quanta q_res *
  page184_i50
#ISCELL
  standard offpage *
  page184_i51
#ISCELL
  standard offpage *
  page184_i52
#ISCELL
  standard offpage *
  page184_i53
#ISCELL
  standard offpage *
  page184_i54
#ISCELL
  standard offpage *
  page184_i55
#ISCELL
  logical_power universal_gnd *
  page184_i56
#ISCELL
  logical_power universal_gnd *
  page184_i57
#CELL
  pure_quanta q_res *
  page184_i58
#CELL
  pure_quanta q_res *
  page184_i59
#CELL
  pure_quanta q_res *
  page184_i6
#ISCELL
  logical_power universal_gnd *
  page184_i60
#CELL
  pure_quanta q_res *
  page184_i61
#CELL
  pure_quanta q_res *
  page184_i62
#CELL
  pure_quanta q_res *
  page184_i63
#ISCELL
  logical_power universal_power *
  page184_i64
#ISCELL
  logical_power universal_gnd *
  page184_i65
#ISCELL
  logical_power universal_gnd *
  page184_i66
#CELL
  pure_quanta q_res *
  page184_i67
#ISCELL
  logical_power universal_gnd *
  page184_i68
#CELL
  pure_quanta q_res *
  page184_i69
#ISCELL
  logical_power universal_power *
  page184_i7
#CELL
  pure_quanta q_res *
  page184_i70
#CELL
  pure_quanta q_res *
  page184_i71
#CELL
  pure_quanta q_res *
  page184_i72
#ISCELL
  logical_power universal_power *
  page184_i73
#CELL
  pure_quanta q_res *
  page184_i74
#CELL
  pure_quanta q_res *
  page184_i75
#ISCELL
  standard offpage *
  page184_i76
#ISCELL
  standard offpage *
  page184_i77
#ISCELL
  standard offpage *
  page184_i78
#ISCELL
  standard offpage *
  page184_i79
#ISCELL
  logical_power universal_gnd *
  page184_i8
#ISCELL
  standard offpage *
  page184_i80
#ISCELL
  standard offpage *
  page184_i81
#CELL
  pure_quanta q_res *
  page184_i9
#ISCELL
  logical_power cad_note *
  *
#ISCELL
  mstr_misc dns *
  *
#ISCELL
  pure_quanta quanta_title_block_c *
  *
#ISCELL
  logical_power universal_gnd *
  page194_i1
#ISCELL
  logical_power universal_power *
  page194_i10
#ISCELL
  standard offpage *
  page194_i11
#ISCELL
  standard offpage *
  page194_i12
#CELL
  pure_quanta q_res *
  page194_i13
#ISCELL
  logical_power universal_gnd *
  page194_i14
#CELL
  pure_quanta q_cap *
  page194_i15
#CELL
  pure_quanta q_res *
  page194_i16
#CELL
  pure_quanta q_res *
  page194_i17
#CELL
  pure_quanta q_res *
  page194_i18
#CELL
  pure_quanta q_res *
  page194_i19
#CELL
  pure_quanta q_cap *
  page194_i2
#CELL
  pure_quanta tusb211irwbr *
  page194_i20
#ISCELL
  logical_power universal_power *
  page194_i21
#CELL
  pure_quanta q_res *
  page194_i22
#CELL
  pure_quanta q_res *
  page194_i23
#CELL
  pure_quanta q_res *
  page194_i24
#CELL
  pure_quanta q_res *
  page194_i25
#CELL
  pure_quanta q_res *
  page194_i26
#CELL
  pure_quanta q_res *
  page194_i27
#ISCELL
  standard offpage *
  page194_i28
#ISCELL
  standard offpage *
  page194_i29
#ISCELL
  logical_power universal_gnd *
  page194_i3
#ISCELL
  standard offpage *
  page194_i30
#ISCELL
  standard offpage *
  page194_i31
#ISCELL
  standard offpage *
  page194_i32
#ISCELL
  standard offpage *
  page194_i33
#ISCELL
  standard offpage *
  page194_i34
#ISCELL
  logical_power universal_gnd *
  page194_i35
#ISCELL
  logical_power universal_gnd *
  page194_i36
#CELL
  pure_quanta q_res *
  page194_i37
#CELL
  pure_quanta q_res *
  page194_i38
#ISCELL
  standard offpage *
  page194_i39
#CELL
  pure_quanta q_res *
  page194_i4
#CELL
  pure_quanta gl852gohy60 *
  page194_i40
#CELL
  pure_quanta q_res *
  page194_i41
#ISCELL
  logical_power universal_gnd *
  page194_i42
#CELL
  pure_quanta q_cap *
  page194_i43
#ISCELL
  logical_power universal_power *
  page194_i44
#CELL
  pure_quanta q_cap *
  page194_i45
#CELL
  pure_quanta q_cap *
  page194_i46
#CELL
  pure_quanta q_cap *
  page194_i47
#ISCELL
  logical_power universal_power *
  page194_i48
#CELL
  pure_quanta q_cap *
  page194_i49
#ISCELL
  standard offpage *
  page194_i5
#CELL
  pure_quanta q_res *
  page194_i50
#CELL
  pure_quanta q_cap *
  page194_i51
#CELL
  pure_quanta q_cap *
  page194_i52
#CELL
  pure_quanta q_cap *
  page194_i53
#ISCELL
  logical_power universal_gnd *
  page194_i54
#CELL
  pure_quanta q_cap *
  page194_i55
#CELL
  pure_quanta q_cap *
  page194_i56
#ISCELL
  logical_power universal_gnd *
  page194_i57
#CELL
  pure_quanta q_cap *
  page194_i58
#ISCELL
  logical_power universal_gnd *
  page194_i59
#ISCELL
  standard offpage *
  page194_i6
#CELL
  pure_quanta q_res *
  page194_i60
#CELL
  pure_quanta q_res *
  page194_i61
#ISCELL
  logical_power universal_power *
  page194_i62
#ISCELL
  logical_power universal_gnd *
  page194_i63
#ISCELL
  standard offpage *
  page194_i64
#ISCELL
  standard offpage *
  page194_i65
#ISCELL
  standard offpage *
  page194_i66
#ISCELL
  standard offpage *
  page194_i67
#ISCELL
  logical_power universal_gnd *
  page194_i7
#CELL
  pure_quanta q_res *
  page194_i72
#CELL
  pure_quanta q_res *
  page194_i73
#ISCELL
  standard offpage *
  page194_i74
#CELL
  pure_quanta q_res *
  page194_i75
#ISCELL
  logical_power universal_gnd *
  page194_i76
#CELL
  pure_quanta q_res *
  page194_i77
#CELL
  pure_quanta q_res *
  page194_i78
#ISCELL
  standard offpage *
  page194_i79
#CELL
  pure_quanta q_res *
  page194_i8
#ISCELL
  logical_power universal_gnd *
  page194_i80
#CELL
  pure_quanta q_cap *
  page194_i81
#ISCELL
  logical_power universal_gnd *
  page194_i82
#CELL
  pure_quanta q_xtal_4p_13bi_24gnd *
  page194_i83
#ISCELL
  logical_power universal_gnd *
  page194_i84
#CELL
  pure_quanta q_cap *
  page194_i85
#ISCELL
  logical_power universal_gnd *
  page194_i86
#ISCELL
  standard offpage *
  page194_i87
#CELL
  pure_quanta q_res *
  page194_i88
#ISCELL
  logical_power universal_gnd *
  page194_i89
#CELL
  pure_quanta q_res *
  page194_i9
#CELL
  pure_quanta q_res *
  page194_i90
#ISCELL
  logical_power universal_gnd *
  page194_i91
#ISCELL
  logical_power design_note *
  *
#ISCELL
  mstr_misc dns *
  *
#ISCELL
  pure_quanta quanta_title_block_c *
  *
#ISCELL
  standard offpage *
  page185_i18
#ISCELL
  standard offpage *
  page185_i19
#ISCELL
  standard offpage *
  page185_i20
#ISCELL
  logical_power universal_gnd *
  page185_i22
#CELL
  pure_quanta q_res *
  page185_i24
#CELL
  pure_quanta q_res *
  page185_i26
#ISCELL
  logical_power universal_power *
  page185_i27
#ISCELL
  logical_power universal_gnd *
  page185_i28
#CELL
  pure_quanta q_res *
  page185_i30
#ISCELL
  logical_power universal_power *
  page185_i31
#CELL
  pure_quanta q_res *
  page185_i32
#ISCELL
  logical_power universal_gnd *
  page185_i34
#CELL
  pure_quanta nc7sb3157 *
  page185_i35
#CELL
  pure_quanta q_cap *
  page185_i36
#ISCELL
  logical_power universal_power *
  page185_i37
#ISCELL
  logical_power universal_gnd *
  page185_i38
#CELL
  pure_quanta q_res *
  page185_i39
#ISCELL
  logical_power universal_power *
  page185_i40
#CELL
  pure_quanta q_res *
  page185_i41
#CELL
  pure_quanta q_res *
  page185_i42
#ISCELL
  logical_power universal_gnd *
  page185_i43
#ISCELL
  standard offpage *
  page185_i44
#CELL
  pure_quanta q_res *
  page185_i45
#ISCELL
  standard offpage *
  page185_i46
#CELL
  pure_quanta q_res *
  page185_i47
#CELL
  pure_quanta q_res *
  page185_i49
#CELL
  pure_quanta q_res *
  page185_i50
#CELL
  pure_quanta q_res *
  page185_i51
#ISCELL
  logical_power design_note *
  *
#ISCELL
  mstr_misc dns *
  *
#ISCELL
  pure_quanta quanta_title_block_c *
  *
#ISCELL
  logical_power universal_power *
  page186_i10
#CELL
  pure_quanta q_res *
  page186_i11
#ISCELL
  standard offpage *
  page186_i14
#ISCELL
  logical_power universal_power *
  page186_i15
#CELL
  pure_quanta q_res *
  page186_i16
#ISCELL
  standard offpage *
  page186_i41
#ISCELL
  logical_power universal_power *
  page186_i44
#CELL
  pure_quanta q_res *
  page186_i45
#CELL
  pure_quanta q_res *
  page186_i46
#ISCELL
  logical_power universal_gnd *
  page186_i47
#ISCELL
  logical_power universal_power *
  page186_i58
#ISCELL
  standard offpage *
  page186_i59
#CELL
  pure_quanta q_res *
  page186_i60
#CELL
  pure_quanta q_res *
  page186_i61
#ISCELL
  logical_power universal_gnd *
  page186_i62
#ISCELL
  standard offpage *
  page186_i64
#ISCELL
  logical_power universal_power *
  page186_i65
#CELL
  pure_quanta q_res *
  page186_i68
#ISCELL
  standard offpage *
  page186_i72
#ISCELL
  logical_power universal_power *
  page186_i73
#ISCELL
  logical_power universal_gnd *
  page186_i74
#CELL
  pure_quanta q_res *
  page186_i76
#CELL
  pure_quanta q_res *
  page186_i77
#CELL
  pure_quanta q_res *
  page186_i78
#ISCELL
  standard offpage *
  page186_i79
#ISCELL
  standard offpage *
  page186_i8
#ISCELL
  logical_power universal_power *
  page186_i80
#CELL
  pure_quanta q_res *
  page186_i81
#ISCELL
  logical_power universal_gnd *
  page186_i82
#ISCELL
  standard offpage *
  page186_i84
#ISCELL
  logical_power universal_power *
  page186_i85
#ISCELL
  logical_power universal_gnd *
  page186_i87
#CELL
  pure_quanta q_res *
  page186_i88
#CELL
  pure_quanta q_res *
  page186_i89
#CELL
  pure_quanta q_res *
  page186_i90
#ISCELL
  logical_power universal_gnd *
  page186_i91
#CELL
  pure_quanta q_res *
  page186_i92
#ISCELL
  logical_power universal_gnd *
  page186_i93
#ISCELL
  mstr_misc dns *
  *
#ISCELL
  pure_quanta quanta_title_block_c *
  *
#ISCELL
  logical_power universal_gnd *
  page187_i11
#ISCELL
  logical_power universal_power *
  page187_i12
#CELL
  pure_quanta q_res *
  page187_i13
#CELL
  pure_quanta q_res *
  page187_i14
#ISCELL
  logical_power universal_gnd *
  page187_i15
#ISCELL
  standard offpage *
  page187_i16
#ISCELL
  logical_power universal_power *
  page187_i17
#CELL
  pure_quanta q_res *
  page187_i18
#ISCELL
  standard offpage *
  page187_i19
#ISCELL
  logical_power universal_power *
  page187_i20
#CELL
  pure_quanta q_res *
  page187_i21
#ISCELL
  standard offpage *
  page187_i22
#CELL
  pure_quanta q_res *
  page187_i23
#ISCELL
  logical_power universal_gnd *
  page187_i24
#ISCELL
  logical_power universal_power *
  page187_i25
#ISCELL
  standard offpage *
  page187_i27
#ISCELL
  logical_power universal_power *
  page187_i30
#ISCELL
  standard offpage *
  page187_i32
#ISCELL
  standard offpage *
  page187_i33
#ISCELL
  logical_power universal_gnd *
  page187_i35
#CELL
  pure_quanta q_res *
  page187_i36
#ISCELL
  logical_power universal_gnd *
  page187_i37
#ISCELL
  logical_power universal_power *
  page187_i38
#CELL
  pure_quanta q_res *
  page187_i39
#ISCELL
  standard offpage *
  page187_i4
#CELL
  pure_quanta q_res *
  page187_i40
#ISCELL
  logical_power universal_gnd *
  page187_i41
#ISCELL
  logical_power universal_power *
  page187_i42
#CELL
  pure_quanta q_res *
  page187_i43
#CELL
  pure_quanta q_res *
  page187_i44
#ISCELL
  logical_power universal_gnd *
  page187_i45
#ISCELL
  standard offpage *
  page187_i46
#ISCELL
  logical_power universal_power *
  page187_i47
#CELL
  pure_quanta q_res *
  page187_i48
#ISCELL
  standard offpage *
  page187_i5
#CELL
  pure_quanta q_res *
  page187_i51
#CELL
  pure_quanta q_res *
  page187_i53
#CELL
  pure_quanta q_res *
  page187_i54
#CELL
  pure_quanta q_res *
  page187_i55
#CELL
  pure_quanta q_res *
  page187_i56
#ISCELL
  logical_power universal_power *
  page187_i8
#ISCELL
  mstr_misc dns *
  *
#ISCELL
  pure_quanta quanta_title_block_c *
  *
#ISCELL
  logical_power universal_gnd *
  page188_i20
#CELL
  pure_quanta q_res *
  page188_i21
#CELL
  pure_quanta q_res *
  page188_i22
#ISCELL
  logical_power universal_power *
  page188_i23
#ISCELL
  standard offpage *
  page188_i25
#ISCELL
  standard offpage *
  page188_i26
#ISCELL
  logical_power universal_gnd *
  page188_i30
#CELL
  pure_quanta q_res *
  page188_i31
#ISCELL
  standard offpage *
  page188_i33
#CELL
  pure_quanta q_res *
  page188_i36
#ISCELL
  logical_power universal_gnd *
  page188_i37
#ISCELL
  standard offpage *
  page188_i38
#ISCELL
  logical_power universal_power *
  page188_i39
#ISCELL
  logical_power universal_gnd *
  page188_i42
#CELL
  pure_quanta q_res *
  page188_i43
#CELL
  pure_quanta q_res *
  page188_i44
#ISCELL
  standard offpage *
  page188_i45
#ISCELL
  logical_power universal_power *
  page188_i46
#CELL
  pure_quanta q_res *
  page188_i47
#ISCELL
  logical_power universal_gnd *
  page188_i49
#CELL
  pure_quanta q_res *
  page188_i50
#ISCELL
  standard offpage *
  page188_i51
#ISCELL
  logical_power universal_power *
  page188_i52
#CELL
  pure_quanta q_res *
  page188_i57
#ISCELL
  standard offpage *
  page188_i59
#ISCELL
  logical_power universal_power *
  page188_i60
#ISCELL
  logical_power universal_gnd *
  page188_i62
#CELL
  pure_quanta q_res *
  page188_i63
#CELL
  pure_quanta q_res *
  page188_i64
#ISCELL
  standard offpage *
  page188_i66
#ISCELL
  logical_power universal_power *
  page188_i67
#ISCELL
  logical_power universal_gnd *
  page188_i69
#CELL
  pure_quanta q_res *
  page188_i70
#CELL
  pure_quanta q_res *
  page188_i71
#ISCELL
  standard offpage *
  page188_i72
#ISCELL
  logical_power universal_power *
  page188_i73
#ISCELL
  logical_power universal_gnd *
  page188_i75
#CELL
  pure_quanta q_res *
  page188_i76
#CELL
  pure_quanta q_res *
  page188_i77
#ISCELL
  logical_power design_note *
  *
#ISCELL
  pure_quanta quanta_title_block_c *
  *
#CELL
  pure_quanta q_res *
  page189_i100
#ISCELL
  standard offpage *
  page189_i101
#ISCELL
  standard offpage *
  page189_i102
#ISCELL
  standard offpage *
  page189_i103
#ISCELL
  standard offpage *
  page189_i104
#ISCELL
  logical_power universal_gnd *
  page189_i105
#CELL
  pure_quanta q_res *
  page189_i106
#CELL
  pure_quanta q_res *
  page189_i107
#ISCELL
  logical_power universal_gnd *
  page189_i108
#CELL
  pure_quanta q_res *
  page189_i109
#ISCELL
  logical_power universal_gnd *
  page189_i110
#ISCELL
  standard offpage *
  page189_i111
#ISCELL
  logical_power universal_power *
  page189_i112
#CELL
  pure_quanta q_res *
  page189_i113
#CELL
  pure_quanta q_res *
  page189_i114
#CELL
  pure_quanta sw_pushbutton4p_24 *
  page189_i122
#CELL
  pure_quanta q_res *
  page189_i123
#ISCELL
  logical_power universal_gnd *
  page189_i124
#ISCELL
  standard offpage *
  page189_i125
#ISCELL
  logical_power universal_power *
  page189_i126
#CELL
  pure_quanta q_res *
  page189_i127
#CELL
  pure_quanta q_cap *
  page189_i128
#ISCELL
  logical_power universal_gnd *
  page189_i129
#ISCELL
  standard offpage *
  page189_i130
#ISCELL
  standard offpage *
  page189_i131
#CELL
  pure_quanta q_res *
  page189_i132
#CELL
  pure_quanta q_res *
  page189_i133
#CELL
  pure_quanta conn14_210hp207gbr1 *
  page189_i134
#CELL
  pure_quanta q_res *
  page189_i86
#CELL
  pure_quanta q_res *
  page189_i87
#CELL
  pure_quanta q_res *
  page189_i88
#CELL
  pure_quanta q_res *
  page189_i89
#ISCELL
  logical_power universal_power *
  page189_i90
#ISCELL
  logical_power universal_power *
  page189_i92
#CELL
  pure_quanta q_res *
  page189_i93
#ISCELL
  logical_power universal_gnd *
  page189_i98
#ISCELL
  logical_power universal_power *
  page189_i99
#ISCELL
  logical_power design_note *
  *
#ISCELL
  mstr_misc dns *
  *
#ISCELL
  pure_quanta quanta_title_block_c *
  *
#ISCELL
  standard offpage *
  page190_i10
#CELL
  pure_quanta q_res *
  page190_i100
#CELL
  pure_quanta q_res *
  page190_i101
#CELL
  pure_quanta q_res *
  page190_i102
#ISCELL
  standard offpage *
  page190_i103
#CELL
  pure_quanta q_res *
  page190_i105
#ISCELL
  standard offpage *
  page190_i11
#ISCELL
  standard offpage *
  page190_i12
#ISCELL
  standard offpage *
  page190_i14
#ISCELL
  standard offpage *
  page190_i15
#ISCELL
  standard offpage *
  page190_i18
#ISCELL
  logical_power universal_gnd *
  page190_i20
#ISCELL
  logical_power universal_gnd *
  page190_i21
#ISCELL
  logical_power universal_power *
  page190_i24
#ISCELL
  standard offpage *
  page190_i32
#CELL
  pure_quanta q_res *
  page190_i33
#CELL
  pure_quanta nc7sb3157 *
  page190_i34
#CELL
  pure_quanta q_cap *
  page190_i36
#CELL
  pure_quanta q_cap *
  page190_i37
#CELL
  pure_quanta q_res *
  page190_i38
#CELL
  pure_quanta nc7sb3157 *
  page190_i39
#ISCELL
  logical_power universal_gnd *
  page190_i40
#ISCELL
  standard offpage *
  page190_i41
#CELL
  pure_quanta q_cap *
  page190_i43
#ISCELL
  logical_power universal_power *
  page190_i44
#CELL
  pure_quanta q_cap *
  page190_i45
#ISCELL
  logical_power universal_gnd *
  page190_i46
#ISCELL
  standard offpage *
  page190_i48
#ISCELL
  standard offpage *
  page190_i5
#ISCELL
  standard offpage *
  page190_i50
#ISCELL
  standard offpage *
  page190_i51
#ISCELL
  standard offpage *
  page190_i53
#CELL
  pure_quanta q_res *
  page190_i54
#ISCELL
  standard offpage *
  page190_i6
#ISCELL
  standard offpage *
  page190_i7
#CELL
  pure_quanta q_res *
  page190_i70
#ISCELL
  logical_power universal_power *
  page190_i71
#ISCELL
  standard offpage *
  page190_i79
#ISCELL
  standard offpage *
  page190_i8
#ISCELL
  standard offpage *
  page190_i81
#ISCELL
  standard offpage *
  page190_i82
#ISCELL
  logical_power universal_gnd *
  page190_i83
#CELL
  pure_quanta q_cap *
  page190_i84
#ISCELL
  logical_power universal_gnd *
  page190_i85
#ISCELL
  logical_power universal_power *
  page190_i86
#CELL
  pure_quanta q_res *
  page190_i87
#ISCELL
  logical_power universal_power *
  page190_i88
#CELL
  pure_quanta q_res *
  page190_i89
#ISCELL
  standard offpage *
  page190_i9
#ISCELL
  logical_power universal_gnd *
  page190_i90
#CELL
  pure_quanta q_res *
  page190_i91
#ISCELL
  standard offpage *
  page190_i92
#ISCELL
  logical_power universal_power *
  page190_i93
#CELL
  pure_quanta q_res *
  page190_i94
#CELL
  pure_quanta 74lvc1g07se7 *
  page190_i95
#CELL
  pure_quanta q_res *
  page190_i96
#CELL
  pure_quanta q_res *
  page190_i97
#CELL
  pure_quanta q_res *
  page190_i98
#CELL
  pure_quanta q_res *
  page190_i99
#ISCELL
  pure_quanta quanta_title_block_c *
  *
#ISCELL
  standard offpage *
  page191_i1
#ISCELL
  standard offpage *
  page191_i10
#CELL
  pure_quanta q_res *
  page191_i14
#CELL
  pure_quanta q_res *
  page191_i2
#ISCELL
  standard offpage *
  page191_i22
#ISCELL
  standard offpage *
  page191_i28
#CELL
  pure_quanta q_res *
  page191_i29
#ISCELL
  standard offpage *
  page191_i30
#ISCELL
  logical_power universal_power *
  page191_i34
#CELL
  pure_quanta q_res *
  page191_i35
#ISCELL
  logical_power universal_power *
  page191_i37
#CELL
  pure_quanta q_res *
  page191_i38
#ISCELL
  standard offpage *
  page191_i6
#ISCELL
  mstr_misc dns *
  *
#ISCELL
  pure_quanta quanta_title_block_c *
  *
#CELL
  pure_quanta q_res *
  page192_i1
#CELL
  pure_quanta q_res *
  page192_i11
#ISCELL
  logical_power universal_power *
  page192_i12
#ISCELL
  standard offpage *
  page192_i13
#ISCELL
  standard offpage *
  page192_i14
#ISCELL
  standard offpage *
  page192_i16
#CELL
  pure_quanta q_res *
  page192_i17
#CELL
  pure_quanta q_res *
  page192_i18
#ISCELL
  logical_power universal_power *
  page192_i2
#CELL
  pure_quanta q_res *
  page192_i23
#CELL
  pure_quanta q_res *
  page192_i24
#ISCELL
  logical_power universal_power *
  page192_i25
#CELL
  pure_quanta q_res *
  page192_i26
#ISCELL
  standard offpage *
  page192_i28
#ISCELL
  standard offpage *
  page192_i29
#ISCELL
  standard offpage *
  page192_i3
#ISCELL
  standard offpage *
  page192_i30
#ISCELL
  standard offpage *
  page192_i33
#ISCELL
  standard offpage *
  page192_i34
#ISCELL
  logical_power universal_power *
  page192_i39
#CELL
  pure_quanta q_res *
  page192_i4
#CELL
  pure_quanta q_res *
  page192_i41
#CELL
  pure_quanta q_res *
  page192_i42
#ISCELL
  standard offpage *
  page192_i44
#ISCELL
  standard offpage *
  page192_i45
#ISCELL
  logical_power universal_power *
  page192_i49
#ISCELL
  standard offpage *
  page192_i5
#CELL
  pure_quanta q_res *
  page192_i50
#CELL
  pure_quanta q_res *
  page192_i51
#ISCELL
  standard offpage *
  page192_i53
#ISCELL
  standard offpage *
  page192_i54
#ISCELL
  logical_power universal_power *
  page192_i58
#CELL
  pure_quanta q_res *
  page192_i59
#CELL
  pure_quanta q_res *
  page192_i6
#CELL
  pure_quanta q_res *
  page192_i60
#ISCELL
  standard offpage *
  page192_i61
#CELL
  pure_quanta q_res *
  page192_i62
#ISCELL
  standard offpage *
  page192_i64
#ISCELL
  logical_power universal_power *
  page192_i65
#CELL
  pure_quanta q_res *
  page192_i66
#ISCELL
  logical_power universal_power *
  page192_i67
#ISCELL
  standard offpage *
  page192_i68
#CELL
  pure_quanta q_res *
  page192_i69
#ISCELL
  standard offpage *
  page192_i7
#ISCELL
  standard offpage *
  page192_i71
#CELL
  pure_quanta q_res *
  page192_i72
#ISCELL
  standard offpage *
  page192_i74
#CELL
  pure_quanta q_res *
  page192_i75
#CELL
  pure_quanta q_res *
  page192_i8
#ISCELL
  standard offpage *
  page192_i9
#ISCELL
  pure_quanta quanta_title_block_c *
  *
#ISCELL
  standard offpage *
  page193_i1
#CELL
  pure_quanta q_res *
  page193_i10
#ISCELL
  standard offpage *
  page193_i12
#CELL
  pure_quanta q_res *
  page193_i13
#ISCELL
  standard offpage *
  page193_i14
#ISCELL
  standard offpage *
  page193_i18
#ISCELL
  standard offpage *
  page193_i19
#ISCELL
  standard offpage *
  page193_i2
#CELL
  pure_quanta q_res *
  page193_i20
#CELL
  pure_quanta q_res *
  page193_i21
#ISCELL
  standard offpage *
  page193_i22
#ISCELL
  standard offpage *
  page193_i23
#ISCELL
  standard offpage *
  page193_i25
#ISCELL
  standard offpage *
  page193_i26
#CELL
  pure_quanta q_res *
  page193_i27
#CELL
  pure_quanta q_res *
  page193_i28
#ISCELL
  standard offpage *
  page193_i29
#CELL
  pure_quanta q_res *
  page193_i3
#ISCELL
  standard offpage *
  page193_i30
#CELL
  pure_quanta q_res *
  page193_i32
#ISCELL
  standard offpage *
  page193_i36
#ISCELL
  standard offpage *
  page193_i37
#ISCELL
  standard offpage *
  page193_i38
#ISCELL
  standard offpage *
  page193_i39
#ISCELL
  standard offpage *
  page193_i4
#CELL
  pure_quanta q_res *
  page193_i40
#ISCELL
  standard offpage *
  page193_i41
#CELL
  pure_quanta q_res *
  page193_i5
#ISCELL
  standard offpage *
  page193_i6
#ISCELL
  logical_power design_note *
  *
#ISCELL
  mstr_misc dns *
  *
#ISCELL
  pure_quanta quanta_title_block_c *
  *
#CELL
  pure_quanta 9qxl2001bnhgi8 *
  page195_i119
#ISCELL
  standard offpage *
  page195_i120
#ISCELL
  standard offpage *
  page195_i121
#ISCELL
  standard offpage *
  page195_i122
#ISCELL
  standard offpage *
  page195_i123
#ISCELL
  standard offpage *
  page195_i126
#ISCELL
  standard offpage *
  page195_i127
#ISCELL
  standard offpage *
  page195_i128
#ISCELL
  standard offpage *
  page195_i129
#ISCELL
  standard offpage *
  page195_i150
#ISCELL
  standard offpage *
  page195_i151
#ISCELL
  standard offpage *
  page195_i154
#CELL
  pure_quanta q_res *
  page195_i156
#ISCELL
  standard offpage *
  page195_i157
#ISCELL
  logical_power universal_power *
  page195_i158
#ISCELL
  logical_power universal_power *
  page195_i159
#ISCELL
  logical_power universal_power *
  page195_i160
#ISCELL
  logical_power universal_power *
  page195_i161
#CELL
  pure_quanta q_res *
  page195_i162
#CELL
  pure_quanta q_res *
  page195_i163
#CELL
  pure_quanta q_cap *
  page195_i164
#CELL
  pure_quanta q_cap *
  page195_i165
#ISCELL
  logical_power universal_power *
  page195_i166
#CELL
  pure_quanta q_cap *
  page195_i167
#CELL
  pure_quanta q_cap *
  page195_i168
#ISCELL
  logical_power universal_power *
  page195_i169
#CELL
  pure_quanta q_inductor *
  page195_i170
#CELL
  pure_quanta q_cap *
  page195_i171
#CELL
  pure_quanta q_cap *
  page195_i172
#CELL
  pure_quanta q_cap *
  page195_i173
#CELL
  pure_quanta q_cap *
  page195_i174
#ISCELL
  logical_power universal_power *
  page195_i175
#ISCELL
  logical_power universal_power *
  page195_i176
#CELL
  pure_quanta q_inductor *
  page195_i177
#CELL
  pure_quanta q_res *
  page195_i178
#CELL
  pure_quanta q_res *
  page195_i179
#ISCELL
  logical_power universal_power *
  page195_i183
#CELL
  pure_quanta q_res *
  page195_i185
#CELL
  pure_quanta q_res *
  page195_i187
#ISCELL
  standard offpage *
  page195_i188
#ISCELL
  standard offpage *
  page195_i189
#ISCELL
  standard offpage *
  page195_i190
#ISCELL
  standard offpage *
  page195_i191
#ISCELL
  standard offpage *
  page195_i192
#CELL
  pure_quanta q_res *
  page195_i194
#ISCELL
  logical_power universal_power *
  page195_i195
#CELL
  pure_quanta q_res *
  page195_i197
#CELL
  pure_quanta q_res *
  page195_i199
#ISCELL
  standard offpage *
  page195_i200
#CELL
  pure_quanta q_res *
  page195_i304
#ISCELL
  standard offpage *
  page195_i381
#ISCELL
  standard offpage *
  page195_i382
#ISCELL
  standard offpage *
  page195_i383
#ISCELL
  standard offpage *
  page195_i384
#ISCELL
  standard offpage *
  page195_i385
#ISCELL
  standard offpage *
  page195_i386
#ISCELL
  standard offpage *
  page195_i387
#ISCELL
  standard offpage *
  page195_i388
#ISCELL
  standard offpage *
  page195_i409
#ISCELL
  standard offpage *
  page195_i410
#CELL
  pure_quanta q_cap *
  page195_i419
#ISCELL
  logical_power universal_gnd *
  page195_i432
#ISCELL
  logical_power universal_gnd *
  page195_i433
#ISCELL
  logical_power universal_gnd *
  page195_i434
#ISCELL
  logical_power universal_gnd *
  page195_i435
#ISCELL
  logical_power universal_gnd *
  page195_i436
#ISCELL
  logical_power universal_gnd *
  page195_i437
#ISCELL
  logical_power universal_gnd *
  page195_i438
#ISCELL
  logical_power universal_gnd *
  page195_i439
#CELL
  pure_quanta q_res *
  page195_i487
#ISCELL
  standard offpage *
  page195_i488
#ISCELL
  standard offpage *
  page195_i502
#ISCELL
  standard offpage *
  page195_i503
#ISCELL
  standard offpage *
  page195_i504
#ISCELL
  standard offpage *
  page195_i505
#ISCELL
  standard offpage *
  page195_i506
#ISCELL
  standard offpage *
  page195_i507
#ISCELL
  standard offpage *
  page195_i508
#ISCELL
  standard offpage *
  page195_i509
#ISCELL
  standard offpage *
  page195_i519
#ISCELL
  standard offpage *
  page195_i520
#ISCELL
  standard offpage *
  page195_i523
#ISCELL
  standard offpage *
  page195_i524
#ISCELL
  standard offpage *
  page195_i525
#ISCELL
  standard offpage *
  page195_i528
#ISCELL
  standard offpage *
  page195_i529
#ISCELL
  standard offpage *
  page195_i530
#ISCELL
  standard offpage *
  page195_i531
#ISCELL
  standard offpage *
  page195_i532
#CELL
  pure_quanta q_res *
  page195_i534
#CELL
  pure_quanta q_res *
  page195_i535
#CELL
  pure_quanta q_res *
  page195_i536
#CELL
  pure_quanta q_res *
  page195_i537
#ISCELL
  standard offpage *
  page195_i538
#CELL
  pure_quanta q_res *
  page195_i539
#CELL
  pure_quanta q_res *
  page195_i540
#ISCELL
  logical_power universal_power *
  page195_i541
#ISCELL
  pure_quanta quanta_title_block_c *
  *
#ISCELL
  standard offpage *
  page196_i1
#CELL
  pure_quanta q_res *
  page196_i10
#CELL
  pure_quanta q_res *
  page196_i11
#CELL
  pure_quanta q_res *
  page196_i12
#CELL
  pure_quanta q_res *
  page196_i13
#CELL
  pure_quanta q_res *
  page196_i14
#CELL
  pure_quanta q_res *
  page196_i15
#CELL
  pure_quanta q_res *
  page196_i16
#CELL
  pure_quanta q_res *
  page196_i17
#CELL
  pure_quanta q_res *
  page196_i18
#ISCELL
  standard offpage *
  page196_i19
#ISCELL
  standard offpage *
  page196_i2
#ISCELL
  standard offpage *
  page196_i20
#ISCELL
  standard offpage *
  page196_i21
#ISCELL
  standard offpage *
  page196_i22
#ISCELL
  standard offpage *
  page196_i23
#CELL
  pure_quanta q_res *
  page196_i24
#CELL
  pure_quanta q_res *
  page196_i25
#CELL
  pure_quanta q_res *
  page196_i26
#CELL
  pure_quanta q_res *
  page196_i27
#CELL
  pure_quanta q_res *
  page196_i28
#ISCELL
  standard offpage *
  page196_i29
#ISCELL
  standard offpage *
  page196_i3
#ISCELL
  standard offpage *
  page196_i30
#ISCELL
  standard offpage *
  page196_i31
#ISCELL
  standard offpage *
  page196_i32
#ISCELL
  standard offpage *
  page196_i33
#ISCELL
  standard offpage *
  page196_i34
#ISCELL
  standard offpage *
  page196_i35
#ISCELL
  standard offpage *
  page196_i36
#ISCELL
  standard offpage *
  page196_i37
#ISCELL
  standard offpage *
  page196_i38
#ISCELL
  standard offpage *
  page196_i39
#ISCELL
  standard offpage *
  page196_i4
#ISCELL
  standard offpage *
  page196_i40
#ISCELL
  standard offpage *
  page196_i41
#ISCELL
  standard offpage *
  page196_i42
#ISCELL
  standard offpage *
  page196_i5
#ISCELL
  standard offpage *
  page196_i6
#ISCELL
  standard offpage *
  page196_i7
#ISCELL
  standard offpage *
  page196_i8
#ISCELL
  standard offpage *
  page196_i9
#ISCELL
  logical_power design_note *
  *
#ISCELL
  mstr_misc dns *
  *
#ISCELL
  pure_quanta quanta_title_block_c *
  *
#ISCELL
  standard offpage *
  page197_i100
#ISCELL
  standard offpage *
  page197_i112
#ISCELL
  standard offpage *
  page197_i113
#ISCELL
  standard offpage *
  page197_i115
#ISCELL
  standard offpage *
  page197_i116
#ISCELL
  standard offpage *
  page197_i119
#ISCELL
  standard offpage *
  page197_i120
#ISCELL
  logical_power universal_power *
  page197_i157
#ISCELL
  logical_power universal_power *
  page197_i158
#ISCELL
  logical_power universal_power *
  page197_i159
#ISCELL
  logical_power universal_power *
  page197_i160
#ISCELL
  logical_power universal_power *
  page197_i161
#ISCELL
  logical_power universal_power *
  page197_i162
#ISCELL
  standard offpage *
  page197_i163
#ISCELL
  standard offpage *
  page197_i164
#ISCELL
  standard offpage *
  page197_i165
#ISCELL
  standard offpage *
  page197_i167
#ISCELL
  standard offpage *
  page197_i168
#ISCELL
  standard offpage *
  page197_i170
#ISCELL
  standard offpage *
  page197_i171
#ISCELL
  standard offpage *
  page197_i172
#CELL
  pure_quanta 9sq440nqqi8 *
  page197_i180
#ISCELL
  standard offpage *
  page197_i182
#ISCELL
  standard offpage *
  page197_i206
#ISCELL
  standard offpage *
  page197_i207
#ISCELL
  standard offpage *
  page197_i242
#CELL
  pure_quanta q_res *
  page197_i252
#ISCELL
  standard offpage *
  page197_i253
#ISCELL
  standard offpage *
  page197_i254
#ISCELL
  standard offpage *
  page197_i255
#ISCELL
  standard offpage *
  page197_i256
#ISCELL
  standard offpage *
  page197_i257
#ISCELL
  standard offpage *
  page197_i258
#ISCELL
  standard offpage *
  page197_i259
#ISCELL
  standard offpage *
  page197_i260
#ISCELL
  standard offpage *
  page197_i261
#ISCELL
  standard offpage *
  page197_i262
#ISCELL
  standard offpage *
  page197_i263
#ISCELL
  standard offpage *
  page197_i264
#CELL
  pure_quanta q_res *
  page197_i265
#CELL
  pure_quanta q_res *
  page197_i267
#CELL
  pure_quanta q_res *
  page197_i268
#CELL
  pure_quanta q_res *
  page197_i269
#CELL
  pure_quanta q_res *
  page197_i270
#CELL
  pure_quanta q_res *
  page197_i271
#CELL
  pure_quanta q_res *
  page197_i272
#CELL
  pure_quanta q_res *
  page197_i273
#CELL
  pure_quanta q_res *
  page197_i274
#CELL
  pure_quanta q_res *
  page197_i275
#CELL
  pure_quanta q_res *
  page197_i276
#CELL
  pure_quanta q_res *
  page197_i277
#CELL
  pure_quanta q_res *
  page197_i278
#ISCELL
  logical_power universal_power *
  page197_i279
#CELL
  pure_quanta q_res *
  page197_i280
#CELL
  pure_quanta q_res *
  page197_i281
#CELL
  pure_quanta q_res *
  page197_i282
#CELL
  pure_quanta q_res *
  page197_i283
#ISCELL
  logical_power universal_gnd *
  page197_i285
#CELL
  pure_quanta q_cap *
  page197_i286
#CELL
  pure_quanta 9sq440nqqi8 *
  page197_i288
#ISCELL
  logical_power universal_gnd *
  page197_i294
#ISCELL
  logical_power universal_gnd *
  page197_i295
#ISCELL
  logical_power universal_gnd *
  page197_i301
#ISCELL
  logical_power universal_gnd *
  page197_i302
#CELL
  pure_quanta q_res *
  page197_i303
#ISCELL
  logical_power universal_power *
  page197_i304
#ISCELL
  standard offpage *
  page197_i330
#CELL
  pure_quanta q_res *
  page197_i378
#CELL
  pure_quanta q_res *
  page197_i379
#CELL
  pure_quanta q_res *
  page197_i380
#CELL
  pure_quanta q_res *
  page197_i381
#CELL
  pure_quanta q_res *
  page197_i382
#CELL
  pure_quanta q_res *
  page197_i383
#ISCELL
  logical_power universal_power *
  page197_i385
#CELL
  pure_quanta q_xtal_4p_13bi_24gnd *
  page197_i391
#CELL
  pure_quanta q_res *
  page197_i392
#CELL
  pure_quanta q_cap *
  page197_i393
#CELL
  pure_quanta q_cap *
  page197_i394
#ISCELL
  standard offpage *
  page197_i99
#ISCELL
  mstr_misc dns *
  *
#ISCELL
  pure_quanta quanta_title_block_c *
  *
#ISCELL
  standard offpage *
  page198_i1
#CELL
  pure_quanta q_res *
  page198_i10
#CELL
  pure_quanta q_res *
  page198_i11
#CELL
  pure_quanta q_res *
  page198_i12
#ISCELL
  standard offpage *
  page198_i13
#ISCELL
  standard offpage *
  page198_i14
#ISCELL
  standard offpage *
  page198_i15
#ISCELL
  standard offpage *
  page198_i16
#ISCELL
  standard offpage *
  page198_i17
#ISCELL
  standard offpage *
  page198_i18
#CELL
  pure_quanta q_res *
  page198_i19
#ISCELL
  standard offpage *
  page198_i2
#CELL
  pure_quanta q_res *
  page198_i20
#CELL
  pure_quanta q_res *
  page198_i21
#CELL
  pure_quanta q_res *
  page198_i22
#CELL
  pure_quanta q_res *
  page198_i23
#CELL
  pure_quanta q_res *
  page198_i24
#ISCELL
  standard offpage *
  page198_i25
#ISCELL
  standard offpage *
  page198_i26
#CELL
  pure_quanta q_res *
  page198_i27
#CELL
  pure_quanta q_res *
  page198_i28
#CELL
  pure_quanta q_res *
  page198_i29
#ISCELL
  standard offpage *
  page198_i3
#CELL
  pure_quanta q_res *
  page198_i30
#ISCELL
  standard offpage *
  page198_i31
#ISCELL
  standard offpage *
  page198_i32
#ISCELL
  standard offpage *
  page198_i33
#ISCELL
  standard offpage *
  page198_i34
#ISCELL
  standard offpage *
  page198_i35
#ISCELL
  standard offpage *
  page198_i36
#ISCELL
  standard offpage *
  page198_i37
#ISCELL
  standard offpage *
  page198_i38
#ISCELL
  standard offpage *
  page198_i39
#ISCELL
  standard offpage *
  page198_i4
#ISCELL
  standard offpage *
  page198_i40
#ISCELL
  standard offpage *
  page198_i41
#ISCELL
  standard offpage *
  page198_i42
#CELL
  pure_quanta q_res *
  page198_i43
#CELL
  pure_quanta q_res *
  page198_i44
#CELL
  pure_quanta q_res *
  page198_i45
#CELL
  pure_quanta q_res *
  page198_i46
#CELL
  pure_quanta q_res *
  page198_i47
#CELL
  pure_quanta q_res *
  page198_i48
#ISCELL
  standard offpage *
  page198_i49
#ISCELL
  standard offpage *
  page198_i5
#ISCELL
  standard offpage *
  page198_i50
#ISCELL
  standard offpage *
  page198_i51
#ISCELL
  standard offpage *
  page198_i52
#ISCELL
  standard offpage *
  page198_i53
#ISCELL
  standard offpage *
  page198_i54
#ISCELL
  standard offpage *
  page198_i55
#ISCELL
  standard offpage *
  page198_i56
#CELL
  pure_quanta q_res *
  page198_i57
#CELL
  pure_quanta q_res *
  page198_i58
#ISCELL
  standard offpage *
  page198_i59
#ISCELL
  standard offpage *
  page198_i6
#ISCELL
  standard offpage *
  page198_i60
#CELL
  pure_quanta q_res *
  page198_i7
#CELL
  pure_quanta q_res *
  page198_i8
#CELL
  pure_quanta q_res *
  page198_i9
#ISCELL
  logical_power cad_note *
  *
#ISCELL
  pure_quanta quanta_title_block_c *
  *
#CELL
  pure_quanta q_cap *
  page199_i19
#CELL
  pure_quanta q_inductor *
  page199_i20
#ISCELL
  logical_power universal_power *
  page199_i21
#ISCELL
  logical_power universal_power *
  page199_i3
#ISCELL
  logical_power universal_power *
  page199_i31
#ISCELL
  logical_power universal_power *
  page199_i35
#CELL
  pure_quanta q_res *
  page199_i36
#CELL
  pure_quanta q_inductor *
  page199_i41
#ISCELL
  logical_power universal_power *
  page199_i42
#CELL
  pure_quanta q_cap *
  page199_i43
#CELL
  pure_quanta q_cap *
  page199_i44
#CELL
  pure_quanta q_cap *
  page199_i48
#ISCELL
  logical_power universal_power *
  page199_i51
#CELL
  pure_quanta q_cap *
  page199_i53
#CELL
  pure_quanta q_res *
  page199_i55
#ISCELL
  logical_power universal_power *
  page199_i56
#CELL
  pure_quanta q_cap *
  page199_i58
#CELL
  pure_quanta q_cap *
  page199_i59
#CELL
  pure_quanta q_cap *
  page199_i6
#CELL
  pure_quanta q_inductor *
  page199_i60
#ISCELL
  logical_power universal_power *
  page199_i61
#ISCELL
  logical_power universal_gnd *
  page199_i69
#CELL
  pure_quanta q_res *
  page199_i7
#ISCELL
  logical_power universal_gnd *
  page199_i70
#ISCELL
  logical_power universal_gnd *
  page199_i71
#ISCELL
  logical_power universal_gnd *
  page199_i72
#ISCELL
  logical_power universal_gnd *
  page199_i73
#ISCELL
  logical_power universal_gnd *
  page199_i74
#CELL
  pure_quanta q_cap *
  page199_i76
#CELL
  pure_quanta q_cap *
  page199_i77
#CELL
  pure_quanta q_cap *
  page199_i78
#CELL
  pure_quanta q_cap *
  page199_i79
#ISCELL
  logical_power universal_power *
  page199_i8
#CELL
  pure_quanta q_cap *
  page199_i80
#CELL
  pure_quanta q_cap *
  page199_i81
#CELL
  pure_quanta q_cap *
  page199_i82
#CELL
  pure_quanta q_cap *
  page199_i85
#CELL
  pure_quanta q_cap *
  page199_i86
#CELL
  pure_quanta q_cap *
  page199_i87
#CELL
  pure_quanta q_cap *
  page199_i88
#CELL
  pure_quanta q_cap *
  page199_i89
#ISCELL
  mstr_misc dns *
  *
#ISCELL
  pure_quanta quanta_title_block_c *
  *
#CELL
  pure_quanta 9zxl0451ekilft *
  page200_i1
#CELL
  pure_quanta q_cap *
  page200_i10
#CELL
  pure_quanta q_res *
  page200_i11
#ISCELL
  logical_power universal_gnd *
  page200_i12
#CELL
  pure_quanta q_cap *
  page200_i17
#ISCELL
  logical_power universal_gnd *
  page200_i21
#ISCELL
  logical_power universal_gnd *
  page200_i22
#ISCELL
  logical_power universal_power *
  page200_i23
#ISCELL
  logical_power universal_power *
  page200_i24
#ISCELL
  logical_power universal_power *
  page200_i25
#ISCELL
  logical_power universal_power *
  page200_i26
#ISCELL
  logical_power universal_power *
  page200_i27
#ISCELL
  logical_power universal_power *
  page200_i28
#ISCELL
  logical_power universal_power *
  page200_i29
#CELL
  pure_quanta q_res *
  page200_i30
#CELL
  pure_quanta q_res *
  page200_i31
#ISCELL
  logical_power universal_power *
  page200_i32
#ISCELL
  logical_power universal_gnd *
  page200_i33
#ISCELL
  standard offpage *
  page200_i34
#ISCELL
  standard offpage *
  page200_i35
#ISCELL
  standard offpage *
  page200_i36
#ISCELL
  standard offpage *
  page200_i37
#ISCELL
  standard offpage *
  page200_i38
#CELL
  pure_quanta q_res *
  page200_i39
#CELL
  pure_quanta q_res *
  page200_i4
#ISCELL
  standard offpage *
  page200_i40
#ISCELL
  standard offpage *
  page200_i41
#ISCELL
  standard offpage *
  page200_i42
#ISCELL
  standard offpage *
  page200_i43
#ISCELL
  standard offpage *
  page200_i44
#ISCELL
  standard offpage *
  page200_i45
#CELL
  pure_quanta q_res *
  page200_i48
#CELL
  pure_quanta q_res *
  page200_i49
#CELL
  pure_quanta q_cap *
  page200_i5
#ISCELL
  logical_power universal_power *
  page200_i50
#ISCELL
  logical_power universal_gnd *
  page200_i51
#ISCELL
  standard offpage *
  page200_i52
#ISCELL
  standard offpage *
  page200_i53
#CELL
  pure_quanta q_cap *
  page200_i54
#CELL
  pure_quanta q_cap *
  page200_i55
#CELL
  pure_quanta q_cap *
  page200_i56
#CELL
  pure_quanta q_cap *
  page200_i57
#CELL
  pure_quanta q_cap *
  page200_i58
#CELL
  pure_quanta q_cap *
  page200_i59
#ISCELL
  standard offpage *
  page200_i62
#ISCELL
  standard offpage *
  page200_i63
#ISCELL
  standard offpage *
  page200_i66
#CELL
  pure_quanta q_res *
  page200_i69
#ISCELL
  logical_power universal_power *
  page200_i7
#ISCELL
  logical_power universal_power *
  page200_i70
#CELL
  pure_quanta q_cap *
  page200_i71
#ISCELL
  standard offpage *
  page200_i72
#ISCELL
  standard offpage *
  page200_i73
#CELL
  pure_quanta q_res *
  page200_i74
#CELL
  pure_quanta q_res *
  page200_i75
#CELL
  pure_quanta q_res *
  page200_i76
#CELL
  pure_quanta q_res *
  page200_i77
#CELL
  pure_quanta q_res *
  page200_i78
#CELL
  pure_quanta q_res *
  page200_i79
#ISCELL
  logical_power universal_gnd *
  page200_i8
#ISCELL
  logical_power universal_power *
  page200_i80
#CELL
  pure_quanta q_inductor *
  page200_i81
#CELL
  pure_quanta q_inductor *
  page200_i82
#ISCELL
  logical_power design_note *
  *
#ISCELL
  mstr_misc dns *
  *
#ISCELL
  pure_quanta quanta_title_block_c *
  *
#CELL
  pure_quanta q_res *
  page201_i102
#CELL
  pure_quanta q_cap *
  page201_i103
#CELL
  pure_quanta q_cap *
  page201_i104
#CELL
  pure_quanta q_cap *
  page201_i105
#CELL
  pure_quanta q_cap *
  page201_i106
#ISCELL
  logical_power universal_gnd *
  page201_i107
#ISCELL
  logical_power universal_power *
  page201_i108
#ISCELL
  logical_power universal_power *
  page201_i109
#ISCELL
  logical_power universal_power *
  page201_i110
#ISCELL
  logical_power universal_power *
  page201_i111
#ISCELL
  logical_power universal_gnd *
  page201_i113
#ISCELL
  logical_power universal_gnd *
  page201_i115
#ISCELL
  logical_power universal_gnd *
  page201_i116
#ISCELL
  logical_power universal_gnd *
  page201_i117
#ISCELL
  standard offpage *
  page201_i125
#ISCELL
  standard offpage *
  page201_i126
#CELL
  pure_quanta q_res *
  page201_i127
#CELL
  pure_quanta q_res *
  page201_i128
#ISCELL
  standard offpage *
  page201_i129
#ISCELL
  logical_power universal_power *
  page201_i130
#ISCELL
  logical_power universal_gnd *
  page201_i133
#CELL
  pure_quanta q_res *
  page201_i134
#CELL
  pure_quanta q_res *
  page201_i135
#ISCELL
  standard offpage *
  page201_i139
#ISCELL
  standard offpage *
  page201_i140
#ISCELL
  logical_power universal_power *
  page201_i141
#CELL
  pure_quanta q_res *
  page201_i142
#CELL
  pure_quanta q_res *
  page201_i146
#CELL
  pure_quanta q_res *
  page201_i147
#ISCELL
  standard offpage *
  page201_i150
#ISCELL
  standard offpage *
  page201_i151
#ISCELL
  standard offpage *
  page201_i152
#ISCELL
  standard offpage *
  page201_i153
#ISCELL
  standard offpage *
  page201_i154
#CELL
  pure_quanta q_inductor *
  page201_i155
#ISCELL
  logical_power universal_power *
  page201_i156
#CELL
  pure_quanta q_res *
  page201_i157
#CELL
  pure_quanta 74lvc1g32gw *
  page201_i158
#CELL
  pure_quanta q_xtal_4p_13bi_24gnd *
  page201_i159
#CELL
  pure_quanta q_cap *
  page201_i16
#CELL
  pure_quanta q_res *
  page201_i160
#CELL
  pure_quanta q_res *
  page201_i161
#ISCELL
  logical_power universal_gnd *
  page201_i162
#CELL
  pure_quanta q_res *
  page201_i163
#ISCELL
  logical_power universal_power *
  page201_i164
#CELL
  pure_quanta q_cap *
  page201_i165
#CELL
  pure_quanta q_cap *
  page201_i166
#CELL
  pure_quanta 9fgl0251dkilft *
  page201_i167
#CELL
  pure_quanta q_cap *
  page201_i18
#CELL
  pure_quanta q_cap *
  page201_i19
#ISCELL
  logical_power universal_power *
  page201_i20
#ISCELL
  logical_power universal_gnd *
  page201_i21
#ISCELL
  logical_power universal_gnd *
  page201_i22
#ISCELL
  standard offpage *
  page201_i32
#ISCELL
  logical_power universal_power *
  page201_i33
#ISCELL
  logical_power universal_gnd *
  page201_i35
#CELL
  pure_quanta q_res *
  page201_i69
#ISCELL
  standard offpage *
  page201_i70
#ISCELL
  standard offpage *
  page201_i71
#ISCELL
  standard offpage *
  page201_i72
#ISCELL
  standard offpage *
  page201_i73
#CELL
  pure_quanta q_res *
  page201_i74
#CELL
  pure_quanta q_res *
  page201_i75
#CELL
  pure_quanta q_res *
  page201_i76
#ISCELL
  logical_power universal_power *
  page201_i79
#CELL
  pure_quanta q_cap *
  page201_i80
#ISCELL
  logical_power universal_gnd *
  page201_i81
#ISCELL
  logical_power universal_gnd *
  page201_i82
#CELL
  pure_quanta q_res *
  page201_i84
#CELL
  pure_quanta q_res *
  page201_i85
#ISCELL
  standard offpage *
  page201_i87
#ISCELL
  standard offpage *
  page201_i88
#ISCELL
  mstr_misc dns *
  *
#ISCELL
  pure_quanta quanta_title_block_c *
  *
#ISCELL
  standard offpage *
  page314_i1
#ISCELL
  standard offpage *
  page314_i10
#ISCELL
  standard offpage *
  page314_i100
#ISCELL
  standard offpage *
  page314_i101
#ISCELL
  standard offpage *
  page314_i102
#ISCELL
  standard offpage *
  page314_i103
#ISCELL
  standard offpage *
  page314_i104
#ISCELL
  standard offpage *
  page314_i105
#CELL
  pure_quanta q_res *
  page314_i106
#CELL
  pure_quanta q_res *
  page314_i107
#CELL
  pure_quanta q_res *
  page314_i108
#CELL
  pure_quanta q_res *
  page314_i109
#ISCELL
  standard offpage *
  page314_i11
#CELL
  pure_quanta q_res *
  page314_i110
#CELL
  pure_quanta q_res *
  page314_i111
#CELL
  pure_quanta q_res *
  page314_i112
#CELL
  pure_quanta q_res *
  page314_i113
#CELL
  pure_quanta q_res *
  page314_i114
#CELL
  pure_quanta q_res *
  page314_i115
#ISCELL
  standard offpage *
  page314_i116
#ISCELL
  standard offpage *
  page314_i117
#ISCELL
  standard offpage *
  page314_i118
#ISCELL
  standard offpage *
  page314_i119
#ISCELL
  standard offpage *
  page314_i12
#ISCELL
  standard offpage *
  page314_i120
#ISCELL
  standard offpage *
  page314_i121
#ISCELL
  standard offpage *
  page314_i122
#ISCELL
  standard offpage *
  page314_i123
#ISCELL
  standard offpage *
  page314_i124
#ISCELL
  standard offpage *
  page314_i125
#ISCELL
  standard offpage *
  page314_i126
#ISCELL
  standard offpage *
  page314_i127
#ISCELL
  standard offpage *
  page314_i128
#ISCELL
  standard offpage *
  page314_i129
#ISCELL
  standard offpage *
  page314_i13
#ISCELL
  standard offpage *
  page314_i130
#ISCELL
  standard offpage *
  page314_i131
#ISCELL
  standard offpage *
  page314_i132
#ISCELL
  standard offpage *
  page314_i133
#CELL
  pure_quanta q_res *
  page314_i134
#CELL
  pure_quanta q_res *
  page314_i135
#CELL
  pure_quanta q_res *
  page314_i136
#CELL
  pure_quanta q_res *
  page314_i137
#CELL
  pure_quanta q_res *
  page314_i138
#CELL
  pure_quanta q_res *
  page314_i139
#CELL
  pure_quanta q_res *
  page314_i14
#CELL
  pure_quanta q_res *
  page314_i140
#CELL
  pure_quanta q_res *
  page314_i141
#ISCELL
  standard offpage *
  page314_i142
#ISCELL
  standard offpage *
  page314_i143
#ISCELL
  standard offpage *
  page314_i144
#ISCELL
  standard offpage *
  page314_i145
#ISCELL
  standard offpage *
  page314_i146
#ISCELL
  standard offpage *
  page314_i147
#ISCELL
  standard offpage *
  page314_i148
#ISCELL
  standard offpage *
  page314_i149
#CELL
  pure_quanta q_res *
  page314_i15
#ISCELL
  standard offpage *
  page314_i150
#ISCELL
  standard offpage *
  page314_i151
#ISCELL
  standard offpage *
  page314_i152
#ISCELL
  standard offpage *
  page314_i153
#ISCELL
  standard offpage *
  page314_i154
#ISCELL
  standard offpage *
  page314_i155
#ISCELL
  standard offpage *
  page314_i156
#ISCELL
  standard offpage *
  page314_i157
#ISCELL
  standard offpage *
  page314_i158
#ISCELL
  standard offpage *
  page314_i159
#CELL
  pure_quanta q_res *
  page314_i16
#ISCELL
  standard offpage *
  page314_i160
#ISCELL
  standard offpage *
  page314_i161
#ISCELL
  standard offpage *
  page314_i162
#ISCELL
  standard offpage *
  page314_i163
#ISCELL
  standard offpage *
  page314_i164
#ISCELL
  standard offpage *
  page314_i165
#ISCELL
  standard offpage *
  page314_i166
#ISCELL
  standard offpage *
  page314_i167
#ISCELL
  standard offpage *
  page314_i168
#ISCELL
  standard offpage *
  page314_i169
#CELL
  pure_quanta q_res *
  page314_i17
#ISCELL
  standard offpage *
  page314_i170
#ISCELL
  standard offpage *
  page314_i171
#ISCELL
  standard offpage *
  page314_i172
#ISCELL
  standard offpage *
  page314_i173
#ISCELL
  standard offpage *
  page314_i174
#ISCELL
  standard offpage *
  page314_i175
#ISCELL
  standard offpage *
  page314_i176
#ISCELL
  standard offpage *
  page314_i177
#CELL
  pure_quanta q_res *
  page314_i178
#CELL
  pure_quanta q_res *
  page314_i179
#CELL
  pure_quanta q_res *
  page314_i18
#ISCELL
  logical_power universal_power *
  page314_i180
#ISCELL
  standard offpage *
  page314_i181
#ISCELL
  standard offpage *
  page314_i182
#ISCELL
  standard offpage *
  page314_i183
#ISCELL
  standard offpage *
  page314_i184
#ISCELL
  standard offpage *
  page314_i185
#ISCELL
  standard offpage *
  page314_i186
#ISCELL
  standard offpage *
  page314_i187
#CELL
  pure_quanta lcmxo3lf9400c5bg484c *
  page314_i188
#ISCELL
  standard offpage *
  page314_i189
#CELL
  pure_quanta q_res *
  page314_i19
#ISCELL
  standard offpage *
  page314_i190
#ISCELL
  standard offpage *
  page314_i193
#ISCELL
  standard offpage *
  page314_i194
#ISCELL
  standard offpage *
  page314_i195
#ISCELL
  standard offpage *
  page314_i196
#CELL
  pure_quanta q_res *
  page314_i197
#CELL
  pure_quanta q_res *
  page314_i198
#ISCELL
  standard offpage *
  page314_i2
#CELL
  pure_quanta q_res *
  page314_i20
#CELL
  pure_quanta q_res *
  page314_i21
#CELL
  pure_quanta q_res *
  page314_i22
#CELL
  pure_quanta q_res *
  page314_i23
#CELL
  pure_quanta q_res *
  page314_i24
#CELL
  pure_quanta q_res *
  page314_i25
#CELL
  pure_quanta q_res *
  page314_i26
#ISCELL
  standard offpage *
  page314_i27
#ISCELL
  standard offpage *
  page314_i28
#ISCELL
  standard offpage *
  page314_i29
#ISCELL
  standard offpage *
  page314_i3
#ISCELL
  standard offpage *
  page314_i30
#ISCELL
  standard offpage *
  page314_i31
#ISCELL
  standard offpage *
  page314_i32
#ISCELL
  standard offpage *
  page314_i33
#ISCELL
  standard offpage *
  page314_i34
#ISCELL
  standard offpage *
  page314_i35
#ISCELL
  standard offpage *
  page314_i36
#ISCELL
  standard offpage *
  page314_i37
#ISCELL
  standard offpage *
  page314_i38
#ISCELL
  standard offpage *
  page314_i39
#ISCELL
  standard offpage *
  page314_i4
#ISCELL
  standard offpage *
  page314_i40
#CELL
  pure_quanta q_res *
  page314_i41
#ISCELL
  logical_power universal_power *
  page314_i42
#CELL
  pure_quanta mosfet_nch_dual *
  page314_i43
#ISCELL
  logical_power universal_gnd *
  page314_i44
#CELL
  pure_quanta q_res *
  page314_i45
#ISCELL
  logical_power universal_power *
  page314_i46
#CELL
  pure_quanta q_res *
  page314_i47
#ISCELL
  logical_power universal_power *
  page314_i48
#CELL
  pure_quanta mosfet_nch_dual *
  page314_i49
#ISCELL
  standard offpage *
  page314_i5
#ISCELL
  logical_power universal_gnd *
  page314_i50
#CELL
  pure_quanta q_res *
  page314_i51
#ISCELL
  logical_power universal_power *
  page314_i52
#ISCELL
  standard offpage *
  page314_i53
#ISCELL
  standard offpage *
  page314_i54
#ISCELL
  standard offpage *
  page314_i55
#ISCELL
  standard offpage *
  page314_i56
#ISCELL
  standard offpage *
  page314_i57
#ISCELL
  standard offpage *
  page314_i58
#ISCELL
  standard offpage *
  page314_i59
#ISCELL
  standard offpage *
  page314_i6
#ISCELL
  standard offpage *
  page314_i60
#ISCELL
  standard offpage *
  page314_i61
#ISCELL
  standard offpage *
  page314_i62
#ISCELL
  standard offpage *
  page314_i63
#ISCELL
  standard offpage *
  page314_i64
#ISCELL
  standard offpage *
  page314_i65
#ISCELL
  standard offpage *
  page314_i66
#ISCELL
  standard offpage *
  page314_i67
#ISCELL
  standard offpage *
  page314_i68
#ISCELL
  standard offpage *
  page314_i69
#ISCELL
  standard offpage *
  page314_i7
#ISCELL
  standard offpage *
  page314_i70
#ISCELL
  standard offpage *
  page314_i71
#ISCELL
  standard offpage *
  page314_i72
#ISCELL
  standard offpage *
  page314_i73
#ISCELL
  standard offpage *
  page314_i74
#ISCELL
  standard offpage *
  page314_i75
#ISCELL
  standard offpage *
  page314_i76
#ISCELL
  standard offpage *
  page314_i77
#ISCELL
  standard offpage *
  page314_i78
#ISCELL
  standard offpage *
  page314_i79
#ISCELL
  standard offpage *
  page314_i8
#ISCELL
  standard offpage *
  page314_i80
#ISCELL
  standard offpage *
  page314_i81
#ISCELL
  standard offpage *
  page314_i82
#ISCELL
  standard offpage *
  page314_i83
#ISCELL
  standard offpage *
  page314_i84
#ISCELL
  standard offpage *
  page314_i85
#ISCELL
  standard offpage *
  page314_i86
#ISCELL
  standard offpage *
  page314_i87
#ISCELL
  standard offpage *
  page314_i88
#ISCELL
  standard offpage *
  page314_i89
#ISCELL
  standard offpage *
  page314_i9
#ISCELL
  standard offpage *
  page314_i90
#ISCELL
  standard offpage *
  page314_i91
#ISCELL
  standard offpage *
  page314_i92
#ISCELL
  standard offpage *
  page314_i93
#ISCELL
  standard offpage *
  page314_i94
#ISCELL
  standard offpage *
  page314_i95
#ISCELL
  standard offpage *
  page314_i96
#ISCELL
  standard offpage *
  page314_i97
#ISCELL
  standard offpage *
  page314_i98
#ISCELL
  standard offpage *
  page314_i99
#ISCELL
  logical_power cad_note *
  *
#ISCELL
  mstr_misc dns *
  *
#ISCELL
  pure_quanta quanta_title_block_c *
  *
#CELL
  pure_quanta lcmxo3lf9400c5bg484c *
  page313_i1
#ISCELL
  standard offpage *
  page313_i10
#ISCELL
  standard offpage *
  page313_i100
#ISCELL
  standard offpage *
  page313_i104
#ISCELL
  standard offpage *
  page313_i105
#ISCELL
  standard offpage *
  page313_i11
#CELL
  pure_quanta q_res *
  page313_i115
#ISCELL
  standard offpage *
  page313_i12
#ISCELL
  logical_power universal_gnd *
  page313_i123
#ISCELL
  logical_power universal_power *
  page313_i124
#ISCELL
  logical_power universal_gnd *
  page313_i125
#CELL
  pure_quanta q_cap *
  page313_i126
#CELL
  pure_quanta q_osc4p *
  page313_i127
#ISCELL
  logical_power universal_power *
  page313_i128
#CELL
  pure_quanta q_res *
  page313_i129
#ISCELL
  standard offpage *
  page313_i13
#ISCELL
  standard offpage *
  page313_i130
#ISCELL
  standard offpage *
  page313_i131
#ISCELL
  standard offpage *
  page313_i133
#ISCELL
  standard offpage *
  page313_i134
#ISCELL
  standard offpage *
  page313_i135
#ISCELL
  standard offpage *
  page313_i14
#ISCELL
  standard offpage *
  page313_i144
#ISCELL
  standard offpage *
  page313_i145
#ISCELL
  standard offpage *
  page313_i146
#CELL
  pure_quanta q_res *
  page313_i147
#ISCELL
  standard offpage *
  page313_i148
#ISCELL
  standard offpage *
  page313_i149
#ISCELL
  standard offpage *
  page313_i15
#ISCELL
  standard offpage *
  page313_i150
#ISCELL
  standard offpage *
  page313_i155
#ISCELL
  standard offpage *
  page313_i156
#ISCELL
  standard offpage *
  page313_i157
#ISCELL
  standard offpage *
  page313_i158
#CELL
  pure_quanta q_res *
  page313_i159
#ISCELL
  standard offpage *
  page313_i16
#CELL
  pure_quanta q_res *
  page313_i160
#ISCELL
  standard offpage *
  page313_i161
#ISCELL
  standard offpage *
  page313_i162
#ISCELL
  standard offpage *
  page313_i163
#ISCELL
  standard offpage *
  page313_i164
#ISCELL
  standard offpage *
  page313_i165
#CELL
  pure_quanta q_res *
  page313_i166
#CELL
  pure_quanta q_res *
  page313_i167
#ISCELL
  standard offpage *
  page313_i168
#ISCELL
  standard offpage *
  page313_i169
#ISCELL
  standard offpage *
  page313_i17
#ISCELL
  standard offpage *
  page313_i170
#ISCELL
  standard offpage *
  page313_i171
#ISCELL
  standard offpage *
  page313_i172
#ISCELL
  standard offpage *
  page313_i173
#ISCELL
  standard offpage *
  page313_i174
#CELL
  pure_quanta q_res *
  page313_i175
#CELL
  pure_quanta q_res *
  page313_i176
#ISCELL
  standard offpage *
  page313_i177
#ISCELL
  standard offpage *
  page313_i178
#ISCELL
  standard offpage *
  page313_i179
#ISCELL
  standard offpage *
  page313_i18
#CELL
  pure_quanta q_res *
  page313_i180
#ISCELL
  standard offpage *
  page313_i181
#ISCELL
  standard offpage *
  page313_i182
#CELL
  pure_quanta q_res *
  page313_i183
#ISCELL
  standard offpage *
  page313_i184
#ISCELL
  standard offpage *
  page313_i185
#ISCELL
  standard offpage *
  page313_i186
#ISCELL
  standard offpage *
  page313_i188
#ISCELL
  standard offpage *
  page313_i189
#ISCELL
  standard offpage *
  page313_i19
#CELL
  pure_quanta q_res *
  page313_i190
#ISCELL
  standard offpage *
  page313_i193
#CELL
  pure_quanta q_res *
  page313_i194
#ISCELL
  standard offpage *
  page313_i195
#ISCELL
  standard offpage *
  page313_i196
#ISCELL
  standard offpage *
  page313_i199
#ISCELL
  standard offpage *
  page313_i20
#CELL
  pure_quanta q_res *
  page313_i200
#ISCELL
  standard offpage *
  page313_i201
#ISCELL
  standard offpage *
  page313_i202
#ISCELL
  standard offpage *
  page313_i205
#CELL
  pure_quanta q_res *
  page313_i206
#ISCELL
  standard offpage *
  page313_i207
#ISCELL
  standard offpage *
  page313_i208
#ISCELL
  standard offpage *
  page313_i21
#ISCELL
  standard offpage *
  page313_i210
#CELL
  pure_quanta q_res *
  page313_i211
#ISCELL
  standard offpage *
  page313_i212
#ISCELL
  standard offpage *
  page313_i213
#ISCELL
  standard offpage *
  page313_i214
#ISCELL
  standard offpage *
  page313_i215
#ISCELL
  standard offpage *
  page313_i216
#ISCELL
  standard offpage *
  page313_i22
#ISCELL
  standard offpage *
  page313_i23
#ISCELL
  standard offpage *
  page313_i24
#ISCELL
  standard offpage *
  page313_i25
#ISCELL
  standard offpage *
  page313_i26
#ISCELL
  standard offpage *
  page313_i27
#ISCELL
  standard offpage *
  page313_i28
#ISCELL
  standard offpage *
  page313_i29
#ISCELL
  standard offpage *
  page313_i3
#ISCELL
  standard offpage *
  page313_i30
#ISCELL
  standard offpage *
  page313_i31
#ISCELL
  standard offpage *
  page313_i32
#ISCELL
  standard offpage *
  page313_i33
#ISCELL
  standard offpage *
  page313_i34
#ISCELL
  standard offpage *
  page313_i35
#ISCELL
  standard offpage *
  page313_i36
#ISCELL
  standard offpage *
  page313_i37
#ISCELL
  standard offpage *
  page313_i38
#ISCELL
  standard offpage *
  page313_i39
#ISCELL
  standard offpage *
  page313_i4
#ISCELL
  standard offpage *
  page313_i40
#ISCELL
  standard offpage *
  page313_i41
#ISCELL
  standard offpage *
  page313_i42
#ISCELL
  standard offpage *
  page313_i43
#ISCELL
  standard offpage *
  page313_i44
#ISCELL
  standard offpage *
  page313_i45
#ISCELL
  standard offpage *
  page313_i46
#ISCELL
  standard offpage *
  page313_i47
#ISCELL
  standard offpage *
  page313_i48
#ISCELL
  standard offpage *
  page313_i49
#ISCELL
  standard offpage *
  page313_i5
#ISCELL
  standard offpage *
  page313_i50
#ISCELL
  standard offpage *
  page313_i51
#ISCELL
  standard offpage *
  page313_i52
#ISCELL
  standard offpage *
  page313_i53
#ISCELL
  standard offpage *
  page313_i54
#ISCELL
  standard offpage *
  page313_i55
#ISCELL
  standard offpage *
  page313_i56
#ISCELL
  standard offpage *
  page313_i57
#ISCELL
  standard offpage *
  page313_i58
#ISCELL
  standard offpage *
  page313_i59
#ISCELL
  standard offpage *
  page313_i6
#ISCELL
  standard offpage *
  page313_i60
#ISCELL
  standard offpage *
  page313_i61
#ISCELL
  standard offpage *
  page313_i62
#ISCELL
  standard offpage *
  page313_i63
#ISCELL
  standard offpage *
  page313_i64
#ISCELL
  standard offpage *
  page313_i65
#ISCELL
  standard offpage *
  page313_i7
#ISCELL
  standard offpage *
  page313_i76
#ISCELL
  standard offpage *
  page313_i77
#ISCELL
  standard offpage *
  page313_i78
#ISCELL
  standard offpage *
  page313_i79
#ISCELL
  standard offpage *
  page313_i8
#CELL
  pure_quanta q_res *
  page313_i83
#CELL
  pure_quanta q_res *
  page313_i84
#CELL
  pure_quanta q_res *
  page313_i85
#CELL
  pure_quanta q_res *
  page313_i86
#ISCELL
  standard offpage *
  page313_i87
#ISCELL
  standard offpage *
  page313_i88
#ISCELL
  standard offpage *
  page313_i9
#ISCELL
  standard offpage *
  page313_i99
#ISCELL
  mstr_misc dns *
  *
#ISCELL
  pure_quanta quanta_title_block_c *
  *
#CELL
  pure_quanta lcmxo3lf9400c5bg484c *
  page312_i1
#ISCELL
  standard offpage *
  page312_i10
#ISCELL
  standard offpage *
  page312_i100
#ISCELL
  standard offpage *
  page312_i101
#ISCELL
  standard offpage *
  page312_i102
#CELL
  pure_quanta q_res *
  page312_i103
#CELL
  pure_quanta q_res *
  page312_i104
#ISCELL
  standard offpage *
  page312_i105
#ISCELL
  standard offpage *
  page312_i106
#ISCELL
  standard offpage *
  page312_i107
#ISCELL
  standard offpage *
  page312_i108
#ISCELL
  standard offpage *
  page312_i109
#ISCELL
  standard offpage *
  page312_i11
#ISCELL
  standard offpage *
  page312_i110
#ISCELL
  standard offpage *
  page312_i111
#ISCELL
  standard offpage *
  page312_i112
#ISCELL
  standard offpage *
  page312_i113
#CELL
  pure_quanta q_res *
  page312_i114
#ISCELL
  standard offpage *
  page312_i115
#ISCELL
  standard offpage *
  page312_i116
#ISCELL
  standard offpage *
  page312_i117
#ISCELL
  standard offpage *
  page312_i118
#ISCELL
  standard offpage *
  page312_i119
#ISCELL
  standard offpage *
  page312_i12
#CELL
  pure_quanta q_res *
  page312_i120
#CELL
  pure_quanta q_res *
  page312_i121
#CELL
  pure_quanta q_res *
  page312_i122
#ISCELL
  standard offpage *
  page312_i123
#ISCELL
  standard offpage *
  page312_i124
#ISCELL
  standard offpage *
  page312_i125
#ISCELL
  standard offpage *
  page312_i126
#ISCELL
  standard offpage *
  page312_i127
#ISCELL
  standard offpage *
  page312_i128
#ISCELL
  standard offpage *
  page312_i129
#ISCELL
  standard offpage *
  page312_i13
#ISCELL
  standard offpage *
  page312_i132
#ISCELL
  standard offpage *
  page312_i133
#CELL
  pure_quanta q_res *
  page312_i134
#CELL
  pure_quanta q_res *
  page312_i135
#ISCELL
  standard offpage *
  page312_i136
#ISCELL
  standard offpage *
  page312_i137
#ISCELL
  standard offpage *
  page312_i138
#ISCELL
  standard offpage *
  page312_i14
#ISCELL
  standard offpage *
  page312_i140
#ISCELL
  standard offpage *
  page312_i142
#CELL
  pure_quanta q_res *
  page312_i143
#ISCELL
  standard offpage *
  page312_i144
#CELL
  pure_quanta q_res *
  page312_i145
#ISCELL
  standard offpage *
  page312_i146
#ISCELL
  standard offpage *
  page312_i148
#ISCELL
  standard offpage *
  page312_i15
#CELL
  pure_quanta q_res *
  page312_i150
#ISCELL
  standard offpage *
  page312_i152
#ISCELL
  standard offpage *
  page312_i153
#ISCELL
  standard offpage *
  page312_i154
#ISCELL
  standard offpage *
  page312_i156
#ISCELL
  standard offpage *
  page312_i157
#CELL
  pure_quanta q_res *
  page312_i158
#ISCELL
  standard offpage *
  page312_i159
#ISCELL
  standard offpage *
  page312_i160
#ISCELL
  standard offpage *
  page312_i161
#ISCELL
  standard offpage *
  page312_i162
#ISCELL
  standard offpage *
  page312_i163
#CELL
  pure_quanta q_res *
  page312_i164
#CELL
  pure_quanta q_res *
  page312_i165
#ISCELL
  standard offpage *
  page312_i166
#ISCELL
  standard offpage *
  page312_i167
#ISCELL
  standard offpage *
  page312_i168
#CELL
  pure_quanta q_res *
  page312_i169
#ISCELL
  standard offpage *
  page312_i17
#CELL
  pure_quanta q_res *
  page312_i170
#ISCELL
  standard offpage *
  page312_i171
#ISCELL
  standard offpage *
  page312_i172
#ISCELL
  standard offpage *
  page312_i173
#ISCELL
  standard offpage *
  page312_i174
#ISCELL
  standard offpage *
  page312_i175
#CELL
  pure_quanta q_res *
  page312_i176
#CELL
  pure_quanta q_res *
  page312_i177
#CELL
  pure_quanta q_res *
  page312_i178
#ISCELL
  standard offpage *
  page312_i179
#ISCELL
  standard offpage *
  page312_i18
#ISCELL
  standard offpage *
  page312_i180
#ISCELL
  standard offpage *
  page312_i181
#ISCELL
  standard offpage *
  page312_i182
#CELL
  pure_quanta q_res *
  page312_i183
#CELL
  pure_quanta q_res *
  page312_i184
#ISCELL
  standard offpage *
  page312_i185
#ISCELL
  standard offpage *
  page312_i186
#CELL
  pure_quanta conn3_210hp1030br1 *
  page312_i187
#ISCELL
  logical_power universal_power *
  page312_i188
#ISCELL
  logical_power universal_gnd *
  page312_i189
#ISCELL
  standard offpage *
  page312_i19
#CELL
  pure_quanta q_res *
  page312_i190
#CELL
  pure_quanta q_res *
  page312_i191
#ISCELL
  standard offpage *
  page312_i192
#ISCELL
  standard offpage *
  page312_i193
#ISCELL
  standard offpage *
  page312_i194
#ISCELL
  logical_power universal_power *
  page312_i2
#ISCELL
  standard offpage *
  page312_i20
#ISCELL
  standard offpage *
  page312_i21
#ISCELL
  standard offpage *
  page312_i212
#CELL
  pure_quanta q_res *
  page312_i213
#ISCELL
  standard offpage *
  page312_i214
#ISCELL
  standard offpage *
  page312_i215
#ISCELL
  standard offpage *
  page312_i216
#CELL
  pure_quanta q_res *
  page312_i217
#ISCELL
  standard offpage *
  page312_i23
#ISCELL
  standard offpage *
  page312_i24
#ISCELL
  standard offpage *
  page312_i25
#ISCELL
  standard offpage *
  page312_i26
#ISCELL
  standard offpage *
  page312_i27
#ISCELL
  standard offpage *
  page312_i28
#ISCELL
  standard offpage *
  page312_i29
#CELL
  pure_quanta q_res *
  page312_i3
#ISCELL
  standard offpage *
  page312_i30
#ISCELL
  standard offpage *
  page312_i31
#ISCELL
  standard offpage *
  page312_i32
#ISCELL
  standard offpage *
  page312_i34
#ISCELL
  standard offpage *
  page312_i36
#ISCELL
  standard offpage *
  page312_i37
#CELL
  pure_quanta q_res *
  page312_i38
#CELL
  pure_quanta q_cap *
  page312_i39
#ISCELL
  logical_power universal_power *
  page312_i4
#ISCELL
  logical_power universal_gnd *
  page312_i40
#ISCELL
  standard offpage *
  page312_i41
#ISCELL
  standard offpage *
  page312_i42
#ISCELL
  standard offpage *
  page312_i43
#ISCELL
  standard offpage *
  page312_i44
#ISCELL
  standard offpage *
  page312_i45
#ISCELL
  standard offpage *
  page312_i46
#ISCELL
  standard offpage *
  page312_i47
#ISCELL
  standard offpage *
  page312_i48
#CELL
  pure_quanta q_res *
  page312_i5
#ISCELL
  standard offpage *
  page312_i50
#ISCELL
  standard offpage *
  page312_i51
#ISCELL
  standard offpage *
  page312_i52
#ISCELL
  standard offpage *
  page312_i53
#ISCELL
  standard offpage *
  page312_i54
#ISCELL
  standard offpage *
  page312_i55
#ISCELL
  standard offpage *
  page312_i56
#ISCELL
  standard offpage *
  page312_i57
#ISCELL
  standard offpage *
  page312_i58
#ISCELL
  standard offpage *
  page312_i59
#ISCELL
  standard offpage *
  page312_i6
#ISCELL
  standard offpage *
  page312_i60
#ISCELL
  standard offpage *
  page312_i61
#ISCELL
  standard offpage *
  page312_i62
#ISCELL
  standard offpage *
  page312_i63
#ISCELL
  standard offpage *
  page312_i64
#ISCELL
  standard offpage *
  page312_i65
#ISCELL
  standard offpage *
  page312_i66
#ISCELL
  standard offpage *
  page312_i67
#ISCELL
  standard offpage *
  page312_i68
#ISCELL
  standard offpage *
  page312_i69
#ISCELL
  standard offpage *
  page312_i7
#ISCELL
  standard offpage *
  page312_i70
#ISCELL
  standard offpage *
  page312_i71
#ISCELL
  standard offpage *
  page312_i72
#ISCELL
  standard offpage *
  page312_i73
#ISCELL
  standard offpage *
  page312_i74
#ISCELL
  standard offpage *
  page312_i75
#ISCELL
  standard offpage *
  page312_i76
#ISCELL
  standard offpage *
  page312_i77
#ISCELL
  standard offpage *
  page312_i78
#ISCELL
  standard offpage *
  page312_i79
#ISCELL
  standard offpage *
  page312_i8
#CELL
  pure_quanta q_res *
  page312_i80
#ISCELL
  standard offpage *
  page312_i81
#ISCELL
  standard offpage *
  page312_i82
#ISCELL
  standard offpage *
  page312_i84
#ISCELL
  standard offpage *
  page312_i85
#CELL
  pure_quanta q_res *
  page312_i86
#ISCELL
  logical_power universal_power *
  page312_i87
#ISCELL
  standard offpage *
  page312_i88
#CELL
  pure_quanta q_res *
  page312_i89
#ISCELL
  standard offpage *
  page312_i9
#ISCELL
  standard offpage *
  page312_i90
#ISCELL
  standard offpage *
  page312_i91
#ISCELL
  standard offpage *
  page312_i92
#CELL
  pure_quanta q_res *
  page312_i93
#ISCELL
  standard offpage *
  page312_i94
#ISCELL
  standard offpage *
  page312_i95
#ISCELL
  standard offpage *
  page312_i96
#CELL
  pure_quanta q_res *
  page312_i97
#CELL
  pure_quanta q_res *
  page312_i98
#ISCELL
  standard offpage *
  page312_i99
#ISCELL
  logical_power design_note *
  *
#ISCELL
  pure_quanta quanta_title_block_c *
  *
#ISCELL
  standard offpage *
  page311_i1
#ISCELL
  standard offpage *
  page311_i10
#ISCELL
  standard offpage *
  page311_i14
#ISCELL
  standard offpage *
  page311_i15
#ISCELL
  standard offpage *
  page311_i16
#ISCELL
  standard offpage *
  page311_i17
#ISCELL
  standard offpage *
  page311_i18
#ISCELL
  standard offpage *
  page311_i19
#ISCELL
  standard offpage *
  page311_i2
#ISCELL
  standard offpage *
  page311_i20
#ISCELL
  standard offpage *
  page311_i21
#ISCELL
  standard offpage *
  page311_i22
#ISCELL
  standard offpage *
  page311_i23
#ISCELL
  standard offpage *
  page311_i24
#ISCELL
  standard offpage *
  page311_i25
#ISCELL
  standard offpage *
  page311_i26
#ISCELL
  standard offpage *
  page311_i27
#ISCELL
  logical_power universal_power *
  page311_i28
#CELL
  pure_quanta q_res *
  page311_i29
#ISCELL
  logical_power universal_power *
  page311_i3
#ISCELL
  standard offpage *
  page311_i30
#ISCELL
  standard offpage *
  page311_i31
#ISCELL
  standard offpage *
  page311_i32
#CELL
  pure_quanta lcmxo3lf9400c5bg484c *
  page311_i33
#ISCELL
  standard offpage *
  page311_i34
#ISCELL
  standard offpage *
  page311_i35
#ISCELL
  standard offpage *
  page311_i36
#ISCELL
  standard offpage *
  page311_i37
#ISCELL
  standard offpage *
  page311_i38
#ISCELL
  standard offpage *
  page311_i39
#CELL
  pure_quanta q_res *
  page311_i4
#ISCELL
  standard offpage *
  page311_i40
#ISCELL
  standard offpage *
  page311_i41
#ISCELL
  standard offpage *
  page311_i42
#ISCELL
  standard offpage *
  page311_i43
#ISCELL
  standard offpage *
  page311_i44
#ISCELL
  standard offpage *
  page311_i45
#ISCELL
  standard offpage *
  page311_i46
#ISCELL
  standard offpage *
  page311_i47
#ISCELL
  standard offpage *
  page311_i48
#ISCELL
  standard offpage *
  page311_i49
#ISCELL
  standard offpage *
  page311_i5
#ISCELL
  standard offpage *
  page311_i50
#ISCELL
  standard offpage *
  page311_i51
#ISCELL
  standard offpage *
  page311_i52
#ISCELL
  standard offpage *
  page311_i55
#ISCELL
  standard offpage *
  page311_i56
#ISCELL
  standard offpage *
  page311_i57
#ISCELL
  standard offpage *
  page311_i58
#ISCELL
  standard offpage *
  page311_i59
#ISCELL
  standard offpage *
  page311_i60
#ISCELL
  standard offpage *
  page311_i62
#ISCELL
  standard offpage *
  page311_i68
#ISCELL
  standard offpage *
  page311_i69
#ISCELL
  standard offpage *
  page311_i7
#CELL
  pure_quanta lcmxo3lf9400c5bg484c *
  page311_i70
#ISCELL
  standard offpage *
  page311_i71
#ISCELL
  standard offpage *
  page311_i72
#ISCELL
  standard offpage *
  page311_i73
#ISCELL
  standard offpage *
  page311_i74
#ISCELL
  standard offpage *
  page311_i75
#ISCELL
  standard offpage *
  page311_i76
#ISCELL
  standard offpage *
  page311_i77
#ISCELL
  standard offpage *
  page311_i78
#CELL
  pure_quanta q_res *
  page311_i79
#ISCELL
  standard offpage *
  page311_i8
#ISCELL
  standard offpage *
  page311_i80
#ISCELL
  standard offpage *
  page311_i81
#ISCELL
  standard offpage *
  page311_i82
#ISCELL
  standard offpage *
  page311_i83
#ISCELL
  standard offpage *
  page311_i84
#ISCELL
  standard offpage *
  page311_i85
#CELL
  pure_quanta q_res *
  page311_i86
#ISCELL
  standard offpage *
  page311_i87
#ISCELL
  standard offpage *
  page311_i88
#ISCELL
  standard offpage *
  page311_i89
#ISCELL
  standard offpage *
  page311_i9
#CELL
  pure_quanta q_res *
  page311_i90
#ISCELL
  standard offpage *
  page311_i91
#ISCELL
  standard offpage *
  page311_i92
#ISCELL
  standard offpage *
  page311_i93
#ISCELL
  standard offpage *
  page311_i94
#CELL
  pure_quanta q_res *
  page311_i95
#ISCELL
  standard offpage *
  page311_i96
#ISCELL
  standard offpage *
  page311_i97
#ISCELL
  standard offpage *
  page311_i98
#ISCELL
  pure_quanta quanta_title_block_c *
  *
#CELL
  pure_quanta lcmxo3lf9400c5bg484c *
  page202_i1
#ISCELL
  logical_power universal_gnd *
  page202_i10
#CELL
  pure_quanta q_cap *
  page202_i100
#CELL
  pure_quanta q_cap *
  page202_i101
#CELL
  pure_quanta lcmxo3lf9400c5bg484c *
  page202_i102
#ISCELL
  logical_power universal_power *
  page202_i103
#ISCELL
  logical_power universal_power *
  page202_i104
#ISCELL
  logical_power universal_power *
  page202_i105
#ISCELL
  logical_power universal_power *
  page202_i106
#CELL
  pure_quanta q_cap *
  page202_i107
#CELL
  pure_quanta q_res *
  page202_i108
#ISCELL
  logical_power universal_power *
  page202_i109
#ISCELL
  logical_power universal_power *
  page202_i11
#CELL
  pure_quanta q_res *
  page202_i119
#CELL
  pure_quanta q_cap *
  page202_i12
#CELL
  pure_quanta q_cap *
  page202_i120
#CELL
  pure_quanta q_cap *
  page202_i121
#ISCELL
  logical_power universal_gnd *
  page202_i13
#ISCELL
  logical_power universal_power *
  page202_i14
#CELL
  pure_quanta q_cap *
  page202_i15
#ISCELL
  logical_power universal_gnd *
  page202_i16
#ISCELL
  logical_power universal_power *
  page202_i17
#CELL
  pure_quanta q_cap *
  page202_i18
#ISCELL
  logical_power universal_gnd *
  page202_i19
#ISCELL
  logical_power universal_power *
  page202_i2
#CELL
  pure_quanta q_cap *
  page202_i20
#CELL
  pure_quanta q_cap *
  page202_i21
#CELL
  pure_quanta q_cap *
  page202_i22
#CELL
  pure_quanta q_cap *
  page202_i23
#CELL
  pure_quanta q_cap *
  page202_i24
#CELL
  pure_quanta q_cap *
  page202_i25
#CELL
  pure_quanta q_cap *
  page202_i26
#CELL
  pure_quanta q_cap *
  page202_i27
#CELL
  pure_quanta q_cap *
  page202_i28
#CELL
  pure_quanta q_cap *
  page202_i29
#CELL
  pure_quanta q_cap *
  page202_i3
#CELL
  pure_quanta q_cap *
  page202_i30
#ISCELL
  logical_power universal_power *
  page202_i32
#CELL
  pure_quanta q_cap *
  page202_i33
#CELL
  pure_quanta q_cap *
  page202_i34
#CELL
  pure_quanta q_cap *
  page202_i35
#CELL
  pure_quanta q_cap *
  page202_i36
#CELL
  pure_quanta q_cap *
  page202_i37
#CELL
  pure_quanta q_cap *
  page202_i38
#CELL
  pure_quanta q_cap *
  page202_i39
#ISCELL
  logical_power universal_gnd *
  page202_i4
#CELL
  pure_quanta q_cap *
  page202_i40
#CELL
  pure_quanta q_cap *
  page202_i41
#CELL
  pure_quanta q_cap *
  page202_i42
#CELL
  pure_quanta q_cap *
  page202_i43
#CELL
  pure_quanta q_cap *
  page202_i44
#CELL
  pure_quanta q_cap *
  page202_i45
#CELL
  pure_quanta q_cap *
  page202_i46
#CELL
  pure_quanta q_cap *
  page202_i47
#CELL
  pure_quanta q_cap *
  page202_i48
#CELL
  pure_quanta q_cap *
  page202_i49
#CELL
  pure_quanta q_cap *
  page202_i5
#CELL
  pure_quanta q_cap *
  page202_i50
#CELL
  pure_quanta q_cap *
  page202_i51
#CELL
  pure_quanta q_cap *
  page202_i52
#CELL
  pure_quanta q_cap *
  page202_i53
#CELL
  pure_quanta q_cap *
  page202_i54
#CELL
  pure_quanta q_cap *
  page202_i55
#CELL
  pure_quanta q_cap *
  page202_i56
#CELL
  pure_quanta q_cap *
  page202_i57
#CELL
  pure_quanta q_cap *
  page202_i58
#CELL
  pure_quanta q_cap *
  page202_i59
#CELL
  pure_quanta q_res *
  page202_i60
#ISCELL
  logical_power universal_power *
  page202_i61
#CELL
  pure_quanta q_cap *
  page202_i62
#CELL
  pure_quanta q_res *
  page202_i63
#CELL
  pure_quanta q_cap *
  page202_i64
#CELL
  pure_quanta q_cap *
  page202_i65
#CELL
  pure_quanta q_cap *
  page202_i66
#CELL
  pure_quanta q_res *
  page202_i67
#ISCELL
  logical_power universal_power *
  page202_i68
#ISCELL
  logical_power universal_power *
  page202_i69
#CELL
  pure_quanta q_cap *
  page202_i70
#CELL
  pure_quanta q_cap *
  page202_i71
#CELL
  pure_quanta q_res *
  page202_i72
#ISCELL
  logical_power universal_power *
  page202_i73
#CELL
  pure_quanta q_cap *
  page202_i74
#ISCELL
  logical_power universal_gnd *
  page202_i75
#CELL
  pure_quanta q_cap *
  page202_i76
#CELL
  pure_quanta q_cap *
  page202_i77
#ISCELL
  logical_power universal_power *
  page202_i78
#ISCELL
  logical_power universal_gnd *
  page202_i79
#ISCELL
  logical_power universal_power *
  page202_i8
#CELL
  pure_quanta q_cap *
  page202_i80
#CELL
  pure_quanta q_res *
  page202_i81
#CELL
  pure_quanta q_cap *
  page202_i82
#CELL
  pure_quanta q_cap *
  page202_i9
#ISCELL
  logical_power universal_power *
  page202_i92
#ISCELL
  logical_power universal_power *
  page202_i93
#ISCELL
  logical_power universal_power *
  page202_i94
#ISCELL
  logical_power universal_power *
  page202_i95
#ISCELL
  logical_power universal_power *
  page202_i96
#CELL
  pure_quanta q_cap *
  page202_i97
#ISCELL
  logical_power universal_gnd *
  page202_i98
#CELL
  pure_quanta q_cap *
  page202_i99
#ISCELL
  pure_quanta quanta_title_block_c *
  *
#CELL
  pure_quanta mosfet_n *
  page207_i236
#ISCELL
  logical_power universal_gnd *
  page207_i237
#ISCELL
  standard offpage *
  page207_i238
#ISCELL
  logical_power universal_power *
  page207_i240
#ISCELL
  logical_power universal_gnd *
  page207_i267
#CELL
  pure_quanta q_res *
  page207_i268
#ISCELL
  logical_power universal_gnd *
  page207_i269
#ISCELL
  logical_power universal_power *
  page207_i270
#CELL
  pure_quanta mosfet_nch_gds_esd_protected *
  page207_i272
#CELL
  pure_quanta q_res *
  page207_i273
#ISCELL
  logical_power universal_power *
  page207_i274
#CELL
  pure_quanta q_res *
  page207_i275
#ISCELL
  standard offpage *
  page207_i276
#CELL
  pure_quanta q_led *
  page207_i277
#CELL
  pure_quanta q_res *
  page207_i278
#CELL
  pure_quanta q_led *
  page207_i279
#CELL
  pure_quanta q_res *
  page207_i280
#ISCELL
  mstr_misc dns *
  *
#ISCELL
  pure_quanta quanta_title_block_c *
  *
#ISCELL
  standard offpage *
  page208_i1
#CELL
  pure_quanta q_res *
  page208_i10
#CELL
  pure_quanta q_res *
  page208_i11
#CELL
  pure_quanta q_res *
  page208_i12
#CELL
  pure_quanta q_res *
  page208_i13
#CELL
  pure_quanta q_res *
  page208_i14
#CELL
  pure_quanta q_res *
  page208_i15
#CELL
  pure_quanta q_res *
  page208_i16
#CELL
  pure_quanta q_res *
  page208_i17
#CELL
  pure_quanta q_res *
  page208_i18
#CELL
  pure_quanta q_res *
  page208_i19
#ISCELL
  standard offpage *
  page208_i2
#CELL
  pure_quanta q_res *
  page208_i20
#CELL
  pure_quanta q_res *
  page208_i21
#CELL
  pure_quanta q_res *
  page208_i22
#CELL
  pure_quanta q_res *
  page208_i23
#CELL
  pure_quanta q_res *
  page208_i24
#CELL
  pure_quanta q_res *
  page208_i25
#CELL
  pure_quanta q_res *
  page208_i26
#ISCELL
  standard offpage *
  page208_i27
#ISCELL
  standard offpage *
  page208_i28
#ISCELL
  standard offpage *
  page208_i29
#ISCELL
  standard offpage *
  page208_i3
#ISCELL
  standard offpage *
  page208_i30
#ISCELL
  standard offpage *
  page208_i31
#ISCELL
  standard offpage *
  page208_i32
#ISCELL
  standard offpage *
  page208_i33
#ISCELL
  standard offpage *
  page208_i34
#ISCELL
  standard offpage *
  page208_i35
#ISCELL
  standard offpage *
  page208_i36
#ISCELL
  standard offpage *
  page208_i37
#ISCELL
  standard offpage *
  page208_i38
#ISCELL
  standard offpage *
  page208_i39
#CELL
  pure_quanta q_res *
  page208_i4
#ISCELL
  standard offpage *
  page208_i40
#ISCELL
  standard offpage *
  page208_i41
#ISCELL
  standard offpage *
  page208_i42
#ISCELL
  standard offpage *
  page208_i43
#ISCELL
  standard offpage *
  page208_i44
#ISCELL
  standard offpage *
  page208_i45
#ISCELL
  standard offpage *
  page208_i46
#ISCELL
  standard offpage *
  page208_i47
#ISCELL
  standard offpage *
  page208_i48
#ISCELL
  standard offpage *
  page208_i49
#CELL
  pure_quanta q_res *
  page208_i5
#ISCELL
  logical_power universal_gnd *
  page208_i50
#CELL
  pure_quanta q_res *
  page208_i51
#CELL
  pure_quanta q_res *
  page208_i52
#CELL
  pure_quanta q_res *
  page208_i53
#CELL
  pure_quanta q_res *
  page208_i54
#CELL
  pure_quanta q_res *
  page208_i55
#CELL
  pure_quanta q_res *
  page208_i56
#CELL
  pure_quanta q_res *
  page208_i57
#CELL
  pure_quanta q_res *
  page208_i58
#CELL
  pure_quanta q_res *
  page208_i59
#CELL
  pure_quanta q_res *
  page208_i6
#ISCELL
  standard offpage *
  page208_i60
#ISCELL
  standard offpage *
  page208_i61
#ISCELL
  standard offpage *
  page208_i62
#ISCELL
  standard offpage *
  page208_i63
#ISCELL
  standard offpage *
  page208_i64
#ISCELL
  standard offpage *
  page208_i65
#CELL
  pure_quanta q_res *
  page208_i66
#ISCELL
  standard offpage *
  page208_i67
#CELL
  pure_quanta q_res *
  page208_i7
#CELL
  pure_quanta q_res *
  page208_i8
#CELL
  pure_quanta q_res *
  page208_i9
#ISCELL
  logical_power cad_note *
  *
#ISCELL
  mstr_misc dns *
  *
#ISCELL
  pure_quanta quanta_title_block_c *
  *
#ISCELL
  standard offpage *
  page209_i1
#ISCELL
  logical_power universal_gnd *
  page209_i10
#CELL
  pure_quanta q_res *
  page209_i11
#ISCELL
  logical_power universal_power *
  page209_i12
#CELL
  pure_quanta q_res *
  page209_i13
#CELL
  pure_quanta q_res *
  page209_i14
#CELL
  pure_quanta q_res *
  page209_i15
#CELL
  pure_quanta q_res *
  page209_i16
#CELL
  pure_quanta q_res *
  page209_i17
#ISCELL
  standard offpage *
  page209_i18
#ISCELL
  logical_power universal_power *
  page209_i19
#ISCELL
  standard offpage *
  page209_i2
#ISCELL
  logical_power universal_gnd *
  page209_i20
#CELL
  pure_quanta q_res *
  page209_i21
#CELL
  pure_quanta q_res *
  page209_i22
#CELL
  pure_quanta q_res *
  page209_i23
#CELL
  pure_quanta q_res *
  page209_i24
#ISCELL
  standard offpage *
  page209_i25
#ISCELL
  standard offpage *
  page209_i26
#ISCELL
  standard offpage *
  page209_i27
#ISCELL
  standard offpage *
  page209_i28
#ISCELL
  standard offpage *
  page209_i29
#CELL
  pure_quanta q_cap *
  page209_i3
#ISCELL
  standard offpage *
  page209_i30
#ISCELL
  standard offpage *
  page209_i31
#ISCELL
  standard offpage *
  page209_i32
#ISCELL
  standard offpage *
  page209_i33
#ISCELL
  standard offpage *
  page209_i34
#CELL
  pure_quanta q_res *
  page209_i35
#CELL
  pure_quanta q_res *
  page209_i36
#CELL
  pure_quanta q_res *
  page209_i37
#CELL
  pure_quanta q_res *
  page209_i38
#CELL
  pure_quanta q_res *
  page209_i39
#CELL
  pure_quanta q_cap *
  page209_i4
#CELL
  pure_quanta q_res *
  page209_i40
#CELL
  pure_quanta q_res *
  page209_i41
#CELL
  pure_quanta q_res *
  page209_i42
#CELL
  pure_quanta q_res *
  page209_i43
#CELL
  pure_quanta q_res *
  page209_i44
#ISCELL
  logical_power universal_power *
  page209_i45
#CELL
  pure_quanta q_res *
  page209_i46
#ISCELL
  logical_power universal_gnd *
  page209_i47
#ISCELL
  logical_power universal_gnd *
  page209_i5
#ISCELL
  standard offpage *
  page209_i6
#ISCELL
  standard offpage *
  page209_i7
#ISCELL
  standard offpage *
  page209_i8
#ISCELL
  standard offpage *
  page209_i9
#ISCELL
  mstr_misc dns *
  *
#ISCELL
  pure_quanta quanta_title_block_c *
  *
#ISCELL
  standard offpage *
  page210_i15
#CELL
  pure_quanta q_res *
  page210_i19
#CELL
  pure_quanta q_res *
  page210_i20
#ISCELL
  standard offpage *
  page210_i21
#CELL
  pure_quanta q_res *
  page210_i25
#ISCELL
  standard offpage *
  page210_i26
#ISCELL
  standard offpage *
  page210_i29
#CELL
  pure_quanta q_res *
  page210_i54
#ISCELL
  standard offpage *
  page210_i55
#ISCELL
  standard offpage *
  page210_i58
#CELL
  pure_quanta q_res *
  page210_i59
#CELL
  pure_quanta q_res *
  page210_i60
#CELL
  pure_quanta q_res *
  page210_i61
#ISCELL
  logical_power universal_power *
  page210_i62
#CELL
  pure_quanta q_res *
  page210_i63
#ISCELL
  logical_power universal_gnd *
  page210_i64
#ISCELL
  standard offpage *
  page210_i65
#ISCELL
  standard offpage *
  page210_i67
#ISCELL
  standard offpage *
  page210_i72
#CELL
  pure_quanta q_res *
  page210_i75
#CELL
  pure_quanta q_res *
  page210_i76
#ISCELL
  logical_power universal_power *
  page210_i77
#ISCELL
  logical_power universal_gnd *
  page210_i78
#CELL
  pure_quanta conn8_210hp1080br1 *
  page210_i79
#ISCELL
  standard offpage *
  page210_i81
#ISCELL
  standard offpage *
  page210_i82
#ISCELL
  standard offpage *
  page210_i83
#ISCELL
  standard offpage *
  page210_i84
#CELL
  pure_quanta q_cap *
  page210_i86
#CELL
  pure_quanta q_cap *
  page210_i88
#ISCELL
  logical_power universal_gnd *
  page210_i89
#ISCELL
  logical_power universal_gnd *
  page210_i90
#CELL
  pure_quanta schottky_12 *
  page210_i91
#ISCELL
  logical_power universal_power *
  page210_i92
#ISCELL
  pure_quanta quanta_title_block_c *
  *
#ISCELL
  standard offpage *
  page211_i1
#CELL
  pure_quanta q_res *
  page211_i10
#ISCELL
  standard offpage *
  page211_i100
#ISCELL
  standard offpage *
  page211_i101
#ISCELL
  standard offpage *
  page211_i102
#ISCELL
  standard offpage *
  page211_i104
#ISCELL
  standard offpage *
  page211_i105
#ISCELL
  standard offpage *
  page211_i108
#ISCELL
  standard offpage *
  page211_i109
#ISCELL
  standard offpage *
  page211_i11
#CELL
  pure_quanta q_res *
  page211_i110
#CELL
  pure_quanta q_res *
  page211_i111
#ISCELL
  standard offpage *
  page211_i116
#ISCELL
  standard offpage *
  page211_i117
#ISCELL
  standard offpage *
  page211_i12
#ISCELL
  standard offpage *
  page211_i120
#ISCELL
  standard offpage *
  page211_i121
#CELL
  pure_quanta q_res *
  page211_i122
#CELL
  pure_quanta q_res *
  page211_i123
#ISCELL
  standard offpage *
  page211_i125
#ISCELL
  standard offpage *
  page211_i126
#CELL
  pure_quanta q_res *
  page211_i127
#ISCELL
  standard offpage *
  page211_i128
#CELL
  pure_quanta q_res *
  page211_i129
#CELL
  pure_quanta q_res *
  page211_i13
#ISCELL
  standard offpage *
  page211_i14
#CELL
  pure_quanta q_res *
  page211_i15
#ISCELL
  standard offpage *
  page211_i16
#ISCELL
  standard offpage *
  page211_i17
#ISCELL
  standard offpage *
  page211_i18
#ISCELL
  standard offpage *
  page211_i19
#ISCELL
  standard offpage *
  page211_i20
#CELL
  pure_quanta q_res *
  page211_i21
#ISCELL
  standard offpage *
  page211_i22
#CELL
  pure_quanta q_res *
  page211_i23
#CELL
  pure_quanta q_res *
  page211_i24
#CELL
  pure_quanta q_res *
  page211_i25
#ISCELL
  standard offpage *
  page211_i26
#ISCELL
  standard offpage *
  page211_i27
#ISCELL
  standard offpage *
  page211_i28
#ISCELL
  standard offpage *
  page211_i3
#ISCELL
  standard offpage *
  page211_i42
#ISCELL
  standard offpage *
  page211_i43
#CELL
  pure_quanta q_res *
  page211_i44
#ISCELL
  standard offpage *
  page211_i45
#ISCELL
  standard offpage *
  page211_i47
#CELL
  pure_quanta q_res *
  page211_i48
#CELL
  pure_quanta q_res *
  page211_i49
#ISCELL
  standard offpage *
  page211_i50
#ISCELL
  standard offpage *
  page211_i51
#ISCELL
  standard offpage *
  page211_i52
#ISCELL
  standard offpage *
  page211_i53
#CELL
  pure_quanta q_res *
  page211_i54
#ISCELL
  standard offpage *
  page211_i6
#CELL
  pure_quanta q_res *
  page211_i62
#ISCELL
  standard offpage *
  page211_i63
#ISCELL
  standard offpage *
  page211_i64
#ISCELL
  standard offpage *
  page211_i66
#ISCELL
  standard offpage *
  page211_i67
#CELL
  pure_quanta q_res *
  page211_i68
#ISCELL
  standard offpage *
  page211_i7
#ISCELL
  standard offpage *
  page211_i77
#ISCELL
  standard offpage *
  page211_i80
#CELL
  pure_quanta q_res *
  page211_i81
#CELL
  pure_quanta q_res *
  page211_i82
#ISCELL
  standard offpage *
  page211_i83
#CELL
  pure_quanta q_res *
  page211_i84
#ISCELL
  standard offpage *
  page211_i85
#ISCELL
  standard offpage *
  page211_i86
#ISCELL
  standard offpage *
  page211_i87
#CELL
  pure_quanta q_res *
  page211_i88
#ISCELL
  standard offpage *
  page211_i89
#CELL
  pure_quanta q_res *
  page211_i9
#ISCELL
  standard offpage *
  page211_i90
#CELL
  pure_quanta q_res *
  page211_i91
#ISCELL
  standard offpage *
  page211_i92
#ISCELL
  standard offpage *
  page211_i93
#ISCELL
  standard offpage *
  page211_i94
#ISCELL
  standard offpage *
  page211_i95
#CELL
  pure_quanta q_res *
  page211_i96
#ISCELL
  standard offpage *
  page211_i97
#CELL
  pure_quanta q_res *
  page211_i98
#CELL
  pure_quanta q_res *
  page211_i99
#ISCELL
  pure_quanta quanta_title_block_c *
  *
#ISCELL
  standard offpage *
  page212_i1
#CELL
  pure_quanta q_res *
  page212_i10
#ISCELL
  standard offpage *
  page212_i100
#CELL
  pure_quanta q_res *
  page212_i105
#ISCELL
  standard offpage *
  page212_i111
#CELL
  pure_quanta q_res *
  page212_i113
#ISCELL
  standard offpage *
  page212_i126
#CELL
  pure_quanta q_res *
  page212_i127
#ISCELL
  standard offpage *
  page212_i128
#CELL
  pure_quanta q_res *
  page212_i129
#ISCELL
  standard offpage *
  page212_i13
#CELL
  pure_quanta q_res *
  page212_i130
#ISCELL
  standard offpage *
  page212_i131
#ISCELL
  standard offpage *
  page212_i14
#CELL
  pure_quanta q_res *
  page212_i15
#ISCELL
  standard offpage *
  page212_i16
#CELL
  pure_quanta q_res *
  page212_i17
#ISCELL
  standard offpage *
  page212_i18
#CELL
  pure_quanta mosfet_n *
  page212_i19
#ISCELL
  standard offpage *
  page212_i2
#ISCELL
  standard offpage *
  page212_i20
#CELL
  pure_quanta q_res *
  page212_i24
#ISCELL
  logical_power universal_power *
  page212_i25
#ISCELL
  logical_power universal_gnd *
  page212_i26
#CELL
  pure_quanta q_res *
  page212_i27
#ISCELL
  standard offpage *
  page212_i28
#ISCELL
  standard offpage *
  page212_i42
#ISCELL
  standard offpage *
  page212_i43
#CELL
  pure_quanta q_res *
  page212_i44
#ISCELL
  standard offpage *
  page212_i45
#ISCELL
  standard offpage *
  page212_i46
#ISCELL
  standard offpage *
  page212_i49
#ISCELL
  standard offpage *
  page212_i5
#ISCELL
  standard offpage *
  page212_i53
#ISCELL
  standard offpage *
  page212_i54
#CELL
  pure_quanta q_res *
  page212_i55
#CELL
  pure_quanta q_res *
  page212_i56
#ISCELL
  standard offpage *
  page212_i57
#ISCELL
  standard offpage *
  page212_i59
#ISCELL
  standard offpage *
  page212_i6
#CELL
  pure_quanta q_res *
  page212_i7
#ISCELL
  standard offpage *
  page212_i73
#ISCELL
  standard offpage *
  page212_i8
#CELL
  pure_quanta q_res *
  page212_i86
#CELL
  pure_quanta q_res *
  page212_i87
#ISCELL
  standard offpage *
  page212_i88
#ISCELL
  standard offpage *
  page212_i9
#ISCELL
  standard offpage *
  page212_i90
#CELL
  pure_quanta q_res *
  page212_i91
#CELL
  pure_quanta q_res *
  page212_i92
#ISCELL
  logical_power universal_gnd *
  page212_i93
#CELL
  pure_quanta q_res *
  page212_i94
#ISCELL
  standard offpage *
  page212_i95
#ISCELL
  standard offpage *
  page212_i96
#ISCELL
  standard offpage *
  page212_i97
#ISCELL
  logical_power cad_note *
  *
#ISCELL
  mstr_misc dns *
  *
#ISCELL
  pure_quanta quanta_title_block_c *
  *
#ISCELL
  standard offpage *
  page213_i1
#ISCELL
  standard offpage *
  page213_i10
#ISCELL
  standard offpage *
  page213_i12
#ISCELL
  logical_power universal_gnd *
  page213_i17
#CELL
  pure_quanta q_res *
  page213_i18
#ISCELL
  logical_power universal_power *
  page213_i19
#CELL
  pure_quanta 74lvc2g17gw *
  page213_i2
#ISCELL
  logical_power universal_gnd *
  page213_i20
#CELL
  pure_quanta mosfet_nch_dual *
  page213_i21
#CELL
  pure_quanta q_res *
  page213_i22
#ISCELL
  logical_power universal_power *
  page213_i23
#CELL
  pure_quanta mosfet_nch_dual *
  page213_i27
#ISCELL
  standard offpage *
  page213_i28
#CELL
  pure_quanta q_res *
  page213_i29
#ISCELL
  logical_power universal_gnd *
  page213_i3
#ISCELL
  standard offpage *
  page213_i30
#ISCELL
  logical_power universal_power *
  page213_i31
#CELL
  pure_quanta q_res *
  page213_i32
#CELL
  pure_quanta q_res *
  page213_i33
#ISCELL
  logical_power universal_gnd *
  page213_i34
#CELL
  pure_quanta q_cap *
  page213_i35
#ISCELL
  logical_power universal_power *
  page213_i36
#CELL
  pure_quanta 74lvc2g07dw7 *
  page213_i37
#ISCELL
  logical_power universal_gnd *
  page213_i38
#ISCELL
  logical_power universal_power *
  page213_i39
#ISCELL
  logical_power universal_gnd *
  page213_i4
#CELL
  pure_quanta q_res *
  page213_i40
#CELL
  pure_quanta q_res *
  page213_i41
#CELL
  pure_quanta q_cap *
  page213_i42
#ISCELL
  logical_power universal_gnd *
  page213_i43
#ISCELL
  standard offpage *
  page213_i44
#CELL
  pure_quanta q_cap *
  page213_i5
#ISCELL
  logical_power universal_power *
  page213_i6
#CELL
  pure_quanta q_res *
  page213_i7
#ISCELL
  logical_power universal_power *
  page213_i8
#ISCELL
  pure_quanta quanta_title_block_c *
  *
#ISCELL
  logical_power universal_gnd *
  page322_i10
#CELL
  pure_quanta q_cap *
  page322_i101
#ISCELL
  logical_power universal_gnd *
  page322_i102
#ISCELL
  logical_power universal_power *
  page322_i105
#CELL
  pure_quanta q_cap *
  page322_i106
#ISCELL
  logical_power universal_gnd *
  page322_i107
#ISCELL
  logical_power universal_power *
  page322_i11
#ISCELL
  logical_power universal_power *
  page322_i110
#CELL
  pure_quanta q_cap *
  page322_i111
#ISCELL
  logical_power universal_gnd *
  page322_i112
#ISCELL
  logical_power universal_power *
  page322_i115
#ISCELL
  standard offpage *
  page322_i116
#ISCELL
  standard offpage *
  page322_i117
#ISCELL
  standard offpage *
  page322_i118
#ISCELL
  standard offpage *
  page322_i119
#ISCELL
  standard offpage *
  page322_i120
#ISCELL
  standard offpage *
  page322_i121
#ISCELL
  standard offpage *
  page322_i122
#ISCELL
  standard offpage *
  page322_i123
#ISCELL
  standard offpage *
  page322_i126
#CELL
  pure_quanta q_res *
  page322_i128
#CELL
  pure_quanta q_res *
  page322_i129
#CELL
  pure_quanta q_res *
  page322_i130
#CELL
  pure_quanta q_res *
  page322_i131
#ISCELL
  logical_power universal_power *
  page322_i132
#CELL
  pure_quanta q_res *
  page322_i157
#CELL
  pure_quanta q_res *
  page322_i158
#CELL
  pure_quanta q_res *
  page322_i159
#CELL
  pure_quanta q_res *
  page322_i160
#ISCELL
  standard offpage *
  page322_i161
#ISCELL
  standard offpage *
  page322_i162
#CELL
  pure_quanta q_res *
  page322_i163
#CELL
  pure_quanta q_res *
  page322_i164
#ISCELL
  standard offpage *
  page322_i165
#ISCELL
  standard offpage *
  page322_i166
#ISCELL
  standard offpage *
  page322_i167
#ISCELL
  standard offpage *
  page322_i168
#CELL
  pure_quanta q_res *
  page322_i169
#CELL
  pure_quanta q_res *
  page322_i171
#CELL
  pure_quanta q_res *
  page322_i172
#CELL
  pure_quanta q_res *
  page322_i173
#CELL
  pure_quanta q_res *
  page322_i174
#ISCELL
  logical_power universal_power *
  page322_i175
#ISCELL
  logical_power universal_power *
  page322_i176
#CELL
  pure_quanta q_res *
  page322_i177
#ISCELL
  standard offpage *
  page322_i178
#ISCELL
  standard offpage *
  page322_i179
#ISCELL
  standard offpage *
  page322_i180
#CELL
  pure_quanta q_res *
  page322_i181
#CELL
  pure_quanta q_res *
  page322_i182
#CELL
  pure_quanta q_res *
  page322_i183
#CELL
  pure_quanta q_res *
  page322_i184
#ISCELL
  standard offpage *
  page322_i185
#ISCELL
  standard offpage *
  page322_i186
#CELL
  pure_quanta q_res *
  page322_i187
#CELL
  pure_quanta q_res *
  page322_i188
#CELL
  pure_quanta q_res *
  page322_i189
#CELL
  pure_quanta q_res *
  page322_i190
#ISCELL
  logical_power universal_gnd *
  page322_i191
#ISCELL
  logical_power universal_gnd *
  page322_i20
#CELL
  pure_quanta gtl2014pw *
  page322_i27
#ISCELL
  standard offpage *
  page322_i32
#ISCELL
  standard offpage *
  page322_i33
#ISCELL
  standard offpage *
  page322_i34
#ISCELL
  standard offpage *
  page322_i35
#CELL
  pure_quanta q_res *
  page322_i36
#CELL
  pure_quanta q_res *
  page322_i37
#CELL
  pure_quanta q_res *
  page322_i38
#CELL
  pure_quanta q_res *
  page322_i39
#CELL
  pure_quanta gtl2014pw *
  page322_i44
#ISCELL
  logical_power universal_gnd *
  page322_i49
#CELL
  pure_quanta q_res *
  page322_i52
#CELL
  pure_quanta q_res *
  page322_i53
#CELL
  pure_quanta q_res *
  page322_i54
#CELL
  pure_quanta q_res *
  page322_i55
#ISCELL
  logical_power universal_gnd *
  page322_i58
#CELL
  pure_quanta q_cap *
  page322_i59
#ISCELL
  logical_power universal_power *
  page322_i60
#ISCELL
  logical_power universal_gnd *
  page322_i61
#ISCELL
  standard offpage *
  page322_i62
#ISCELL
  standard offpage *
  page322_i63
#ISCELL
  standard offpage *
  page322_i64
#ISCELL
  standard offpage *
  page322_i65
#CELL
  pure_quanta q_res *
  page322_i66
#CELL
  pure_quanta q_res *
  page322_i67
#ISCELL
  logical_power universal_gnd *
  page322_i8
#CELL
  pure_quanta gtl2014pw *
  page322_i80
#CELL
  pure_quanta q_cap *
  page322_i83
#ISCELL
  logical_power universal_power *
  page322_i84
#ISCELL
  logical_power universal_gnd *
  page322_i89
#CELL
  pure_quanta q_cap *
  page322_i9
#CELL
  pure_quanta q_res *
  page322_i91
#CELL
  pure_quanta q_res *
  page322_i94
#ISCELL
  logical_power universal_gnd *
  page322_i96
#ISCELL
  logical_power universal_gnd *
  page322_i97
#ISCELL
  pure_quanta quanta_title_block_c *
  *
#CELL
  pure_quanta q_res *
  page321_i101
#ISCELL
  standard offpage *
  page321_i102
#ISCELL
  logical_power universal_gnd *
  page321_i70
#ISCELL
  standard offpage *
  page321_i71
#ISCELL
  standard offpage *
  page321_i72
#ISCELL
  standard offpage *
  page321_i73
#ISCELL
  logical_power universal_gnd *
  page321_i74
#ISCELL
  logical_power universal_power *
  page321_i75
#CELL
  pure_quanta q_res *
  page321_i77
#CELL
  pure_quanta q_res *
  page321_i78
#CELL
  pure_quanta q_res *
  page321_i79
#CELL
  pure_quanta q_res *
  page321_i80
#CELL
  pure_quanta q_cap *
  page321_i83
#CELL
  pure_quanta q_cap *
  page321_i85
#ISCELL
  logical_power universal_gnd *
  page321_i86
#ISCELL
  logical_power universal_power *
  page321_i87
#CELL
  pure_quanta gtl2014pw *
  page321_i91
#ISCELL
  logical_power universal_gnd *
  page321_i92
#ISCELL
  standard offpage *
  page321_i94
#ISCELL
  standard offpage *
  page321_i95
#ISCELL
  standard offpage *
  page321_i96
#CELL
  pure_quanta q_res *
  page321_i97
#CELL
  pure_quanta q_res *
  page321_i98
#ISCELL
  mstr_misc dns *
  *
#ISCELL
  pure_quanta quanta_title_block_c *
  *
#ISCELL
  standard offpage *
  page214_i100
#CELL
  pure_quanta q_res *
  page214_i101
#ISCELL
  standard offpage *
  page214_i113
#ISCELL
  standard offpage *
  page214_i114
#ISCELL
  standard offpage *
  page214_i115
#ISCELL
  standard offpage *
  page214_i116
#ISCELL
  standard offpage *
  page214_i117
#CELL
  pure_quanta q_res *
  page214_i118
#ISCELL
  standard offpage *
  page214_i122
#ISCELL
  standard offpage *
  page214_i123
#ISCELL
  standard offpage *
  page214_i124
#CELL
  pure_quanta q_res *
  page214_i127
#CELL
  pure_quanta q_res *
  page214_i128
#CELL
  pure_quanta q_res *
  page214_i129
#ISCELL
  standard offpage *
  page214_i130
#ISCELL
  standard offpage *
  page214_i131
#ISCELL
  standard offpage *
  page214_i132
#ISCELL
  standard offpage *
  page214_i133
#ISCELL
  standard offpage *
  page214_i134
#ISCELL
  standard offpage *
  page214_i135
#ISCELL
  standard offpage *
  page214_i136
#CELL
  pure_quanta q_res *
  page214_i137
#ISCELL
  standard offpage *
  page214_i138
#ISCELL
  standard offpage *
  page214_i139
#CELL
  pure_quanta q_res *
  page214_i140
#ISCELL
  standard offpage *
  page214_i141
#ISCELL
  standard offpage *
  page214_i142
#ISCELL
  standard offpage *
  page214_i143
#CELL
  pure_quanta q_res *
  page214_i144
#ISCELL
  standard offpage *
  page214_i145
#ISCELL
  standard offpage *
  page214_i146
#ISCELL
  standard offpage *
  page214_i147
#CELL
  pure_quanta q_res *
  page214_i148
#ISCELL
  standard offpage *
  page214_i149
#ISCELL
  standard offpage *
  page214_i150
#ISCELL
  standard offpage *
  page214_i151
#ISCELL
  standard offpage *
  page214_i152
#CELL
  pure_quanta q_res *
  page214_i153
#ISCELL
  standard offpage *
  page214_i154
#ISCELL
  standard offpage *
  page214_i155
#CELL
  pure_quanta q_res *
  page214_i156
#ISCELL
  standard offpage *
  page214_i157
#ISCELL
  standard offpage *
  page214_i158
#ISCELL
  standard offpage *
  page214_i159
#ISCELL
  standard offpage *
  page214_i160
#CELL
  pure_quanta q_res *
  page214_i161
#ISCELL
  standard offpage *
  page214_i162
#ISCELL
  standard offpage *
  page214_i163
#CELL
  pure_quanta q_res *
  page214_i164
#ISCELL
  standard offpage *
  page214_i165
#ISCELL
  standard offpage *
  page214_i166
#ISCELL
  standard offpage *
  page214_i167
#ISCELL
  standard offpage *
  page214_i33
#CELL
  pure_quanta q_res *
  page214_i34
#ISCELL
  standard offpage *
  page214_i35
#CELL
  pure_quanta pca9539rpw *
  page214_i66
#ISCELL
  logical_power universal_power *
  page214_i73
#CELL
  pure_quanta q_res *
  page214_i74
#CELL
  pure_quanta q_res *
  page214_i75
#CELL
  pure_quanta q_res *
  page214_i76
#CELL
  pure_quanta q_res *
  page214_i77
#ISCELL
  logical_power universal_gnd *
  page214_i78
#ISCELL
  logical_power universal_gnd *
  page214_i79
#ISCELL
  standard offpage *
  page214_i80
#ISCELL
  standard offpage *
  page214_i81
#ISCELL
  standard offpage *
  page214_i82
#ISCELL
  standard offpage *
  page214_i83
#ISCELL
  standard offpage *
  page214_i84
#ISCELL
  standard offpage *
  page214_i85
#ISCELL
  logical_power universal_gnd *
  page214_i86
#CELL
  pure_quanta q_cap *
  page214_i87
#ISCELL
  logical_power universal_power *
  page214_i88
#ISCELL
  logical_power universal_gnd *
  page214_i89
#CELL
  pure_quanta q_res *
  page214_i90
#ISCELL
  logical_power universal_power *
  page214_i91
#ISCELL
  standard offpage *
  page214_i92
#CELL
  pure_quanta q_res *
  page214_i93
#ISCELL
  logical_power universal_power *
  page214_i94
#CELL
  pure_quanta q_res *
  page214_i95
#CELL
  pure_quanta q_res *
  page214_i96
#ISCELL
  standard offpage *
  page214_i97
#ISCELL
  standard offpage *
  page214_i98
#ISCELL
  standard offpage *
  page214_i99
#ISCELL
  pure_quanta quanta_title_block_c *
  *
#ISCELL
  standard offpage *
  page215_i10
#ISCELL
  standard offpage *
  page215_i11
#CELL
  pure_quanta q_res *
  page215_i12
#CELL
  pure_quanta q_res *
  page215_i13
#ISCELL
  standard offpage *
  page215_i14
#ISCELL
  standard offpage *
  page215_i15
#ISCELL
  standard offpage *
  page215_i17
#ISCELL
  standard offpage *
  page215_i18
#ISCELL
  standard offpage *
  page215_i19
#CELL
  pure_quanta q_res *
  page215_i2
#ISCELL
  standard offpage *
  page215_i20
#ISCELL
  logical_power universal_gnd *
  page215_i21
#CELL
  pure_quanta q_res *
  page215_i23
#ISCELL
  standard offpage *
  page215_i24
#ISCELL
  standard offpage *
  page215_i26
#ISCELL
  logical_power universal_gnd *
  page215_i27
#CELL
  pure_quanta q_res *
  page215_i28
#ISCELL
  standard offpage *
  page215_i29
#ISCELL
  standard offpage *
  page215_i3
#ISCELL
  standard offpage *
  page215_i30
#ISCELL
  standard offpage *
  page215_i31
#CELL
  pure_quanta sconn20_513860200cv01 *
  page215_i32
#ISCELL
  standard offpage *
  page215_i4
#ISCELL
  standard offpage *
  page215_i5
#ISCELL
  standard offpage *
  page215_i6
#ISCELL
  standard offpage *
  page215_i7
#ISCELL
  standard offpage *
  page215_i8
#ISCELL
  standard offpage *
  page215_i9
#ISCELL
  mstr_misc dns *
  *
#ISCELL
  pure_quanta quanta_title_block_c *
  *
#ISCELL
  standard offpage *
  page217_i1
#ISCELL
  standard offpage *
  page217_i10
#ISCELL
  standard offpage *
  page217_i11
#ISCELL
  logical_power universal_gnd *
  page217_i12
#CELL
  pure_quanta q_res *
  page217_i13
#ISCELL
  standard offpage *
  page217_i14
#ISCELL
  standard offpage *
  page217_i15
#CELL
  pure_quanta q_res *
  page217_i16
#CELL
  pure_quanta q_res *
  page217_i17
#CELL
  pure_quanta q_res *
  page217_i18
#CELL
  pure_quanta qs3vh257qg8 *
  page217_i19
#ISCELL
  standard offpage *
  page217_i2
#CELL
  pure_quanta q_res *
  page217_i20
#ISCELL
  logical_power universal_gnd *
  page217_i21
#ISCELL
  logical_power universal_gnd *
  page217_i22
#ISCELL
  logical_power universal_power *
  page217_i23
#CELL
  pure_quanta q_cap *
  page217_i24
#CELL
  pure_quanta q_res *
  page217_i25
#CELL
  pure_quanta q_res *
  page217_i26
#ISCELL
  standard offpage *
  page217_i27
#ISCELL
  standard offpage *
  page217_i28
#CELL
  pure_quanta q_res *
  page217_i29
#CELL
  pure_quanta q_res *
  page217_i30
#ISCELL
  logical_power universal_power *
  page217_i31
#CELL
  pure_quanta q_res *
  page217_i32
#CELL
  pure_quanta q_res *
  page217_i33
#CELL
  pure_quanta q_res *
  page217_i34
#CELL
  pure_quanta q_res *
  page217_i35
#ISCELL
  standard offpage *
  page217_i36
#CELL
  pure_quanta q_res *
  page217_i37
#CELL
  pure_quanta q_res *
  page217_i38
#CELL
  pure_quanta q_res *
  page217_i39
#ISCELL
  standard offpage *
  page217_i4
#CELL
  pure_quanta q_res *
  page217_i40
#ISCELL
  logical_power universal_gnd *
  page217_i41
#CELL
  pure_quanta q_res *
  page217_i42
#CELL
  pure_quanta q_res *
  page217_i43
#ISCELL
  logical_power universal_power *
  page217_i44
#ISCELL
  standard offpage *
  page217_i45
#ISCELL
  standard offpage *
  page217_i46
#ISCELL
  standard offpage *
  page217_i47
#ISCELL
  standard offpage *
  page217_i48
#ISCELL
  standard offpage *
  page217_i49
#ISCELL
  standard offpage *
  page217_i5
#ISCELL
  standard offpage *
  page217_i50
#ISCELL
  standard offpage *
  page217_i51
#ISCELL
  standard offpage *
  page217_i52
#CELL
  pure_quanta q_res *
  page217_i53
#ISCELL
  standard offpage *
  page217_i6
#ISCELL
  standard offpage *
  page217_i7
#ISCELL
  standard offpage *
  page217_i8
#ISCELL
  standard offpage *
  page217_i9
#ISCELL
  mstr_misc dns *
  *
#ISCELL
  pure_quanta quanta_title_block_c *
  *
#ISCELL
  standard offpage *
  page218_i1
#ISCELL
  standard offpage *
  page218_i10
#ISCELL
  standard offpage *
  page218_i11
#CELL
  pure_quanta qs3vh257qg8 *
  page218_i12
#ISCELL
  standard offpage *
  page218_i13
#ISCELL
  standard offpage *
  page218_i14
#ISCELL
  standard offpage *
  page218_i15
#ISCELL
  standard offpage *
  page218_i16
#CELL
  pure_quanta q_res *
  page218_i17
#CELL
  pure_quanta q_res *
  page218_i18
#ISCELL
  logical_power universal_power *
  page218_i19
#ISCELL
  standard offpage *
  page218_i2
#CELL
  pure_quanta q_res *
  page218_i20
#CELL
  pure_quanta q_res *
  page218_i21
#CELL
  pure_quanta q_res *
  page218_i22
#CELL
  pure_quanta q_res *
  page218_i23
#ISCELL
  logical_power universal_gnd *
  page218_i24
#CELL
  pure_quanta q_cap *
  page218_i25
#ISCELL
  logical_power universal_gnd *
  page218_i26
#ISCELL
  logical_power universal_power *
  page218_i27
#CELL
  pure_quanta q_res *
  page218_i28
#CELL
  pure_quanta q_res *
  page218_i29
#ISCELL
  logical_power universal_gnd *
  page218_i3
#CELL
  pure_quanta q_res *
  page218_i30
#CELL
  pure_quanta q_res *
  page218_i31
#CELL
  pure_quanta q_res *
  page218_i32
#CELL
  pure_quanta q_res *
  page218_i33
#CELL
  pure_quanta q_res *
  page218_i34
#CELL
  pure_quanta q_res *
  page218_i35
#CELL
  pure_quanta q_res *
  page218_i36
#CELL
  pure_quanta q_res *
  page218_i37
#ISCELL
  standard offpage *
  page218_i38
#ISCELL
  standard offpage *
  page218_i39
#CELL
  pure_quanta q_res *
  page218_i4
#ISCELL
  standard offpage *
  page218_i40
#ISCELL
  standard offpage *
  page218_i41
#ISCELL
  standard offpage *
  page218_i42
#ISCELL
  standard offpage *
  page218_i43
#ISCELL
  standard offpage *
  page218_i44
#ISCELL
  standard offpage *
  page218_i45
#ISCELL
  standard offpage *
  page218_i5
#ISCELL
  standard offpage *
  page218_i6
#ISCELL
  standard offpage *
  page218_i7
#ISCELL
  standard offpage *
  page218_i8
#ISCELL
  standard offpage *
  page218_i9
#ISCELL
  mstr_misc dns *
  *
#ISCELL
  pure_quanta quanta_title_block_c *
  *
#ISCELL
  logical_power universal_gnd *
  page219_i1
#CELL
  pure_quanta q_res *
  page219_i10
#ISCELL
  standard offpage *
  page219_i11
#ISCELL
  standard offpage *
  page219_i12
#ISCELL
  standard offpage *
  page219_i13
#ISCELL
  standard offpage *
  page219_i14
#ISCELL
  standard offpage *
  page219_i15
#ISCELL
  standard offpage *
  page219_i16
#ISCELL
  standard offpage *
  page219_i17
#CELL
  pure_quanta q_res *
  page219_i18
#ISCELL
  logical_power universal_power *
  page219_i19
#CELL
  pure_quanta q_res *
  page219_i2
#CELL
  pure_quanta q_res *
  page219_i20
#CELL
  pure_quanta q_res *
  page219_i21
#CELL
  pure_quanta q_res *
  page219_i22
#CELL
  pure_quanta q_res *
  page219_i23
#CELL
  pure_quanta q_res *
  page219_i24
#CELL
  pure_quanta q_res *
  page219_i25
#ISCELL
  standard offpage *
  page219_i26
#ISCELL
  standard offpage *
  page219_i27
#ISCELL
  standard offpage *
  page219_i28
#ISCELL
  standard offpage *
  page219_i29
#CELL
  pure_quanta q_res *
  page219_i3
#ISCELL
  standard offpage *
  page219_i30
#ISCELL
  standard offpage *
  page219_i31
#ISCELL
  standard offpage *
  page219_i32
#ISCELL
  standard offpage *
  page219_i33
#ISCELL
  standard offpage *
  page219_i34
#CELL
  pure_quanta q_res *
  page219_i35
#CELL
  pure_quanta q_res *
  page219_i36
#CELL
  pure_quanta q_res *
  page219_i37
#CELL
  pure_quanta q_res *
  page219_i38
#CELL
  pure_quanta q_res *
  page219_i39
#ISCELL
  logical_power universal_power *
  page219_i4
#CELL
  pure_quanta q_res *
  page219_i40
#CELL
  pure_quanta q_res *
  page219_i41
#ISCELL
  standard offpage *
  page219_i42
#ISCELL
  standard offpage *
  page219_i43
#ISCELL
  standard offpage *
  page219_i44
#CELL
  pure_quanta tca9548apwr *
  page219_i45
#ISCELL
  logical_power universal_gnd *
  page219_i46
#CELL
  pure_quanta q_cap *
  page219_i47
#ISCELL
  logical_power universal_power *
  page219_i48
#CELL
  pure_quanta q_res *
  page219_i49
#ISCELL
  logical_power universal_gnd *
  page219_i5
#CELL
  pure_quanta q_res *
  page219_i50
#CELL
  pure_quanta q_res *
  page219_i51
#CELL
  pure_quanta q_res *
  page219_i52
#CELL
  pure_quanta q_res *
  page219_i53
#CELL
  pure_quanta q_res *
  page219_i54
#ISCELL
  logical_power universal_power *
  page219_i55
#CELL
  pure_quanta q_res *
  page219_i56
#CELL
  pure_quanta q_res *
  page219_i57
#ISCELL
  logical_power universal_gnd *
  page219_i58
#CELL
  pure_quanta q_res *
  page219_i59
#CELL
  pure_quanta q_res *
  page219_i6
#CELL
  pure_quanta q_res *
  page219_i60
#CELL
  pure_quanta q_res *
  page219_i61
#CELL
  pure_quanta q_res *
  page219_i62
#CELL
  pure_quanta q_res *
  page219_i63
#CELL
  pure_quanta q_res *
  page219_i64
#CELL
  pure_quanta q_res *
  page219_i65
#CELL
  pure_quanta q_res *
  page219_i66
#ISCELL
  standard offpage *
  page219_i67
#ISCELL
  standard offpage *
  page219_i68
#ISCELL
  standard offpage *
  page219_i69
#ISCELL
  logical_power universal_gnd *
  page219_i7
#ISCELL
  standard offpage *
  page219_i70
#ISCELL
  standard offpage *
  page219_i71
#ISCELL
  standard offpage *
  page219_i72
#ISCELL
  standard offpage *
  page219_i73
#ISCELL
  standard offpage *
  page219_i74
#ISCELL
  standard offpage *
  page219_i75
#ISCELL
  standard offpage *
  page219_i76
#ISCELL
  standard offpage *
  page219_i77
#ISCELL
  standard offpage *
  page219_i78
#ISCELL
  standard offpage *
  page219_i79
#CELL
  pure_quanta q_res *
  page219_i8
#ISCELL
  standard offpage *
  page219_i80
#ISCELL
  standard offpage *
  page219_i81
#ISCELL
  standard offpage *
  page219_i82
#CELL
  pure_quanta q_res *
  page219_i9
#ISCELL
  pure_quanta quanta_title_block_c *
  *
#ISCELL
  standard offpage *
  page220_i1
#CELL
  pure_quanta q_res *
  page220_i11
#ISCELL
  standard offpage *
  page220_i12
#ISCELL
  standard offpage *
  page220_i13
#ISCELL
  standard offpage *
  page220_i14
#ISCELL
  standard offpage *
  page220_i15
#CELL
  pure_quanta q_res *
  page220_i16
#CELL
  pure_quanta q_res *
  page220_i17
#CELL
  pure_quanta q_res *
  page220_i18
#CELL
  pure_quanta q_res *
  page220_i19
#ISCELL
  standard offpage *
  page220_i2
#CELL
  pure_quanta q_res *
  page220_i20
#CELL
  pure_quanta q_res *
  page220_i21
#ISCELL
  standard offpage *
  page220_i22
#ISCELL
  standard offpage *
  page220_i23
#ISCELL
  standard offpage *
  page220_i24
#ISCELL
  standard offpage *
  page220_i25
#CELL
  pure_quanta q_res *
  page220_i26
#CELL
  pure_quanta q_res *
  page220_i3
#CELL
  pure_quanta q_res *
  page220_i4
#ISCELL
  standard offpage *
  page220_i7
#ISCELL
  standard offpage *
  page220_i8
#ISCELL
  mstr_misc dns *
  *
#ISCELL
  pure_quanta quanta_title_block_c *
  *
#ISCELL
  logical_power universal_gnd *
  page221_i1
#CELL
  pure_quanta q_res *
  page221_i10
#ISCELL
  standard offpage *
  page221_i100
#ISCELL
  standard offpage *
  page221_i101
#CELL
  pure_quanta q_res *
  page221_i102
#CELL
  pure_quanta tca9548apwr *
  page221_i103
#ISCELL
  logical_power universal_power *
  page221_i104
#ISCELL
  logical_power universal_gnd *
  page221_i105
#CELL
  pure_quanta q_cap *
  page221_i106
#ISCELL
  standard offpage *
  page221_i107
#ISCELL
  standard offpage *
  page221_i109
#ISCELL
  standard offpage *
  page221_i110
#ISCELL
  standard offpage *
  page221_i113
#ISCELL
  standard offpage *
  page221_i114
#CELL
  pure_quanta q_res *
  page221_i115
#CELL
  pure_quanta q_res *
  page221_i116
#ISCELL
  standard offpage *
  page221_i117
#ISCELL
  standard offpage *
  page221_i118
#CELL
  pure_quanta q_res *
  page221_i119
#CELL
  pure_quanta q_res *
  page221_i120
#ISCELL
  standard offpage *
  page221_i121
#ISCELL
  standard offpage *
  page221_i122
#ISCELL
  standard offpage *
  page221_i123
#ISCELL
  standard offpage *
  page221_i124
#ISCELL
  standard offpage *
  page221_i125
#ISCELL
  standard offpage *
  page221_i126
#ISCELL
  standard offpage *
  page221_i127
#ISCELL
  standard offpage *
  page221_i128
#CELL
  pure_quanta q_res *
  page221_i137
#CELL
  pure_quanta q_res *
  page221_i138
#CELL
  pure_quanta q_res *
  page221_i139
#CELL
  pure_quanta q_res *
  page221_i140
#CELL
  pure_quanta q_res *
  page221_i141
#CELL
  pure_quanta q_res *
  page221_i142
#CELL
  pure_quanta q_res *
  page221_i143
#CELL
  pure_quanta q_res *
  page221_i144
#CELL
  pure_quanta q_res *
  page221_i145
#ISCELL
  logical_power universal_power *
  page221_i146
#CELL
  pure_quanta q_res *
  page221_i147
#ISCELL
  standard offpage *
  page221_i148
#ISCELL
  logical_power universal_gnd *
  page221_i149
#CELL
  pure_quanta q_res *
  page221_i2
#CELL
  pure_quanta q_res *
  page221_i3
#ISCELL
  standard offpage *
  page221_i33
#CELL
  pure_quanta q_res *
  page221_i34
#ISCELL
  standard offpage *
  page221_i35
#ISCELL
  standard offpage *
  page221_i36
#ISCELL
  standard offpage *
  page221_i37
#ISCELL
  logical_power universal_power *
  page221_i4
#CELL
  pure_quanta q_res *
  page221_i48
#CELL
  pure_quanta q_res *
  page221_i49
#ISCELL
  logical_power universal_gnd *
  page221_i5
#CELL
  pure_quanta q_res *
  page221_i50
#CELL
  pure_quanta q_res *
  page221_i51
#CELL
  pure_quanta q_res *
  page221_i52
#CELL
  pure_quanta q_res *
  page221_i53
#ISCELL
  logical_power universal_power *
  page221_i54
#CELL
  pure_quanta q_res *
  page221_i55
#CELL
  pure_quanta q_res *
  page221_i56
#CELL
  pure_quanta q_res *
  page221_i6
#ISCELL
  logical_power universal_gnd *
  page221_i7
#ISCELL
  standard offpage *
  page221_i75
#ISCELL
  standard offpage *
  page221_i76
#ISCELL
  standard offpage *
  page221_i77
#ISCELL
  standard offpage *
  page221_i78
#ISCELL
  standard offpage *
  page221_i79
#CELL
  pure_quanta q_res *
  page221_i8
#ISCELL
  standard offpage *
  page221_i80
#ISCELL
  standard offpage *
  page221_i81
#ISCELL
  standard offpage *
  page221_i82
#ISCELL
  standard offpage *
  page221_i83
#CELL
  pure_quanta q_res *
  page221_i9
#CELL
  pure_quanta q_res *
  page221_i98
#CELL
  pure_quanta q_res *
  page221_i99
#ISCELL
  mstr_misc dns *
  *
#ISCELL
  pure_quanta quanta_title_block_c *
  *
#ISCELL
  standard offpage *
  page222_i1
#ISCELL
  logical_power universal_gnd *
  page222_i10
#CELL
  pure_quanta ltc4307cms8 *
  page222_i11
#CELL
  pure_quanta q_res *
  page222_i12
#CELL
  pure_quanta q_res *
  page222_i13
#ISCELL
  logical_power universal_gnd *
  page222_i14
#ISCELL
  logical_power universal_gnd *
  page222_i15
#CELL
  pure_quanta q_res *
  page222_i16
#CELL
  pure_quanta q_res *
  page222_i17
#CELL
  pure_quanta q_res *
  page222_i18
#CELL
  pure_quanta q_res *
  page222_i19
#ISCELL
  standard offpage *
  page222_i2
#CELL
  pure_quanta q_cap *
  page222_i20
#ISCELL
  logical_power universal_gnd *
  page222_i21
#ISCELL
  logical_power universal_power *
  page222_i22
#CELL
  pure_quanta q_res *
  page222_i23
#ISCELL
  logical_power universal_power *
  page222_i24
#CELL
  pure_quanta q_res *
  page222_i25
#CELL
  pure_quanta q_res *
  page222_i26
#CELL
  pure_quanta q_res *
  page222_i27
#ISCELL
  logical_power universal_gnd *
  page222_i28
#CELL
  pure_quanta q_res *
  page222_i29
#ISCELL
  standard offpage *
  page222_i3
#CELL
  pure_quanta q_res *
  page222_i30
#CELL
  pure_quanta ltc4307cms8 *
  page222_i31
#ISCELL
  logical_power universal_gnd *
  page222_i32
#CELL
  pure_quanta q_res *
  page222_i33
#CELL
  pure_quanta q_cap *
  page222_i34
#ISCELL
  logical_power universal_power *
  page222_i35
#ISCELL
  standard offpage *
  page222_i36
#ISCELL
  standard offpage *
  page222_i37
#CELL
  pure_quanta q_res *
  page222_i38
#ISCELL
  standard offpage *
  page222_i39
#ISCELL
  standard offpage *
  page222_i4
#ISCELL
  standard offpage *
  page222_i40
#ISCELL
  standard offpage *
  page222_i41
#CELL
  pure_quanta q_res *
  page222_i42
#CELL
  pure_quanta q_res *
  page222_i43
#CELL
  pure_quanta q_res *
  page222_i44
#ISCELL
  standard offpage *
  page222_i45
#ISCELL
  standard offpage *
  page222_i46
#ISCELL
  standard offpage *
  page222_i47
#CELL
  pure_quanta q_res *
  page222_i48
#ISCELL
  logical_power universal_gnd *
  page222_i49
#ISCELL
  standard offpage *
  page222_i5
#CELL
  pure_quanta ltc4307cms8 *
  page222_i50
#CELL
  pure_quanta q_res *
  page222_i51
#CELL
  pure_quanta q_res *
  page222_i52
#CELL
  pure_quanta q_res *
  page222_i53
#CELL
  pure_quanta q_res *
  page222_i54
#CELL
  pure_quanta q_res *
  page222_i55
#ISCELL
  logical_power universal_gnd *
  page222_i56
#ISCELL
  logical_power universal_power *
  page222_i57
#CELL
  pure_quanta q_cap *
  page222_i58
#CELL
  pure_quanta q_res *
  page222_i59
#ISCELL
  standard offpage *
  page222_i6
#ISCELL
  logical_power universal_power *
  page222_i60
#CELL
  pure_quanta q_res *
  page222_i61
#ISCELL
  logical_power universal_gnd *
  page222_i62
#CELL
  pure_quanta ltc4307cms8 *
  page222_i63
#CELL
  pure_quanta q_res *
  page222_i64
#CELL
  pure_quanta q_res *
  page222_i65
#CELL
  pure_quanta q_cap *
  page222_i66
#ISCELL
  logical_power universal_gnd *
  page222_i67
#ISCELL
  logical_power universal_power *
  page222_i68
#ISCELL
  standard offpage *
  page222_i69
#CELL
  pure_quanta q_res *
  page222_i7
#ISCELL
  standard offpage *
  page222_i70
#CELL
  pure_quanta q_res *
  page222_i71
#CELL
  pure_quanta q_res *
  page222_i72
#ISCELL
  standard offpage *
  page222_i73
#ISCELL
  standard offpage *
  page222_i74
#CELL
  pure_quanta q_res *
  page222_i75
#ISCELL
  logical_power universal_power *
  page222_i76
#CELL
  pure_quanta q_res *
  page222_i77
#CELL
  pure_quanta q_res *
  page222_i78
#CELL
  pure_quanta q_res *
  page222_i79
#CELL
  pure_quanta q_res *
  page222_i8
#CELL
  pure_quanta q_res *
  page222_i80
#CELL
  pure_quanta q_res *
  page222_i81
#ISCELL
  logical_power universal_power *
  page222_i82
#ISCELL
  standard offpage *
  page222_i83
#ISCELL
  standard offpage *
  page222_i84
#CELL
  pure_quanta q_res *
  page222_i9
#ISCELL
  logical_power design_note *
  *
#ISCELL
  pure_quanta quanta_title_block_c *
  *
#ISCELL
  logical_power universal_gnd *
  page223_i10
#CELL
  pure_quanta q_res *
  page223_i100
#CELL
  pure_quanta q_res *
  page223_i101
#CELL
  pure_quanta q_res *
  page223_i102
#CELL
  pure_quanta mosfet_nch_dual *
  page223_i104
#CELL
  pure_quanta mosfet_nch_dual *
  page223_i106
#CELL
  pure_quanta mosfet_nch_dual *
  page223_i108
#CELL
  pure_quanta mosfet_nch_dual *
  page223_i109
#ISCELL
  logical_power universal_power *
  page223_i11
#CELL
  pure_quanta q_res *
  page223_i12
#ISCELL
  logical_power universal_power *
  page223_i16
#ISCELL
  logical_power universal_gnd *
  page223_i17
#CELL
  pure_quanta q_cap *
  page223_i18
#ISCELL
  logical_power universal_power *
  page223_i19
#CELL
  pure_quanta q_cap *
  page223_i20
#ISCELL
  logical_power universal_gnd *
  page223_i21
#CELL
  pure_quanta q_res *
  page223_i22
#ISCELL
  logical_power universal_power *
  page223_i23
#CELL
  pure_quanta q_res *
  page223_i24
#ISCELL
  logical_power universal_power *
  page223_i30
#CELL
  pure_quanta q_cap *
  page223_i31
#ISCELL
  logical_power universal_gnd *
  page223_i32
#ISCELL
  logical_power universal_power *
  page223_i33
#CELL
  pure_quanta q_res *
  page223_i34
#ISCELL
  logical_power universal_gnd *
  page223_i35
#ISCELL
  logical_power universal_power *
  page223_i37
#CELL
  pure_quanta q_res *
  page223_i38
#CELL
  pure_quanta pca9617adp *
  page223_i39
#ISCELL
  logical_power universal_gnd *
  page223_i40
#ISCELL
  logical_power universal_power *
  page223_i41
#CELL
  pure_quanta q_cap *
  page223_i42
#CELL
  pure_quanta pca9617adp *
  page223_i43
#ISCELL
  logical_power universal_gnd *
  page223_i44
#ISCELL
  logical_power universal_gnd *
  page223_i45
#CELL
  pure_quanta q_res *
  page223_i46
#ISCELL
  logical_power universal_power *
  page223_i47
#CELL
  pure_quanta q_res *
  page223_i48
#ISCELL
  standard offpage *
  page223_i5
#ISCELL
  logical_power universal_power *
  page223_i51
#CELL
  pure_quanta q_res *
  page223_i52
#CELL
  pure_quanta q_res *
  page223_i53
#ISCELL
  logical_power universal_power *
  page223_i54
#CELL
  pure_quanta q_res *
  page223_i55
#ISCELL
  standard offpage *
  page223_i56
#ISCELL
  standard offpage *
  page223_i57
#ISCELL
  standard offpage *
  page223_i58
#ISCELL
  standard offpage *
  page223_i59
#ISCELL
  standard offpage *
  page223_i6
#ISCELL
  standard offpage *
  page223_i60
#ISCELL
  standard offpage *
  page223_i61
#ISCELL
  standard offpage *
  page223_i62
#ISCELL
  logical_power universal_gnd *
  page223_i63
#CELL
  pure_quanta conn3_210hp1030br1 *
  page223_i64
#ISCELL
  logical_power universal_gnd *
  page223_i65
#ISCELL
  logical_power universal_gnd *
  page223_i67
#CELL
  pure_quanta q_res *
  page223_i69
#ISCELL
  logical_power universal_power *
  page223_i7
#ISCELL
  standard offpage *
  page223_i70
#CELL
  pure_quanta q_res *
  page223_i76
#CELL
  pure_quanta q_res *
  page223_i77
#ISCELL
  standard offpage *
  page223_i78
#ISCELL
  standard offpage *
  page223_i79
#CELL
  pure_quanta q_res *
  page223_i8
#ISCELL
  logical_power universal_power *
  page223_i80
#CELL
  pure_quanta q_res *
  page223_i81
#CELL
  pure_quanta q_res *
  page223_i82
#CELL
  pure_quanta q_res *
  page223_i88
#CELL
  pure_quanta q_res *
  page223_i89
#ISCELL
  standard offpage *
  page223_i90
#ISCELL
  standard offpage *
  page223_i91
#ISCELL
  logical_power universal_power *
  page223_i92
#CELL
  pure_quanta q_res *
  page223_i93
#CELL
  pure_quanta q_res *
  page223_i94
#CELL
  pure_quanta q_res *
  page223_i99
#ISCELL
  mstr_misc dns *
  *
#ISCELL
  pure_quanta quanta_title_block_c *
  *
#ISCELL
  standard offpage *
  page224_i1
#CELL
  pure_quanta q_res *
  page224_i101
#ISCELL
  logical_power universal_power *
  page224_i102
#CELL
  pure_quanta q_res *
  page224_i103
#ISCELL
  logical_power universal_power *
  page224_i104
#ISCELL
  standard offpage *
  page224_i105
#CELL
  pure_quanta pca9545apw *
  page224_i106
#ISCELL
  standard offpage *
  page224_i107
#ISCELL
  standard offpage *
  page224_i108
#CELL
  pure_quanta q_res *
  page224_i109
#CELL
  pure_quanta q_res *
  page224_i110
#CELL
  pure_quanta q_res *
  page224_i111
#ISCELL
  standard offpage *
  page224_i112
#ISCELL
  standard offpage *
  page224_i113
#CELL
  pure_quanta q_res *
  page224_i114
#CELL
  pure_quanta q_res *
  page224_i115
#CELL
  pure_quanta q_res *
  page224_i116
#CELL
  pure_quanta q_res *
  page224_i117
#ISCELL
  standard offpage *
  page224_i118
#ISCELL
  standard offpage *
  page224_i119
#ISCELL
  standard offpage *
  page224_i123
#ISCELL
  standard offpage *
  page224_i124
#ISCELL
  standard offpage *
  page224_i125
#CELL
  pure_quanta q_res *
  page224_i13
#CELL
  pure_quanta q_res *
  page224_i130
#CELL
  pure_quanta q_res *
  page224_i131
#CELL
  pure_quanta q_res *
  page224_i132
#CELL
  pure_quanta q_res *
  page224_i133
#ISCELL
  logical_power universal_power *
  page224_i138
#ISCELL
  standard offpage *
  page224_i139
#CELL
  pure_quanta q_res *
  page224_i14
#CELL
  pure_quanta q_res *
  page224_i142
#CELL
  pure_quanta q_res *
  page224_i143
#ISCELL
  logical_power universal_power *
  page224_i15
#CELL
  pure_quanta q_res *
  page224_i16
#ISCELL
  standard offpage *
  page224_i2
#ISCELL
  logical_power universal_power *
  page224_i21
#CELL
  pure_quanta q_cap *
  page224_i22
#ISCELL
  logical_power universal_gnd *
  page224_i23
#ISCELL
  logical_power universal_power *
  page224_i24
#CELL
  pure_quanta q_cap *
  page224_i25
#ISCELL
  logical_power universal_gnd *
  page224_i26
#CELL
  pure_quanta pca9517ad *
  page224_i28
#ISCELL
  logical_power universal_gnd *
  page224_i29
#CELL
  pure_quanta q_res *
  page224_i3
#ISCELL
  logical_power universal_power *
  page224_i31
#ISCELL
  logical_power universal_gnd *
  page224_i32
#CELL
  pure_quanta q_cap *
  page224_i33
#ISCELL
  logical_power universal_power *
  page224_i34
#CELL
  pure_quanta q_cap *
  page224_i35
#ISCELL
  logical_power universal_gnd *
  page224_i36
#CELL
  pure_quanta pca9517ad *
  page224_i37
#ISCELL
  logical_power universal_gnd *
  page224_i38
#ISCELL
  standard offpage *
  page224_i4
#ISCELL
  logical_power universal_power *
  page224_i41
#CELL
  pure_quanta q_res *
  page224_i42
#CELL
  pure_quanta q_res *
  page224_i43
#CELL
  pure_quanta q_res *
  page224_i44
#ISCELL
  standard offpage *
  page224_i46
#ISCELL
  standard offpage *
  page224_i47
#ISCELL
  logical_power universal_power *
  page224_i48
#CELL
  pure_quanta q_res *
  page224_i49
#ISCELL
  standard offpage *
  page224_i5
#CELL
  pure_quanta q_res *
  page224_i50
#CELL
  pure_quanta q_res *
  page224_i51
#ISCELL
  standard offpage *
  page224_i53
#ISCELL
  standard offpage *
  page224_i54
#CELL
  pure_quanta q_res *
  page224_i6
#CELL
  pure_quanta q_res *
  page224_i62
#CELL
  pure_quanta q_res *
  page224_i63
#CELL
  pure_quanta q_res *
  page224_i64
#CELL
  pure_quanta q_res *
  page224_i65
#ISCELL
  logical_power universal_gnd *
  page224_i67
#CELL
  pure_quanta q_cap *
  page224_i68
#ISCELL
  logical_power universal_gnd *
  page224_i69
#ISCELL
  logical_power universal_power *
  page224_i7
#ISCELL
  logical_power universal_power *
  page224_i70
#CELL
  pure_quanta q_res *
  page224_i8
#CELL
  pure_quanta q_res *
  page224_i83
#CELL
  pure_quanta q_res *
  page224_i84
#CELL
  pure_quanta q_res *
  page224_i85
#CELL
  pure_quanta q_res *
  page224_i86
#ISCELL
  logical_power universal_power *
  page224_i87
#ISCELL
  logical_power universal_gnd *
  page224_i88
#ISCELL
  standard offpage *
  page224_i89
#ISCELL
  standard offpage *
  page224_i90
#ISCELL
  standard offpage *
  page224_i91
#ISCELL
  standard offpage *
  page224_i92
#ISCELL
  standard offpage *
  page224_i93
#ISCELL
  standard offpage *
  page224_i95
#ISCELL
  standard offpage *
  page224_i96
#CELL
  pure_quanta q_res *
  page224_i97
#ISCELL
  standard offpage *
  page224_i99
#ISCELL
  pure_quanta quanta_title_block_c *
  *
#CELL
  pure_quanta q_res *
  page225_i11
#CELL
  pure_quanta q_res *
  page225_i12
#ISCELL
  logical_power universal_power *
  page225_i13
#CELL
  pure_quanta pca9617adp *
  page225_i17
#ISCELL
  standard offpage *
  page225_i18
#ISCELL
  standard offpage *
  page225_i19
#ISCELL
  standard offpage *
  page225_i22
#ISCELL
  standard offpage *
  page225_i23
#CELL
  pure_quanta q_res *
  page225_i24
#CELL
  pure_quanta q_res *
  page225_i25
#CELL
  pure_quanta q_res *
  page225_i26
#CELL
  pure_quanta q_res *
  page225_i27
#ISCELL
  standard offpage *
  page225_i28
#ISCELL
  standard offpage *
  page225_i29
#ISCELL
  logical_power universal_gnd *
  page225_i3
#ISCELL
  standard offpage *
  page225_i30
#ISCELL
  standard offpage *
  page225_i31
#CELL
  pure_quanta q_res *
  page225_i32
#CELL
  pure_quanta q_res *
  page225_i33
#CELL
  pure_quanta q_res *
  page225_i34
#ISCELL
  standard offpage *
  page225_i35
#ISCELL
  standard offpage *
  page225_i36
#ISCELL
  logical_power universal_gnd *
  page225_i4
#CELL
  pure_quanta q_cap *
  page225_i5
#ISCELL
  logical_power universal_power *
  page225_i6
#ISCELL
  logical_power universal_gnd *
  page225_i7
#CELL
  pure_quanta q_cap *
  page225_i8
#ISCELL
  logical_power universal_power *
  page225_i9
#ISCELL
  pure_quanta quanta_title_block_c *
  *
#ISCELL
  standard offpage *
  page216_i1
#CELL
  pure_quanta q_cap *
  page216_i10
#CELL
  pure_quanta q_cap *
  page216_i11
#ISCELL
  standard offpage *
  page216_i12
#ISCELL
  standard offpage *
  page216_i13
#ISCELL
  logical_power universal_power *
  page216_i14
#ISCELL
  logical_power universal_gnd *
  page216_i15
#ISCELL
  logical_power universal_gnd *
  page216_i16
#CELL
  pure_quanta q_cap *
  page216_i17
#ISCELL
  logical_power universal_power *
  page216_i18
#ISCELL
  logical_power universal_power *
  page216_i19
#ISCELL
  standard offpage *
  page216_i2
#ISCELL
  logical_power universal_power *
  page216_i20
#CELL
  pure_quanta q_res *
  page216_i21
#ISCELL
  standard offpage *
  page216_i22
#CELL
  pure_quanta q_cap *
  page216_i23
#ISCELL
  logical_power universal_gnd *
  page216_i24
#ISCELL
  standard offpage *
  page216_i25
#ISCELL
  standard offpage *
  page216_i26
#ISCELL
  standard offpage *
  page216_i27
#CELL
  pure_quanta pca9617adp *
  page216_i28
#ISCELL
  logical_power universal_power *
  page216_i29
#ISCELL
  logical_power universal_gnd *
  page216_i3
#CELL
  pure_quanta q_res *
  page216_i30
#CELL
  pure_quanta q_res *
  page216_i31
#ISCELL
  logical_power universal_power *
  page216_i32
#CELL
  pure_quanta q_res *
  page216_i33
#CELL
  pure_quanta q_res *
  page216_i34
#ISCELL
  logical_power universal_gnd *
  page216_i4
#CELL
  pure_quanta pca9617adp *
  page216_i5
#ISCELL
  logical_power universal_gnd *
  page216_i6
#CELL
  pure_quanta q_res *
  page216_i7
#ISCELL
  standard offpage *
  page216_i8
#ISCELL
  standard offpage *
  page216_i9
#ISCELL
  logical_power design_note *
  *
#ISCELL
  mstr_misc dns *
  *
#ISCELL
  pure_quanta quanta_title_block_c *
  *
#CELL
  pure_quanta q_res *
  page226_i1
#CELL
  pure_quanta q_res *
  page226_i10
#CELL
  pure_quanta q_res *
  page226_i11
#CELL
  pure_quanta q_res *
  page226_i12
#CELL
  pure_quanta q_res *
  page226_i13
#CELL
  pure_quanta q_res *
  page226_i14
#ISCELL
  logical_power universal_power *
  page226_i15
#CELL
  pure_quanta q_cap *
  page226_i16
#ISCELL
  logical_power universal_gnd *
  page226_i17
#CELL
  pure_quanta gtl2014pw *
  page226_i18
#ISCELL
  logical_power universal_gnd *
  page226_i19
#ISCELL
  standard offpage *
  page226_i2
#CELL
  pure_quanta q_res *
  page226_i20
#ISCELL
  standard offpage *
  page226_i21
#ISCELL
  standard offpage *
  page226_i22
#ISCELL
  standard offpage *
  page226_i26
#CELL
  pure_quanta q_cap *
  page226_i27
#ISCELL
  logical_power universal_power *
  page226_i28
#ISCELL
  logical_power universal_gnd *
  page226_i29
#ISCELL
  standard offpage *
  page226_i3
#ISCELL
  logical_power universal_power *
  page226_i30
#CELL
  pure_quanta q_res *
  page226_i31
#ISCELL
  logical_power universal_gnd *
  page226_i32
#CELL
  pure_quanta q_res *
  page226_i34
#CELL
  pure_quanta q_res *
  page226_i36
#CELL
  pure_quanta q_res *
  page226_i37
#CELL
  pure_quanta nx3l2267gm *
  page226_i38
#ISCELL
  logical_power universal_gnd *
  page226_i39
#ISCELL
  standard offpage *
  page226_i4
#ISCELL
  standard offpage *
  page226_i40
#ISCELL
  standard offpage *
  page226_i41
#ISCELL
  logical_power universal_power *
  page226_i42
#CELL
  pure_quanta q_cap *
  page226_i43
#ISCELL
  logical_power universal_gnd *
  page226_i44
#CELL
  pure_quanta gtl2014pw *
  page226_i45
#ISCELL
  logical_power universal_gnd *
  page226_i46
#CELL
  pure_quanta q_res *
  page226_i47
#CELL
  pure_quanta q_res *
  page226_i48
#ISCELL
  logical_power universal_gnd *
  page226_i49
#ISCELL
  standard offpage *
  page226_i5
#ISCELL
  standard offpage *
  page226_i51
#ISCELL
  standard offpage *
  page226_i52
#ISCELL
  standard offpage *
  page226_i53
#ISCELL
  logical_power universal_power *
  page226_i54
#CELL
  pure_quanta q_cap *
  page226_i55
#ISCELL
  logical_power universal_gnd *
  page226_i56
#CELL
  pure_quanta q_res *
  page226_i57
#CELL
  pure_quanta q_res *
  page226_i58
#CELL
  pure_quanta q_res *
  page226_i59
#ISCELL
  logical_power universal_power *
  page226_i6
#ISCELL
  standard offpage *
  page226_i60
#ISCELL
  standard offpage *
  page226_i61
#ISCELL
  standard offpage *
  page226_i62
#ISCELL
  standard offpage *
  page226_i63
#CELL
  pure_quanta q_res *
  page226_i64
#CELL
  pure_quanta q_res *
  page226_i65
#ISCELL
  standard offpage *
  page226_i66
#ISCELL
  standard offpage *
  page226_i67
#CELL
  pure_quanta nx3l2267gm *
  page226_i68
#ISCELL
  logical_power universal_gnd *
  page226_i69
#CELL
  pure_quanta q_res *
  page226_i7
#ISCELL
  standard offpage *
  page226_i70
#ISCELL
  standard offpage *
  page226_i71
#ISCELL
  standard offpage *
  page226_i72
#ISCELL
  logical_power universal_power *
  page226_i76
#CELL
  pure_quanta q_res *
  page226_i77
#ISCELL
  logical_power universal_gnd *
  page226_i78
#CELL
  pure_quanta q_res *
  page226_i79
#ISCELL
  logical_power universal_gnd *
  page226_i8
#CELL
  pure_quanta q_res *
  page226_i80
#ISCELL
  standard offpage *
  page226_i81
#CELL
  pure_quanta q_res *
  page226_i82
#ISCELL
  standard offpage *
  page226_i83
#ISCELL
  standard offpage *
  page226_i84
#ISCELL
  standard offpage *
  page226_i85
#ISCELL
  logical_power universal_power *
  page226_i86
#CELL
  pure_quanta q_res *
  page226_i87
#CELL
  pure_quanta q_res *
  page226_i88
#CELL
  pure_quanta q_res *
  page226_i89
#ISCELL
  logical_power universal_power *
  page226_i9
#CELL
  pure_quanta q_res *
  page226_i90
#CELL
  pure_quanta q_res *
  page226_i91
#ISCELL
  logical_power universal_power *
  page226_i92
#CELL
  pure_quanta q_cap *
  page226_i93
#ISCELL
  standard offpage *
  page226_i94
#ISCELL
  standard offpage *
  page226_i95
#ISCELL
  logical_power design_note *
  *
#ISCELL
  mstr_misc dns *
  *
#ISCELL
  pure_quanta quanta_title_block_c *
  *
#ISCELL
  logical_power universal_gnd *
  page227_i1
#ISCELL
  standard offpage *
  page227_i10
#CELL
  pure_quanta q_res *
  page227_i100
#CELL
  pure_quanta q_res *
  page227_i101
#CELL
  pure_quanta q_res *
  page227_i102
#ISCELL
  standard offpage *
  page227_i103
#ISCELL
  standard offpage *
  page227_i104
#ISCELL
  standard offpage *
  page227_i105
#ISCELL
  standard offpage *
  page227_i106
#ISCELL
  standard offpage *
  page227_i107
#ISCELL
  standard offpage *
  page227_i108
#ISCELL
  standard offpage *
  page227_i109
#ISCELL
  standard offpage *
  page227_i11
#ISCELL
  standard offpage *
  page227_i110
#ISCELL
  standard offpage *
  page227_i111
#ISCELL
  standard offpage *
  page227_i112
#ISCELL
  standard offpage *
  page227_i113
#ISCELL
  standard offpage *
  page227_i114
#ISCELL
  standard offpage *
  page227_i115
#ISCELL
  standard offpage *
  page227_i116
#ISCELL
  standard offpage *
  page227_i117
#ISCELL
  standard offpage *
  page227_i118
#ISCELL
  standard offpage *
  page227_i119
#ISCELL
  standard offpage *
  page227_i12
#ISCELL
  standard offpage *
  page227_i120
#ISCELL
  standard offpage *
  page227_i121
#ISCELL
  standard offpage *
  page227_i122
#ISCELL
  standard offpage *
  page227_i123
#ISCELL
  standard offpage *
  page227_i124
#ISCELL
  standard offpage *
  page227_i125
#ISCELL
  logical_power universal_power *
  page227_i126
#ISCELL
  standard offpage *
  page227_i127
#ISCELL
  standard offpage *
  page227_i128
#ISCELL
  standard offpage *
  page227_i129
#ISCELL
  standard offpage *
  page227_i13
#ISCELL
  standard offpage *
  page227_i130
#ISCELL
  standard offpage *
  page227_i131
#ISCELL
  standard offpage *
  page227_i132
#ISCELL
  standard offpage *
  page227_i133
#ISCELL
  standard offpage *
  page227_i134
#ISCELL
  standard offpage *
  page227_i135
#ISCELL
  standard offpage *
  page227_i136
#ISCELL
  standard offpage *
  page227_i137
#ISCELL
  standard offpage *
  page227_i138
#ISCELL
  standard offpage *
  page227_i139
#ISCELL
  standard offpage *
  page227_i14
#ISCELL
  standard offpage *
  page227_i140
#ISCELL
  standard offpage *
  page227_i141
#ISCELL
  standard offpage *
  page227_i142
#ISCELL
  standard offpage *
  page227_i143
#ISCELL
  standard offpage *
  page227_i144
#ISCELL
  standard offpage *
  page227_i145
#ISCELL
  standard offpage *
  page227_i146
#ISCELL
  standard offpage *
  page227_i147
#ISCELL
  standard offpage *
  page227_i148
#ISCELL
  standard offpage *
  page227_i149
#ISCELL
  standard offpage *
  page227_i15
#ISCELL
  standard offpage *
  page227_i150
#ISCELL
  standard offpage *
  page227_i151
#ISCELL
  standard offpage *
  page227_i152
#ISCELL
  standard offpage *
  page227_i153
#ISCELL
  standard offpage *
  page227_i154
#ISCELL
  standard offpage *
  page227_i155
#ISCELL
  standard offpage *
  page227_i156
#ISCELL
  standard offpage *
  page227_i157
#ISCELL
  standard offpage *
  page227_i158
#CELL
  pure_quanta q_res *
  page227_i159
#ISCELL
  standard offpage *
  page227_i16
#ISCELL
  logical_power universal_power *
  page227_i160
#ISCELL
  standard offpage *
  page227_i161
#ISCELL
  standard offpage *
  page227_i162
#ISCELL
  standard offpage *
  page227_i163
#CELL
  pure_quanta q_res *
  page227_i164
#ISCELL
  standard offpage *
  page227_i165
#ISCELL
  standard offpage *
  page227_i166
#CELL
  pure_quanta q_res *
  page227_i167
#ISCELL
  standard offpage *
  page227_i168
#ISCELL
  standard offpage *
  page227_i169
#ISCELL
  standard offpage *
  page227_i17
#ISCELL
  standard offpage *
  page227_i170
#ISCELL
  logical_power universal_gnd *
  page227_i171
#CELL
  pure_quanta q_res *
  page227_i172
#CELL
  pure_quanta sconn168_me1016810202011 *
  page227_i173
#CELL
  pure_quanta q_res *
  page227_i18
#CELL
  pure_quanta q_res *
  page227_i19
#CELL
  pure_quanta q_res *
  page227_i2
#CELL
  pure_quanta q_res *
  page227_i20
#CELL
  pure_quanta q_res *
  page227_i21
#CELL
  pure_quanta q_res *
  page227_i22
#CELL
  pure_quanta q_res *
  page227_i23
#CELL
  pure_quanta q_res *
  page227_i24
#CELL
  pure_quanta q_res *
  page227_i25
#CELL
  pure_quanta q_res *
  page227_i26
#CELL
  pure_quanta q_res *
  page227_i27
#CELL
  pure_quanta q_res *
  page227_i28
#ISCELL
  standard offpage *
  page227_i29
#ISCELL
  standard offpage *
  page227_i3
#ISCELL
  standard offpage *
  page227_i30
#ISCELL
  standard offpage *
  page227_i31
#ISCELL
  standard offpage *
  page227_i32
#ISCELL
  standard offpage *
  page227_i33
#ISCELL
  standard offpage *
  page227_i34
#ISCELL
  standard offpage *
  page227_i35
#ISCELL
  standard offpage *
  page227_i36
#ISCELL
  standard offpage *
  page227_i37
#ISCELL
  standard offpage *
  page227_i38
#ISCELL
  standard offpage *
  page227_i39
#ISCELL
  standard offpage *
  page227_i4
#ISCELL
  logical_power universal_gnd *
  page227_i40
#ISCELL
  logical_power universal_gnd *
  page227_i41
#ISCELL
  standard offpage *
  page227_i42
#ISCELL
  standard offpage *
  page227_i43
#ISCELL
  standard offpage *
  page227_i44
#ISCELL
  standard offpage *
  page227_i45
#ISCELL
  standard offpage *
  page227_i46
#ISCELL
  standard offpage *
  page227_i47
#CELL
  pure_quanta q_res *
  page227_i48
#CELL
  pure_quanta q_res *
  page227_i49
#ISCELL
  standard offpage *
  page227_i5
#ISCELL
  standard offpage *
  page227_i50
#ISCELL
  standard offpage *
  page227_i51
#ISCELL
  standard offpage *
  page227_i52
#ISCELL
  standard offpage *
  page227_i53
#ISCELL
  standard offpage *
  page227_i54
#ISCELL
  standard offpage *
  page227_i55
#ISCELL
  standard offpage *
  page227_i56
#CELL
  pure_quanta q_res *
  page227_i57
#CELL
  pure_quanta q_res *
  page227_i58
#ISCELL
  standard offpage *
  page227_i59
#ISCELL
  standard offpage *
  page227_i6
#ISCELL
  standard offpage *
  page227_i60
#ISCELL
  standard offpage *
  page227_i61
#ISCELL
  standard offpage *
  page227_i62
#ISCELL
  standard offpage *
  page227_i63
#ISCELL
  standard offpage *
  page227_i64
#ISCELL
  standard offpage *
  page227_i65
#ISCELL
  standard offpage *
  page227_i66
#ISCELL
  standard offpage *
  page227_i67
#ISCELL
  standard offpage *
  page227_i68
#ISCELL
  standard offpage *
  page227_i69
#ISCELL
  standard offpage *
  page227_i7
#ISCELL
  standard offpage *
  page227_i70
#ISCELL
  standard offpage *
  page227_i71
#ISCELL
  standard offpage *
  page227_i72
#ISCELL
  standard offpage *
  page227_i73
#ISCELL
  standard offpage *
  page227_i74
#ISCELL
  standard offpage *
  page227_i75
#ISCELL
  standard offpage *
  page227_i76
#ISCELL
  standard offpage *
  page227_i77
#ISCELL
  standard offpage *
  page227_i78
#ISCELL
  standard offpage *
  page227_i79
#ISCELL
  standard offpage *
  page227_i8
#ISCELL
  standard offpage *
  page227_i80
#ISCELL
  logical_power universal_gnd *
  page227_i81
#CELL
  pure_quanta q_cap *
  page227_i82
#ISCELL
  logical_power universal_power *
  page227_i83
#CELL
  pure_quanta q_res *
  page227_i84
#CELL
  pure_quanta q_res *
  page227_i85
#CELL
  pure_quanta q_res *
  page227_i86
#CELL
  pure_quanta q_res *
  page227_i87
#CELL
  pure_quanta q_res *
  page227_i88
#CELL
  pure_quanta q_res *
  page227_i89
#ISCELL
  standard offpage *
  page227_i9
#CELL
  pure_quanta q_res *
  page227_i90
#CELL
  pure_quanta q_res *
  page227_i91
#CELL
  pure_quanta q_res *
  page227_i92
#CELL
  pure_quanta q_res *
  page227_i93
#CELL
  pure_quanta q_res *
  page227_i94
#CELL
  pure_quanta q_res *
  page227_i95
#CELL
  pure_quanta q_res *
  page227_i96
#CELL
  pure_quanta q_res *
  page227_i97
#CELL
  pure_quanta q_res *
  page227_i98
#CELL
  pure_quanta q_res *
  page227_i99
#ISCELL
  logical_power cad_note *
  *
#ISCELL
  mstr_misc dns *
  *
#ISCELL
  pure_quanta quanta_title_block_c *
  *
#ISCELL
  logical_power universal_power *
  page228_i1
#ISCELL
  standard offpage *
  page228_i10
#ISCELL
  standard offpage *
  page228_i100
#ISCELL
  standard offpage *
  page228_i101
#ISCELL
  standard offpage *
  page228_i11
#ISCELL
  standard offpage *
  page228_i12
#ISCELL
  standard offpage *
  page228_i13
#ISCELL
  standard offpage *
  page228_i16
#ISCELL
  standard offpage *
  page228_i17
#CELL
  pure_quanta q_res *
  page228_i172
#CELL
  pure_quanta q_res *
  page228_i173
#CELL
  pure_quanta q_res *
  page228_i176
#CELL
  pure_quanta q_res *
  page228_i177
#ISCELL
  standard offpage *
  page228_i178
#ISCELL
  standard offpage *
  page228_i179
#ISCELL
  standard offpage *
  page228_i18
#ISCELL
  standard offpage *
  page228_i182
#ISCELL
  standard offpage *
  page228_i183
#ISCELL
  standard offpage *
  page228_i19
#ISCELL
  standard offpage *
  page228_i199
#CELL
  pure_quanta q_res *
  page228_i2
#ISCELL
  standard offpage *
  page228_i20
#ISCELL
  standard offpage *
  page228_i201
#CELL
  pure_quanta q_res *
  page228_i202
#CELL
  pure_quanta q_res *
  page228_i203
#ISCELL
  standard offpage *
  page228_i204
#ISCELL
  standard offpage *
  page228_i205
#CELL
  pure_quanta q_res *
  page228_i206
#CELL
  pure_quanta q_res *
  page228_i207
#ISCELL
  standard offpage *
  page228_i208
#ISCELL
  standard offpage *
  page228_i209
#ISCELL
  standard offpage *
  page228_i21
#ISCELL
  standard offpage *
  page228_i210
#ISCELL
  standard offpage *
  page228_i211
#ISCELL
  standard offpage *
  page228_i214
#ISCELL
  standard offpage *
  page228_i215
#CELL
  pure_quanta q_res *
  page228_i216
#CELL
  pure_quanta q_res *
  page228_i217
#CELL
  pure_quanta q_res *
  page228_i218
#CELL
  pure_quanta q_res *
  page228_i219
#ISCELL
  standard offpage *
  page228_i22
#ISCELL
  standard offpage *
  page228_i226
#ISCELL
  standard offpage *
  page228_i227
#CELL
  pure_quanta q_res *
  page228_i228
#CELL
  pure_quanta q_res *
  page228_i229
#ISCELL
  standard offpage *
  page228_i23
#CELL
  pure_quanta q_res *
  page228_i230
#CELL
  pure_quanta q_res *
  page228_i231
#ISCELL
  standard offpage *
  page228_i232
#ISCELL
  standard offpage *
  page228_i233
#CELL
  pure_quanta q_res *
  page228_i234
#ISCELL
  standard offpage *
  page228_i235
#ISCELL
  standard offpage *
  page228_i236
#CELL
  pure_quanta q_res *
  page228_i237
#ISCELL
  standard offpage *
  page228_i238
#ISCELL
  standard offpage *
  page228_i239
#ISCELL
  standard offpage *
  page228_i240
#ISCELL
  standard offpage *
  page228_i241
#CELL
  pure_quanta q_res *
  page228_i242
#CELL
  pure_quanta q_res *
  page228_i243
#CELL
  pure_quanta q_res *
  page228_i250
#CELL
  pure_quanta q_res *
  page228_i251
#ISCELL
  standard offpage *
  page228_i252
#ISCELL
  standard offpage *
  page228_i253
#ISCELL
  standard offpage *
  page228_i254
#ISCELL
  standard offpage *
  page228_i255
#ISCELL
  standard offpage *
  page228_i256
#ISCELL
  standard offpage *
  page228_i257
#CELL
  pure_quanta q_res *
  page228_i258
#CELL
  pure_quanta q_res *
  page228_i259
#CELL
  pure_quanta q_res *
  page228_i260
#CELL
  pure_quanta q_res *
  page228_i261
#ISCELL
  standard offpage *
  page228_i262
#ISCELL
  standard offpage *
  page228_i263
#CELL
  pure_quanta q_res *
  page228_i264
#ISCELL
  standard offpage *
  page228_i266
#ISCELL
  standard offpage *
  page228_i267
#CELL
  pure_quanta q_res *
  page228_i268
#ISCELL
  standard offpage *
  page228_i269
#ISCELL
  standard offpage *
  page228_i270
#CELL
  pure_quanta q_res *
  page228_i271
#CELL
  pure_quanta q_res *
  page228_i272
#CELL
  pure_quanta q_res *
  page228_i273
#CELL
  pure_quanta q_res *
  page228_i274
#ISCELL
  standard offpage *
  page228_i275
#ISCELL
  standard offpage *
  page228_i276
#ISCELL
  standard offpage *
  page228_i277
#ISCELL
  standard offpage *
  page228_i278
#ISCELL
  standard offpage *
  page228_i28
#CELL
  pure_quanta q_res *
  page228_i284
#CELL
  pure_quanta q_res *
  page228_i285
#ISCELL
  standard offpage *
  page228_i286
#ISCELL
  standard offpage *
  page228_i287
#ISCELL
  standard offpage *
  page228_i288
#ISCELL
  standard offpage *
  page228_i289
#ISCELL
  standard offpage *
  page228_i29
#ISCELL
  standard offpage *
  page228_i290
#ISCELL
  standard offpage *
  page228_i291
#CELL
  pure_quanta q_res *
  page228_i293
#ISCELL
  standard offpage *
  page228_i294
#ISCELL
  standard offpage *
  page228_i295
#CELL
  pure_quanta q_res *
  page228_i296
#ISCELL
  standard offpage *
  page228_i299
#CELL
  pure_quanta q_res *
  page228_i3
#ISCELL
  standard offpage *
  page228_i30
#ISCELL
  standard offpage *
  page228_i300
#ISCELL
  standard offpage *
  page228_i301
#ISCELL
  standard offpage *
  page228_i302
#CELL
  pure_quanta q_res *
  page228_i303
#CELL
  pure_quanta q_res *
  page228_i304
#CELL
  pure_quanta q_res *
  page228_i305
#CELL
  pure_quanta q_res *
  page228_i306
#ISCELL
  standard offpage *
  page228_i307
#ISCELL
  standard offpage *
  page228_i308
#ISCELL
  standard offpage *
  page228_i309
#ISCELL
  standard offpage *
  page228_i31
#ISCELL
  standard offpage *
  page228_i310
#CELL
  pure_quanta q_res *
  page228_i311
#CELL
  pure_quanta q_res *
  page228_i312
#CELL
  pure_quanta q_res *
  page228_i313
#CELL
  pure_quanta q_res *
  page228_i314
#CELL
  pure_quanta q_res *
  page228_i315
#CELL
  pure_quanta q_res *
  page228_i316
#CELL
  pure_quanta q_res *
  page228_i317
#CELL
  pure_quanta q_res *
  page228_i318
#ISCELL
  standard offpage *
  page228_i32
#ISCELL
  standard offpage *
  page228_i33
#ISCELL
  standard offpage *
  page228_i34
#ISCELL
  standard offpage *
  page228_i35
#CELL
  pure_quanta q_res *
  page228_i38
#CELL
  pure_quanta q_res *
  page228_i39
#CELL
  pure_quanta q_res *
  page228_i4
#CELL
  pure_quanta q_res *
  page228_i40
#CELL
  pure_quanta q_res *
  page228_i41
#CELL
  pure_quanta q_res *
  page228_i42
#CELL
  pure_quanta q_res *
  page228_i43
#CELL
  pure_quanta q_res *
  page228_i44
#CELL
  pure_quanta q_res *
  page228_i45
#CELL
  pure_quanta q_res *
  page228_i5
#ISCELL
  standard offpage *
  page228_i52
#ISCELL
  standard offpage *
  page228_i53
#ISCELL
  standard offpage *
  page228_i54
#ISCELL
  standard offpage *
  page228_i55
#ISCELL
  standard offpage *
  page228_i56
#ISCELL
  standard offpage *
  page228_i57
#CELL
  pure_quanta q_res *
  page228_i6
#ISCELL
  standard offpage *
  page228_i66
#ISCELL
  standard offpage *
  page228_i67
#ISCELL
  standard offpage *
  page228_i68
#ISCELL
  standard offpage *
  page228_i69
#CELL
  pure_quanta q_res *
  page228_i7
#ISCELL
  standard offpage *
  page228_i70
#ISCELL
  standard offpage *
  page228_i71
#ISCELL
  standard offpage *
  page228_i72
#ISCELL
  standard offpage *
  page228_i73
#ISCELL
  standard offpage *
  page228_i8
#CELL
  pure_quanta q_res *
  page228_i89
#ISCELL
  standard offpage *
  page228_i9
#CELL
  pure_quanta q_res *
  page228_i90
#ISCELL
  standard offpage *
  page228_i91
#ISCELL
  standard offpage *
  page228_i92
#ISCELL
  mstr_misc dns *
  *
#ISCELL
  pure_quanta quanta_title_block_c *
  *
#ISCELL
  standard offpage *
  page229_i1
#ISCELL
  logical_power universal_gnd *
  page229_i10
#CELL
  pure_quanta q_res *
  page229_i11
#CELL
  pure_quanta q_res *
  page229_i12
#ISCELL
  logical_power gnd *
  page229_i13
#CELL
  pure_quanta q_res *
  page229_i14
#ISCELL
  standard offpage *
  page229_i15
#ISCELL
  logical_power universal_power *
  page229_i16
#CELL
  pure_quanta q_res *
  page229_i17
#CELL
  pure_quanta q_res *
  page229_i18
#ISCELL
  logical_power universal_power *
  page229_i19
#CELL
  pure_quanta q_res *
  page229_i2
#CELL
  pure_quanta q_res *
  page229_i20
#CELL
  pure_quanta mosfet_nch_dual *
  page229_i21
#ISCELL
  logical_power gnd *
  page229_i22
#ISCELL
  logical_power gnd *
  page229_i23
#CELL
  pure_quanta q_res *
  page229_i24
#ISCELL
  logical_power universal_power *
  page229_i25
#CELL
  pure_quanta mosfet_nch_dual *
  page229_i26
#CELL
  pure_quanta q_res *
  page229_i27
#ISCELL
  logical_power gnd *
  page229_i28
#CELL
  pure_quanta diode_tvs *
  page229_i29
#CELL
  pure_quanta q_res *
  page229_i3
#ISCELL
  logical_power universal_power *
  page229_i30
#CELL
  pure_quanta q_cap *
  page229_i31
#ISCELL
  logical_power gnd *
  page229_i32
#CELL
  pure_quanta q_cap *
  page229_i33
#CELL
  pure_quanta q_res *
  page229_i34
#ISCELL
  logical_power gnd *
  page229_i35
#ISCELL
  logical_power gnd *
  page229_i36
#CELL
  pure_quanta q_cap *
  page229_i37
#ISCELL
  logical_power universal_power *
  page229_i38
#CELL
  pure_quanta q_res *
  page229_i39
#ISCELL
  logical_power gnd *
  page229_i4
#CELL
  pure_quanta q_cap *
  page229_i42
#ISCELL
  logical_power gnd *
  page229_i43
#CELL
  pure_quanta q_res *
  page229_i44
#ISCELL
  logical_power gnd *
  page229_i45
#ISCELL
  standard offpage *
  page229_i46
#ISCELL
  standard offpage *
  page229_i47
#CELL
  pure_quanta q_res *
  page229_i48
#ISCELL
  logical_power vccaux15 *
  page229_i49
#ISCELL
  logical_power gnd *
  page229_i5
#CELL
  pure_quanta q_res *
  page229_i50
#CELL
  pure_quanta q_res *
  page229_i51
#CELL
  pure_quanta q_res *
  page229_i52
#CELL
  pure_quanta q_cap *
  page229_i53
#CELL
  pure_quanta q_res *
  page229_i54
#ISCELL
  logical_power universal_power *
  page229_i55
#ISCELL
  logical_power gnd *
  page229_i56
#CELL
  pure_quanta q_cap *
  page229_i57
#ISCELL
  logical_power universal_power *
  page229_i58
#ISCELL
  standard offpage *
  page229_i59
#ISCELL
  logical_power gnd *
  page229_i6
#ISCELL
  logical_power gnd *
  page229_i60
#CELL
  pure_quanta q_res *
  page229_i61
#ISCELL
  logical_power gnd *
  page229_i62
#CELL
  pure_quanta q_res *
  page229_i63
#CELL
  pure_quanta q_res *
  page229_i64
#ISCELL
  logical_power gnd *
  page229_i65
#CELL
  pure_quanta q_cap *
  page229_i66
#CELL
  pure_quanta q_res *
  page229_i67
#CELL
  pure_quanta q_cap *
  page229_i68
#CELL
  pure_quanta max15090bewit *
  page229_i69
#CELL
  pure_quanta q_cap *
  page229_i7
#CELL
  pure_quanta q_res *
  page229_i70
#ISCELL
  logical_power gnd *
  page229_i71
#CELL
  pure_quanta q_res *
  page229_i72
#CELL
  pure_quanta q_cap *
  page229_i73
#CELL
  pure_quanta q_res *
  page229_i74
#CELL
  pure_quanta q_cap *
  page229_i75
#CELL
  pure_quanta q_res *
  page229_i76
#CELL
  pure_quanta q_res *
  page229_i77
#ISCELL
  logical_power gnd *
  page229_i78
#CELL
  pure_quanta q_res *
  page229_i79
#CELL
  pure_quanta q_cap *
  page229_i8
#ISCELL
  logical_power vccaux15 *
  page229_i80
#CELL
  pure_quanta q_res *
  page229_i81
#CELL
  pure_quanta schottky_ac *
  page229_i82
#CELL
  pure_quanta q_cap *
  page229_i83
#CELL
  pure_quanta q_cap *
  page229_i84
#ISCELL
  standard offpage *
  page229_i85
#ISCELL
  standard offpage *
  page229_i86
#ISCELL
  logical_power gnd *
  page229_i87
#CELL
  pure_quanta q_cap *
  page229_i88
#ISCELL
  logical_power universal_power *
  page229_i89
#CELL
  pure_quanta mosfet_nch_gds_esd_protected *
  page229_i9
#CELL
  pure_quanta rs31312r *
  page229_i90
#CELL
  pure_quanta q_res *
  page229_i91
#CELL
  pure_quanta q_res *
  page229_i92
#ISCELL
  logical_power vccaux15 *
  page229_i93
#ISCELL
  standard offpage *
  page229_i94
#ISCELL
  mstr_misc dns *
  *
#ISCELL
  pure_quanta quanta_title_block_c *
  *
#CELL
  pure_quanta m24128bwmn6tp *
  page231_i35
#ISCELL
  standard offpage *
  page231_i40
#ISCELL
  standard offpage *
  page231_i41
#CELL
  pure_quanta q_res *
  page231_i45
#CELL
  pure_quanta q_res *
  page231_i47
#ISCELL
  logical_power universal_gnd *
  page231_i49
#CELL
  pure_quanta q_res *
  page231_i50
#ISCELL
  logical_power universal_gnd *
  page231_i51
#CELL
  pure_quanta q_res *
  page231_i52
#ISCELL
  logical_power universal_gnd *
  page231_i53
#ISCELL
  logical_power universal_power *
  page231_i54
#CELL
  pure_quanta q_cap *
  page231_i55
#ISCELL
  logical_power universal_gnd *
  page231_i56
#CELL
  pure_quanta q_res *
  page231_i57
#ISCELL
  logical_power universal_gnd *
  page231_i58
#ISCELL
  logical_power universal_gnd *
  page231_i59
#ISCELL
  logical_power universal_power *
  page231_i60
#CELL
  pure_quanta q_res *
  page231_i61
#CELL
  pure_quanta q_res *
  page231_i62
#CELL
  pure_quanta q_res *
  page231_i93
#CELL
  pure_quanta q_res *
  page231_i95
#ISCELL
  logical_power universal_power *
  page231_i96
#ISCELL
  logical_power bom_note *
  *
#ISCELL
  logical_power cad_note *
  *
#ISCELL
  mstr_misc dns *
  *
#ISCELL
  pure_quanta quanta_title_block_c *
  *
#ISCELL
  standard offpage *
  page232_i1
#ISCELL
  logical_power universal_gnd *
  page232_i10
#CELL
  pure_quanta 74lvc1g07se7 *
  page232_i11
#ISCELL
  logical_power universal_power *
  page232_i12
#CELL
  pure_quanta q_res *
  page232_i13
#CELL
  pure_quanta mosfet_nch_gds_esd_protected *
  page232_i14
#ISCELL
  logical_power universal_gnd *
  page232_i15
#CELL
  pure_quanta q_res *
  page232_i16
#ISCELL
  logical_power universal_gnd *
  page232_i17
#CELL
  pure_quanta q_res *
  page232_i18
#ISCELL
  logical_power universal_power *
  page232_i19
#ISCELL
  logical_power universal_gnd *
  page232_i2
#CELL
  pure_quanta q_res *
  page232_i20
#CELL
  pure_quanta q_res *
  page232_i21
#CELL
  pure_quanta q_res *
  page232_i22
#ISCELL
  logical_power universal_gnd *
  page232_i23
#CELL
  pure_quanta q_cap *
  page232_i24
#ISCELL
  standard offpage *
  page232_i25
#CELL
  pure_quanta tps3895adryr *
  page232_i26
#CELL
  pure_quanta adm1086akszreel7 *
  page232_i27
#ISCELL
  logical_power universal_power *
  page232_i28
#ISCELL
  logical_power universal_power *
  page232_i29
#CELL
  pure_quanta q_res *
  page232_i3
#ISCELL
  logical_power universal_gnd *
  page232_i30
#CELL
  pure_quanta q_res *
  page232_i31
#CELL
  pure_quanta q_res *
  page232_i32
#CELL
  pure_quanta q_res *
  page232_i33
#ISCELL
  logical_power universal_gnd *
  page232_i34
#CELL
  pure_quanta q_cap *
  page232_i35
#CELL
  pure_quanta q_res *
  page232_i36
#ISCELL
  logical_power universal_power *
  page232_i37
#ISCELL
  logical_power universal_gnd *
  page232_i38
#CELL
  pure_quanta mosfet_nch_gds_esd_protected *
  page232_i39
#CELL
  pure_quanta q_res *
  page232_i4
#CELL
  pure_quanta q_res *
  page232_i40
#ISCELL
  logical_power universal_power *
  page232_i41
#ISCELL
  standard offpage *
  page232_i42
#ISCELL
  standard offpage *
  page232_i43
#ISCELL
  standard offpage *
  page232_i44
#ISCELL
  logical_power universal_gnd *
  page232_i45
#ISCELL
  logical_power universal_gnd *
  page232_i46
#CELL
  pure_quanta q_cap *
  page232_i47
#ISCELL
  standard offpage *
  page232_i48
#ISCELL
  logical_power universal_power *
  page232_i5
#ISCELL
  logical_power universal_gnd *
  page232_i6
#CELL
  pure_quanta q_cap *
  page232_i7
#ISCELL
  logical_power universal_gnd *
  page232_i8
#CELL
  pure_quanta q_cap *
  page232_i9
#ISCELL
  mstr_misc dns *
  *
#ISCELL
  pure_quanta quanta_title_block_c *
  *
#ISCELL
  standard offpage *
  page233_i1
#CELL
  pure_quanta q_res *
  page233_i10
#ISCELL
  logical_power universal_gnd *
  page233_i11
#CELL
  pure_quanta conn60_101062636003k02lf *
  page233_i12
#ISCELL
  logical_power universal_gnd *
  page233_i13
#CELL
  pure_quanta q_res *
  page233_i14
#CELL
  pure_quanta q_res *
  page233_i15
#CELL
  pure_quanta ltc4307cms8 *
  page233_i16
#ISCELL
  logical_power universal_gnd *
  page233_i17
#ISCELL
  logical_power universal_power *
  page233_i18
#CELL
  pure_quanta q_cap *
  page233_i19
#ISCELL
  logical_power universal_gnd *
  page233_i2
#CELL
  pure_quanta q_res *
  page233_i20
#CELL
  pure_quanta q_res *
  page233_i21
#CELL
  pure_quanta q_res *
  page233_i22
#ISCELL
  logical_power universal_power *
  page233_i23
#CELL
  pure_quanta q_res *
  page233_i24
#ISCELL
  standard offpage *
  page233_i25
#ISCELL
  standard offpage *
  page233_i26
#ISCELL
  standard offpage *
  page233_i27
#ISCELL
  standard offpage *
  page233_i28
#ISCELL
  standard offpage *
  page233_i29
#CELL
  pure_quanta q_res *
  page233_i3
#ISCELL
  standard offpage *
  page233_i30
#ISCELL
  standard offpage *
  page233_i31
#ISCELL
  standard offpage *
  page233_i32
#ISCELL
  standard offpage *
  page233_i33
#CELL
  pure_quanta q_res *
  page233_i34
#CELL
  pure_quanta q_res *
  page233_i35
#ISCELL
  logical_power universal_power *
  page233_i36
#CELL
  pure_quanta q_res *
  page233_i37
#CELL
  pure_quanta q_res *
  page233_i38
#CELL
  pure_quanta q_res *
  page233_i39
#CELL
  pure_quanta q_res *
  page233_i4
#ISCELL
  standard offpage *
  page233_i40
#CELL
  pure_quanta q_res *
  page233_i41
#ISCELL
  logical_power universal_power *
  page233_i42
#ISCELL
  standard offpage *
  page233_i43
#ISCELL
  standard offpage *
  page233_i44
#ISCELL
  standard offpage *
  page233_i45
#ISCELL
  standard offpage *
  page233_i46
#ISCELL
  standard offpage *
  page233_i47
#ISCELL
  standard offpage *
  page233_i48
#ISCELL
  standard offpage *
  page233_i49
#ISCELL
  logical_power universal_power *
  page233_i5
#ISCELL
  standard offpage *
  page233_i50
#CELL
  pure_quanta q_cap *
  page233_i51
#CELL
  pure_quanta q_cap *
  page233_i52
#CELL
  pure_quanta q_cap *
  page233_i53
#CELL
  pure_quanta q_cap *
  page233_i54
#CELL
  pure_quanta q_cap *
  page233_i55
#ISCELL
  logical_power universal_gnd *
  page233_i56
#CELL
  pure_quanta q_cap *
  page233_i57
#ISCELL
  standard offpage *
  page233_i6
#ISCELL
  standard offpage *
  page233_i7
#CELL
  pure_quanta q_res *
  page233_i8
#CELL
  pure_quanta q_res *
  page233_i9
#ISCELL
  mstr_misc dns *
  *
#ISCELL
  pure_quanta quanta_title_block_c *
  *
#ISCELL
  logical_power universal_power *
  page230_i10
#ISCELL
  logical_power universal_gnd *
  page230_i12
#ISCELL
  logical_power universal_gnd *
  page230_i13
#CELL
  pure_quanta q_cap *
  page230_i14
#ISCELL
  logical_power universal_power *
  page230_i15
#ISCELL
  logical_power universal_gnd *
  page230_i22
#CELL
  pure_quanta q_res *
  page230_i24
#CELL
  pure_quanta q_res *
  page230_i25
#ISCELL
  logical_power universal_power *
  page230_i26
#ISCELL
  standard offpage *
  page230_i27
#CELL
  pure_quanta q_res *
  page230_i28
#CELL
  pure_quanta q_res *
  page230_i29
#CELL
  pure_quanta q_res *
  page230_i30
#CELL
  pure_quanta 74lvc1g08w57 *
  page230_i31
#CELL
  pure_quanta q_res *
  page230_i34
#ISCELL
  standard offpage *
  page230_i35
#ISCELL
  logical_power universal_gnd *
  page230_i36
#CELL
  pure_quanta 74lvc2g07dw7 *
  page230_i37
#ISCELL
  logical_power universal_power *
  page230_i38
#ISCELL
  logical_power universal_gnd *
  page230_i39
#CELL
  pure_quanta q_cap *
  page230_i40
#CELL
  pure_quanta q_res *
  page230_i41
#ISCELL
  standard offpage *
  page230_i42
#CELL
  pure_quanta q_res *
  page230_i43
#ISCELL
  logical_power universal_gnd *
  page230_i44
#ISCELL
  standard offpage *
  page230_i45
#ISCELL
  logical_power universal_power *
  page230_i46
#CELL
  pure_quanta q_res *
  page230_i47
#CELL
  pure_quanta q_res *
  page230_i48
#ISCELL
  standard offpage *
  page230_i49
#CELL
  pure_quanta q_res *
  page230_i50
#CELL
  pure_quanta q_res *
  page230_i51
#ISCELL
  logical_power universal_power *
  page230_i52
#CELL
  pure_quanta mosfet_nch_dual *
  page230_i53
#ISCELL
  logical_power universal_gnd *
  page230_i54
#CELL
  pure_quanta q_res *
  page230_i55
#ISCELL
  logical_power universal_power *
  page230_i56
#ISCELL
  logical_power universal_gnd *
  page230_i57
#CELL
  pure_quanta mosfet_nch_dual *
  page230_i58
#CELL
  pure_quanta q_res *
  page230_i59
#ISCELL
  logical_power universal_gnd *
  page230_i6
#ISCELL
  logical_power universal_power *
  page230_i60
#ISCELL
  logical_power universal_gnd *
  page230_i61
#CELL
  pure_quanta q_cap *
  page230_i62
#ISCELL
  standard offpage *
  page230_i63
#ISCELL
  logical_power universal_gnd *
  page230_i64
#ISCELL
  standard offpage *
  page230_i7
#ISCELL
  pure_quanta quanta_title_block_c *
  *
#ISCELL
  standard offpage *
  page234_i1
#CELL
  pure_quanta q_res *
  page234_i10
#ISCELL
  logical_power universal_power *
  page234_i11
#CELL
  pure_quanta mosfet_nch_gds_esd_protected *
  page234_i14
#ISCELL
  logical_power universal_gnd *
  page234_i15
#CELL
  pure_quanta q_res *
  page234_i3
#ISCELL
  logical_power universal_gnd *
  page234_i5
#CELL
  pure_quanta mosfet_nch_gds_esd_protected *
  page234_i6
#CELL
  pure_quanta q_res *
  page234_i7
#CELL
  pure_quanta q_res *
  page234_i8
#ISCELL
  logical_power universal_power *
  page234_i9
#ISCELL
  mstr_misc dns *
  *
#ISCELL
  pure_quanta quanta_title_block_c *
  *
#ISCELL
  logical_power universal_gnd *
  page235_i1
#ISCELL
  logical_power universal_gnd *
  page235_i10
#CELL
  pure_quanta q_res *
  page235_i11
#ISCELL
  logical_power universal_power *
  page235_i12
#CELL
  pure_quanta conn3_210hp1030br1 *
  page235_i13
#CELL
  pure_quanta q_res *
  page235_i14
#CELL
  pure_quanta q_res *
  page235_i15
#CELL
  pure_quanta q_res *
  page235_i16
#CELL
  pure_quanta q_res *
  page235_i17
#CELL
  pure_quanta q_res *
  page235_i18
#CELL
  pure_quanta 74cbtlv3126pw *
  page235_i19
#ISCELL
  standard offpage *
  page235_i2
#ISCELL
  logical_power universal_gnd *
  page235_i20
#ISCELL
  logical_power universal_power *
  page235_i21
#ISCELL
  logical_power universal_gnd *
  page235_i22
#CELL
  pure_quanta q_cap *
  page235_i23
#CELL
  pure_quanta q_res *
  page235_i24
#CELL
  pure_quanta q_res *
  page235_i25
#CELL
  pure_quanta q_res *
  page235_i26
#CELL
  pure_quanta q_res *
  page235_i27
#ISCELL
  standard offpage *
  page235_i28
#ISCELL
  standard offpage *
  page235_i29
#CELL
  pure_quanta q_res *
  page235_i3
#ISCELL
  standard offpage *
  page235_i30
#ISCELL
  standard offpage *
  page235_i31
#CELL
  pure_quanta q_res *
  page235_i4
#ISCELL
  logical_power universal_power *
  page235_i5
#ISCELL
  standard offpage *
  page235_i6
#ISCELL
  standard offpage *
  page235_i7
#ISCELL
  standard offpage *
  page235_i8
#ISCELL
  standard offpage *
  page235_i9
#ISCELL
  pure_quanta quanta_title_block_c *
  *
#ISCELL
  logical_power cad_note *
  *
#ISCELL
  mstr_misc dns *
  *
#ISCELL
  pure_quanta quanta_title_block_c *
  *
#ISCELL
  logical_power universal_gnd *
  page239_i101
#ISCELL
  logical_power universal_gnd *
  page239_i102
#CELL
  pure_quanta adc128d818cimtxnopb *
  page239_i103
#ISCELL
  standard offpage *
  page239_i108
#ISCELL
  standard offpage *
  page239_i109
#CELL
  pure_quanta q_res *
  page239_i110
#CELL
  pure_quanta q_res *
  page239_i111
#ISCELL
  standard offpage *
  page239_i112
#ISCELL
  standard offpage *
  page239_i113
#ISCELL
  standard offpage *
  page239_i114
#ISCELL
  standard offpage *
  page239_i115
#ISCELL
  logical_power universal_power *
  page239_i117
#CELL
  pure_quanta q_inductor *
  page239_i118
#ISCELL
  standard offpage *
  page239_i125
#ISCELL
  standard offpage *
  page239_i126
#CELL
  pure_quanta q_cap *
  page239_i127
#CELL
  pure_quanta q_cap *
  page239_i128
#CELL
  pure_quanta q_res *
  page239_i129
#ISCELL
  logical_power universal_gnd *
  page239_i130
#CELL
  pure_quanta q_res *
  page239_i131
#ISCELL
  logical_power universal_gnd *
  page239_i132
#ISCELL
  logical_power universal_gnd *
  page239_i133
#ISCELL
  logical_power universal_power *
  page239_i140
#CELL
  pure_quanta q_res *
  page239_i141
#CELL
  pure_quanta q_res *
  page239_i149
#ISCELL
  logical_power universal_gnd *
  page239_i150
#ISCELL
  logical_power universal_power *
  page239_i160
#CELL
  pure_quanta q_res *
  page239_i161
#CELL
  pure_quanta q_res *
  page239_i162
#CELL
  pure_quanta q_res *
  page239_i163
#ISCELL
  logical_power universal_power *
  page239_i167
#CELL
  pure_quanta q_res *
  page239_i168
#ISCELL
  logical_power universal_power *
  page239_i172
#CELL
  pure_quanta q_res *
  page239_i173
#CELL
  pure_quanta q_res *
  page239_i174
#CELL
  pure_quanta q_res *
  page239_i176
#ISCELL
  standard offpage *
  page239_i177
#ISCELL
  standard offpage *
  page239_i178
#CELL
  pure_quanta q_res *
  page239_i179
#CELL
  pure_quanta q_cap *
  page239_i180
#CELL
  pure_quanta q_cap *
  page239_i181
#ISCELL
  logical_power universal_gnd *
  page239_i182
#ISCELL
  logical_power universal_gnd *
  page239_i183
#ISCELL
  standard offpage *
  page239_i184
#ISCELL
  standard offpage *
  page239_i185
#ISCELL
  logical_power universal_gnd *
  page239_i186
#CELL
  pure_quanta q_cap *
  page239_i187
#CELL
  pure_quanta q_cap *
  page239_i188
#ISCELL
  logical_power universal_gnd *
  page239_i189
#CELL
  pure_quanta q_res *
  page239_i19
#CELL
  pure_quanta q_res *
  page239_i190
#CELL
  pure_quanta q_res *
  page239_i191
#ISCELL
  logical_power universal_gnd *
  page239_i192
#ISCELL
  standard offpage *
  page239_i193
#ISCELL
  standard offpage *
  page239_i194
#ISCELL
  logical_power universal_gnd *
  page239_i195
#CELL
  pure_quanta q_cap *
  page239_i196
#CELL
  pure_quanta q_cap *
  page239_i197
#ISCELL
  logical_power universal_gnd *
  page239_i198
#CELL
  pure_quanta q_res *
  page239_i199
#CELL
  pure_quanta q_res *
  page239_i20
#CELL
  pure_quanta q_res *
  page239_i200
#ISCELL
  logical_power universal_gnd *
  page239_i201
#ISCELL
  logical_power universal_gnd *
  page239_i202
#ISCELL
  standard offpage *
  page239_i203
#ISCELL
  standard offpage *
  page239_i204
#CELL
  pure_quanta q_cap *
  page239_i205
#ISCELL
  logical_power universal_gnd *
  page239_i206
#CELL
  pure_quanta q_cap *
  page239_i207
#ISCELL
  logical_power universal_gnd *
  page239_i208
#CELL
  pure_quanta q_res *
  page239_i209
#ISCELL
  standard offpage *
  page239_i21
#CELL
  pure_quanta q_res *
  page239_i210
#ISCELL
  standard offpage *
  page239_i214
#ISCELL
  standard offpage *
  page239_i218
#ISCELL
  standard offpage *
  page239_i22
#ISCELL
  logical_power universal_gnd *
  page239_i222
#CELL
  pure_quanta q_res *
  page239_i223
#CELL
  pure_quanta q_res *
  page239_i224
#ISCELL
  logical_power universal_power *
  page239_i225
#ISCELL
  logical_power universal_gnd *
  page239_i226
#CELL
  pure_quanta q_res *
  page239_i227
#CELL
  pure_quanta q_res *
  page239_i228
#ISCELL
  standard offpage *
  page239_i229
#ISCELL
  standard offpage *
  page239_i23
#ISCELL
  standard offpage *
  page239_i230
#ISCELL
  standard offpage *
  page239_i231
#ISCELL
  standard offpage *
  page239_i232
#ISCELL
  standard offpage *
  page239_i233
#ISCELL
  standard offpage *
  page239_i234
#ISCELL
  standard offpage *
  page239_i235
#CELL
  pure_quanta q_cap *
  page239_i236
#ISCELL
  logical_power universal_gnd *
  page239_i237
#CELL
  pure_quanta q_cap *
  page239_i238
#ISCELL
  logical_power universal_gnd *
  page239_i239
#ISCELL
  standard offpage *
  page239_i24
#CELL
  pure_quanta q_res *
  page239_i240
#CELL
  pure_quanta q_res *
  page239_i241
#ISCELL
  standard offpage *
  page239_i288
#ISCELL
  standard offpage *
  page239_i289
#ISCELL
  standard offpage *
  page239_i290
#ISCELL
  standard offpage *
  page239_i291
#ISCELL
  standard offpage *
  page239_i292
#ISCELL
  standard offpage *
  page239_i293
#ISCELL
  standard offpage *
  page239_i294
#ISCELL
  standard offpage *
  page239_i295
#ISCELL
  standard offpage *
  page239_i297
#ISCELL
  standard offpage *
  page239_i298
#ISCELL
  standard offpage *
  page239_i299
#ISCELL
  standard offpage *
  page239_i300
#ISCELL
  standard offpage *
  page239_i301
#ISCELL
  standard offpage *
  page239_i302
#ISCELL
  logical_power universal_gnd *
  page239_i303
#CELL
  pure_quanta q_cap *
  page239_i304
#CELL
  pure_quanta q_cap *
  page239_i305
#ISCELL
  logical_power universal_gnd *
  page239_i306
#ISCELL
  standard offpage *
  page239_i307
#ISCELL
  standard offpage *
  page239_i308
#CELL
  pure_quanta q_cap *
  page239_i309
#ISCELL
  logical_power universal_gnd *
  page239_i310
#CELL
  pure_quanta q_cap *
  page239_i311
#ISCELL
  logical_power universal_gnd *
  page239_i312
#CELL
  pure_quanta q_res *
  page239_i313
#CELL
  pure_quanta q_res *
  page239_i314
#CELL
  pure_quanta q_res *
  page239_i315
#CELL
  pure_quanta q_res *
  page239_i316
#ISCELL
  standard offpage *
  page239_i317
#ISCELL
  standard offpage *
  page239_i318
#ISCELL
  standard offpage *
  page239_i319
#ISCELL
  standard offpage *
  page239_i320
#CELL
  pure_quanta q_res *
  page239_i321
#CELL
  pure_quanta q_res *
  page239_i322
#CELL
  pure_quanta q_res *
  page239_i323
#CELL
  pure_quanta q_res *
  page239_i324
#ISCELL
  standard offpage *
  page239_i325
#ISCELL
  standard offpage *
  page239_i326
#ISCELL
  standard offpage *
  page239_i327
#ISCELL
  standard offpage *
  page239_i328
#ISCELL
  standard offpage *
  page239_i329
#CELL
  pure_quanta q_res *
  page239_i330
#ISCELL
  standard offpage *
  page239_i331
#ISCELL
  standard offpage *
  page239_i332
#CELL
  pure_quanta q_cap *
  page239_i333
#ISCELL
  logical_power universal_gnd *
  page239_i334
#ISCELL
  logical_power universal_gnd *
  page239_i335
#CELL
  pure_quanta q_cap *
  page239_i336
#CELL
  pure_quanta q_res *
  page239_i337
#CELL
  pure_quanta q_res *
  page239_i338
#CELL
  pure_quanta q_res *
  page239_i339
#ISCELL
  standard offpage *
  page239_i340
#ISCELL
  standard offpage *
  page239_i341
#ISCELL
  standard offpage *
  page239_i342
#ISCELL
  standard offpage *
  page239_i343
#ISCELL
  standard offpage *
  page239_i344
#CELL
  pure_quanta q_res *
  page239_i346
#ISCELL
  logical_power universal_gnd *
  page239_i347
#CELL
  pure_quanta q_res *
  page239_i348
#CELL
  pure_quanta max11617eeet *
  page239_i57
#CELL
  pure_quanta q_cap *
  page239_i58
#ISCELL
  logical_power universal_gnd *
  page239_i60
#CELL
  pure_quanta q_cap *
  page239_i61
#CELL
  pure_quanta q_inductor *
  page239_i62
#ISCELL
  logical_power universal_power *
  page239_i63
#ISCELL
  logical_power universal_gnd *
  page239_i64
#CELL
  pure_quanta q_cap *
  page239_i68
#ISCELL
  logical_power universal_gnd *
  page239_i69
#CELL
  pure_quanta q_cap *
  page239_i70
#ISCELL
  logical_power universal_gnd *
  page239_i71
#CELL
  pure_quanta q_res *
  page239_i72
#ISCELL
  mstr_misc dns *
  *
#ISCELL
  pure_quanta quanta_title_block_c *
  *
#ISCELL
  standard offpage *
  page240_i1
#ISCELL
  standard offpage *
  page240_i10
#CELL
  pure_quanta q_res_4p_12 *
  page240_i11
#ISCELL
  standard offpage *
  page240_i12
#ISCELL
  logical_power universal_power *
  page240_i13
#ISCELL
  logical_power universal_gnd *
  page240_i14
#CELL
  pure_quanta q_cap *
  page240_i15
#CELL
  pure_quanta q_res *
  page240_i16
#ISCELL
  logical_power universal_gnd *
  page240_i17
#CELL
  pure_quanta q_res *
  page240_i18
#CELL
  pure_quanta q_res *
  page240_i19
#ISCELL
  logical_power universal_power *
  page240_i2
#ISCELL
  standard offpage *
  page240_i20
#ISCELL
  standard offpage *
  page240_i21
#CELL
  pure_quanta ina183a1idbvr *
  page240_i22
#ISCELL
  logical_power universal_gnd *
  page240_i23
#ISCELL
  standard offpage *
  page240_i24
#ISCELL
  standard offpage *
  page240_i25
#ISCELL
  standard offpage *
  page240_i26
#ISCELL
  logical_power universal_gnd *
  page240_i28
#CELL
  pure_quanta ina183a1idbvr *
  page240_i29
#CELL
  pure_quanta q_res_4p_12 *
  page240_i3
#ISCELL
  logical_power universal_gnd *
  page240_i30
#ISCELL
  standard offpage *
  page240_i31
#ISCELL
  logical_power universal_gnd *
  page240_i32
#CELL
  pure_quanta q_cap *
  page240_i33
#ISCELL
  logical_power universal_power *
  page240_i34
#CELL
  pure_quanta q_res *
  page240_i35
#ISCELL
  logical_power universal_power *
  page240_i36
#CELL
  pure_quanta q_res *
  page240_i37
#CELL
  pure_quanta q_res *
  page240_i38
#CELL
  pure_quanta ina230airgtr *
  page240_i39
#ISCELL
  logical_power universal_power *
  page240_i4
#ISCELL
  standard offpage *
  page240_i5
#ISCELL
  standard offpage *
  page240_i6
#ISCELL
  logical_power universal_power *
  page240_i7
#ISCELL
  standard offpage *
  page240_i8
#ISCELL
  standard offpage *
  page240_i9
#ISCELL
  pure_quanta quanta_title_block_c *
  *
#ISCELL
  standard offpage *
  page242_i1
#ISCELL
  logical_power universal_gnd *
  page242_i10
#CELL
  pure_quanta q_led *
  page242_i11
#CELL
  pure_quanta q_res *
  page242_i12
#CELL
  pure_quanta q_led *
  page242_i13
#CELL
  pure_quanta q_res *
  page242_i14
#CELL
  pure_quanta q_res *
  page242_i15
#ISCELL
  standard offpage *
  page242_i16
#CELL
  pure_quanta mosfet_nch_dual *
  page242_i17
#CELL
  pure_quanta q_led *
  page242_i18
#CELL
  pure_quanta q_res *
  page242_i19
#ISCELL
  standard offpage *
  page242_i2
#ISCELL
  logical_power universal_power *
  page242_i20
#ISCELL
  logical_power universal_power *
  page242_i23
#ISCELL
  standard offpage *
  page242_i24
#ISCELL
  logical_power universal_power *
  page242_i25
#CELL
  pure_quanta mosfet_nch_dual *
  page242_i26
#ISCELL
  logical_power universal_gnd *
  page242_i28
#CELL
  pure_quanta mosfet_nch_dual *
  page242_i3
#ISCELL
  logical_power universal_gnd *
  page242_i30
#CELL
  pure_quanta q_led *
  page242_i31
#ISCELL
  logical_power universal_power *
  page242_i32
#ISCELL
  standard offpage *
  page242_i33
#CELL
  pure_quanta mosfet_nch_dual *
  page242_i34
#CELL
  pure_quanta q_led *
  page242_i35
#CELL
  pure_quanta q_res *
  page242_i37
#ISCELL
  logical_power universal_power *
  page242_i39
#ISCELL
  logical_power universal_gnd *
  page242_i4
#ISCELL
  logical_power universal_power *
  page242_i40
#CELL
  pure_quanta q_res *
  page242_i41
#CELL
  pure_quanta q_led *
  page242_i42
#ISCELL
  logical_power universal_gnd *
  page242_i49
#ISCELL
  logical_power universal_gnd *
  page242_i5
#ISCELL
  logical_power universal_power *
  page242_i51
#CELL
  pure_quanta q_led *
  page242_i52
#CELL
  pure_quanta q_led *
  page242_i53
#ISCELL
  logical_power universal_power *
  page242_i54
#ISCELL
  logical_power universal_gnd *
  page242_i56
#ISCELL
  logical_power universal_gnd *
  page242_i57
#ISCELL
  logical_power universal_power *
  page242_i59
#CELL
  pure_quanta mosfet_nch_dual *
  page242_i6
#CELL
  pure_quanta q_led *
  page242_i60
#CELL
  pure_quanta q_res *
  page242_i61
#CELL
  pure_quanta q_res *
  page242_i62
#CELL
  pure_quanta q_res *
  page242_i64
#ISCELL
  standard offpage *
  page242_i7
#CELL
  pure_quanta mosfet_nch_dual *
  page242_i8
#ISCELL
  logical_power universal_gnd *
  page242_i9
#ISCELL
  pure_quanta quanta_title_block_c *
  *
#ISCELL
  standard offpage *
  page305_i1
#CELL
  pure_quanta q_led *
  page305_i10
#ISCELL
  logical_power universal_gnd *
  page305_i11
#ISCELL
  logical_power universal_gnd *
  page305_i12
#CELL
  pure_quanta q_led *
  page305_i13
#ISCELL
  logical_power universal_power *
  page305_i17
#ISCELL
  standard offpage *
  page305_i18
#ISCELL
  logical_power universal_power *
  page305_i19
#CELL
  pure_quanta mosfet_nch_dual *
  page305_i2
#ISCELL
  logical_power universal_gnd *
  page305_i20
#CELL
  pure_quanta q_led *
  page305_i21
#CELL
  pure_quanta q_led *
  page305_i22
#ISCELL
  logical_power universal_power *
  page305_i25
#ISCELL
  standard offpage *
  page305_i26
#ISCELL
  logical_power universal_power *
  page305_i27
#ISCELL
  standard offpage *
  page305_i28
#ISCELL
  standard offpage *
  page305_i3
#CELL
  pure_quanta mosfet_nch_dual *
  page305_i32
#ISCELL
  logical_power universal_gnd *
  page305_i33
#ISCELL
  logical_power universal_gnd *
  page305_i34
#CELL
  pure_quanta q_led *
  page305_i35
#ISCELL
  logical_power universal_power *
  page305_i39
#CELL
  pure_quanta mosfet_nch_dual *
  page305_i4
#CELL
  pure_quanta mosfet_nch_dual *
  page305_i40
#CELL
  pure_quanta mosfet_nch_dual *
  page305_i41
#ISCELL
  logical_power universal_gnd *
  page305_i42
#CELL
  pure_quanta q_led *
  page305_i43
#CELL
  pure_quanta q_led *
  page305_i44
#ISCELL
  logical_power universal_power *
  page305_i46
#ISCELL
  logical_power universal_power *
  page305_i48
#CELL
  pure_quanta q_res *
  page305_i49
#ISCELL
  standard offpage *
  page305_i5
#CELL
  pure_quanta q_res *
  page305_i50
#CELL
  pure_quanta q_res *
  page305_i51
#CELL
  pure_quanta q_res *
  page305_i52
#CELL
  pure_quanta q_res *
  page305_i53
#CELL
  pure_quanta q_res *
  page305_i54
#CELL
  pure_quanta q_res *
  page305_i55
#ISCELL
  standard offpage *
  page305_i6
#CELL
  pure_quanta mosfet_nch_dual *
  page305_i7
#CELL
  pure_quanta mosfet_nch_dual *
  page305_i8
#ISCELL
  logical_power universal_gnd *
  page305_i9
#ISCELL
  pure_quanta quanta_title_block_c *
  *
#ISCELL
  standard offpage *
  page306_i1
#ISCELL
  logical_power universal_gnd *
  page306_i10
#CELL
  pure_quanta q_led *
  page306_i11
#CELL
  pure_quanta q_res *
  page306_i12
#CELL
  pure_quanta q_led *
  page306_i13
#CELL
  pure_quanta q_led *
  page306_i14
#CELL
  pure_quanta q_res *
  page306_i15
#CELL
  pure_quanta q_res *
  page306_i16
#ISCELL
  standard offpage *
  page306_i17
#CELL
  pure_quanta mosfet_nch_dual *
  page306_i18
#CELL
  pure_quanta q_led *
  page306_i19
#ISCELL
  standard offpage *
  page306_i2
#CELL
  pure_quanta q_res *
  page306_i20
#ISCELL
  logical_power universal_power *
  page306_i21
#ISCELL
  standard offpage *
  page306_i22
#ISCELL
  logical_power universal_power *
  page306_i24
#ISCELL
  standard offpage *
  page306_i25
#ISCELL
  logical_power universal_power *
  page306_i26
#CELL
  pure_quanta mosfet_nch_dual *
  page306_i27
#ISCELL
  logical_power universal_gnd *
  page306_i28
#ISCELL
  logical_power universal_gnd *
  page306_i29
#CELL
  pure_quanta mosfet_nch_dual *
  page306_i3
#CELL
  pure_quanta q_led *
  page306_i30
#ISCELL
  logical_power universal_gnd *
  page306_i31
#CELL
  pure_quanta q_led *
  page306_i32
#ISCELL
  logical_power universal_power *
  page306_i33
#ISCELL
  standard offpage *
  page306_i34
#CELL
  pure_quanta mosfet_nch_dual *
  page306_i35
#CELL
  pure_quanta q_led *
  page306_i36
#CELL
  pure_quanta q_res *
  page306_i37
#CELL
  pure_quanta q_res *
  page306_i38
#ISCELL
  logical_power universal_power *
  page306_i39
#ISCELL
  logical_power universal_gnd *
  page306_i4
#ISCELL
  logical_power universal_power *
  page306_i40
#CELL
  pure_quanta q_res *
  page306_i41
#ISCELL
  logical_power universal_power *
  page306_i42
#CELL
  pure_quanta mosfet_nch_dual *
  page306_i43
#ISCELL
  logical_power universal_gnd *
  page306_i5
#CELL
  pure_quanta mosfet_nch_dual *
  page306_i6
#ISCELL
  standard offpage *
  page306_i7
#CELL
  pure_quanta mosfet_nch_dual *
  page306_i8
#ISCELL
  logical_power universal_gnd *
  page306_i9
#ISCELL
  pure_quanta quanta_title_block_c *
  *
#ISCELL
  logical_power universal_gnd *
  page241_i10
#CELL
  pure_quanta q_led *
  page241_i11
#ISCELL
  logical_power universal_power *
  page241_i15
#CELL
  pure_quanta mosfet_nch_dual *
  page241_i16
#CELL
  pure_quanta mosfet_nch_dual *
  page241_i17
#ISCELL
  logical_power universal_gnd *
  page241_i18
#CELL
  pure_quanta q_led *
  page241_i19
#CELL
  pure_quanta q_led *
  page241_i20
#ISCELL
  logical_power universal_power *
  page241_i24
#ISCELL
  logical_power universal_power *
  page241_i25
#ISCELL
  standard offpage *
  page241_i26
#ISCELL
  standard offpage *
  page241_i3
#ISCELL
  logical_power universal_gnd *
  page241_i31
#CELL
  pure_quanta q_led *
  page241_i33
#ISCELL
  logical_power universal_power *
  page241_i37
#CELL
  pure_quanta q_res *
  page241_i38
#CELL
  pure_quanta q_res *
  page241_i39
#ISCELL
  standard offpage *
  page241_i4
#CELL
  pure_quanta q_res *
  page241_i40
#CELL
  pure_quanta q_res *
  page241_i41
#CELL
  pure_quanta mosfet_nch_dual *
  page241_i42
#ISCELL
  logical_power universal_power *
  page241_i47
#CELL
  pure_quanta q_led *
  page241_i49
#ISCELL
  standard offpage *
  page241_i5
#ISCELL
  logical_power universal_gnd *
  page241_i50
#ISCELL
  logical_power universal_power *
  page241_i54
#CELL
  pure_quanta q_led *
  page241_i58
#ISCELL
  logical_power universal_gnd *
  page241_i59
#CELL
  pure_quanta q_res *
  page241_i61
#CELL
  pure_quanta q_res *
  page241_i62
#CELL
  pure_quanta q_res *
  page241_i63
#CELL
  pure_quanta q_res *
  page241_i64
#CELL
  pure_quanta q_res *
  page241_i65
#CELL
  pure_quanta q_res *
  page241_i66
#CELL
  pure_quanta q_led *
  page241_i67
#CELL
  pure_quanta q_res *
  page241_i68
#CELL
  pure_quanta mosfet_nch_dual *
  page241_i69
#ISCELL
  logical_power universal_power *
  page241_i71
#CELL
  pure_quanta mosfet_nch_dual *
  page241_i72
#ISCELL
  logical_power universal_gnd *
  page241_i73
#CELL
  pure_quanta q_res *
  page241_i74
#ISCELL
  logical_power universal_power *
  page241_i75
#ISCELL
  logical_power universal_gnd *
  page241_i76
#ISCELL
  standard offpage *
  page241_i77
#CELL
  pure_quanta mosfet_nch_dual *
  page241_i8
#ISCELL
  logical_power universal_gnd *
  page241_i9
#ISCELL
  pure_quanta quanta_title_block_c *
  *
#ISCELL
  standard offpage *
  page304_i1
#ISCELL
  logical_power universal_gnd *
  page304_i10
#CELL
  pure_quanta q_led *
  page304_i12
#ISCELL
  logical_power universal_power *
  page304_i14
#ISCELL
  logical_power universal_power *
  page304_i16
#ISCELL
  standard offpage *
  page304_i17
#ISCELL
  logical_power universal_gnd *
  page304_i19
#ISCELL
  standard offpage *
  page304_i2
#CELL
  pure_quanta q_led *
  page304_i20
#CELL
  pure_quanta q_led *
  page304_i21
#ISCELL
  logical_power universal_power *
  page304_i24
#ISCELL
  standard offpage *
  page304_i25
#ISCELL
  logical_power universal_power *
  page304_i26
#ISCELL
  logical_power universal_gnd *
  page304_i29
#ISCELL
  standard offpage *
  page304_i3
#CELL
  pure_quanta q_led *
  page304_i31
#CELL
  pure_quanta q_led *
  page304_i32
#ISCELL
  logical_power universal_power *
  page304_i35
#ISCELL
  logical_power universal_power *
  page304_i36
#CELL
  pure_quanta q_res *
  page304_i49
#ISCELL
  standard offpage *
  page304_i5
#CELL
  pure_quanta q_res *
  page304_i50
#CELL
  pure_quanta q_res *
  page304_i51
#CELL
  pure_quanta q_res *
  page304_i52
#CELL
  pure_quanta q_res *
  page304_i53
#CELL
  pure_quanta q_res *
  page304_i54
#ISCELL
  logical_power universal_power *
  page304_i55
#ISCELL
  logical_power universal_power *
  page304_i56
#CELL
  pure_quanta q_res *
  page304_i57
#CELL
  pure_quanta q_led *
  page304_i58
#ISCELL
  logical_power universal_gnd *
  page304_i59
#ISCELL
  logical_power universal_gnd *
  page304_i6
#ISCELL
  standard offpage *
  page304_i61
#CELL
  pure_quanta q_res *
  page304_i62
#CELL
  pure_quanta q_led *
  page304_i63
#ISCELL
  logical_power universal_gnd *
  page304_i64
#ISCELL
  standard offpage *
  page304_i66
#ISCELL
  logical_power universal_gnd *
  page304_i67
#CELL
  pure_quanta mosfet_nch_dual *
  page304_i68
#CELL
  pure_quanta mosfet_nch_dual *
  page304_i69
#CELL
  pure_quanta mosfet_nch_dual *
  page304_i70
#CELL
  pure_quanta mosfet_nch_dual *
  page304_i71
#CELL
  pure_quanta mosfet_nch_dual *
  page304_i72
#CELL
  pure_quanta mosfet_nch_dual *
  page304_i74
#CELL
  pure_quanta mosfet_nch_dual *
  page304_i75
#CELL
  pure_quanta mosfet_nch_dual *
  page304_i76
#ISCELL
  logical_power universal_gnd *
  page304_i8
#CELL
  pure_quanta q_led *
  page304_i9
#ISCELL
  logical_power design_note *
  *
#ISCELL
  mstr_misc dns *
  *
#ISCELL
  pure_quanta quanta_title_block_c *
  *
#ISCELL
  logical_power vcc15 *
  page243_i1
#ISCELL
  logical_power universal_gnd *
  page243_i11
#ISCELL
  logical_power universal_power *
  page243_i12
#CELL
  pure_quanta q_res *
  page243_i13
#ISCELL
  standard offpage *
  page243_i14
#CELL
  pure_quanta mosfet_n *
  page243_i15
#CELL
  pure_quanta q_res *
  page243_i16
#ISCELL
  logical_power universal_power *
  page243_i17
#ISCELL
  logical_power universal_gnd *
  page243_i18
#CELL
  pure_quanta q_res *
  page243_i19
#CELL
  pure_quanta q_res *
  page243_i2
#ISCELL
  standard offpage *
  page243_i20
#ISCELL
  logical_power universal_power *
  page243_i3
#CELL
  pure_quanta q_cap *
  page243_i4
#CELL
  pure_quanta q_cap *
  page243_i5
#ISCELL
  logical_power universal_power *
  page243_i6
#CELL
  pure_quanta q_res *
  page243_i7
#CELL
  pure_quanta q_res *
  page243_i8
#ISCELL
  logical_power universal_gnd *
  page243_i9
#ISCELL
  pure_quanta quanta_title_block_c *
  *
#ISCELL
  logical_power gnd *
  page244_i1
#CELL
  pure_quanta q_res *
  page244_i10
#CELL
  pure_quanta q_cap *
  page244_i11
#CELL
  pure_quanta q_cap *
  page244_i12
#ISCELL
  standard offpage *
  page244_i13
#CELL
  pure_quanta q_cap *
  page244_i14
#ISCELL
  logical_power gnd *
  page244_i15
#CELL
  pure_quanta q_res *
  page244_i16
#ISCELL
  logical_power gnd *
  page244_i17
#ISCELL
  logical_power gnd *
  page244_i18
#ISCELL
  logical_power gnd *
  page244_i19
#CELL
  pure_quanta q_cap *
  page244_i2
#CELL
  pure_quanta rs53318lr *
  page244_i20
#CELL
  pure_quanta q_cap *
  page244_i21
#CELL
  pure_quanta q_cap *
  page244_i22
#ISCELL
  logical_power gnd *
  page244_i23
#ISCELL
  logical_power gnd *
  page244_i24
#CELL
  pure_quanta q_res *
  page244_i25
#CELL
  pure_quanta q_cap *
  page244_i26
#CELL
  pure_quanta q_res *
  page244_i27
#CELL
  pure_quanta q_res *
  page244_i28
#ISCELL
  logical_power p1v0_aux *
  page244_i3
#CELL
  pure_quanta q_inductor *
  page244_i30
#ISCELL
  standard offpage *
  page244_i31
#CELL
  pure_quanta q_capp *
  page244_i32
#CELL
  pure_quanta q_cap *
  page244_i33
#CELL
  pure_quanta q_cap *
  page244_i34
#ISCELL
  logical_power gnd *
  page244_i35
#CELL
  pure_quanta q_cap *
  page244_i36
#ISCELL
  logical_power universal_power *
  page244_i37
#ISCELL
  logical_power p1v0 *
  page244_i38
#CELL
  pure_quanta q_res *
  page244_i39
#ISCELL
  logical_power gnd *
  page244_i4
#CELL
  pure_quanta q_inductor *
  page244_i5
#ISCELL
  logical_power gnd *
  page244_i6
#CELL
  pure_quanta q_cap *
  page244_i7
#CELL
  pure_quanta q_cap *
  page244_i8
#ISCELL
  logical_power universal_power *
  page244_i9
#ISCELL
  mstr_misc dns *
  *
#ISCELL
  pure_quanta quanta_title_block_c *
  *
#CELL
  pure_quanta q_cap *
  page245_i100
#CELL
  pure_quanta q_cap *
  page245_i101
#ISCELL
  logical_power gnd *
  page245_i102
#CELL
  pure_quanta q_capp *
  page245_i103
#CELL
  pure_quanta q_capp *
  page245_i104
#CELL
  pure_quanta q_cap *
  page245_i105
#CELL
  pure_quanta q_cap *
  page245_i106
#CELL
  pure_quanta q_cap *
  page245_i107
#CELL
  pure_quanta q_cap *
  page245_i108
#CELL
  pure_quanta q_cap *
  page245_i109
#CELL
  pure_quanta q_cap *
  page245_i110
#CELL
  pure_quanta q_cap *
  page245_i111
#CELL
  pure_quanta q_cap *
  page245_i112
#CELL
  pure_quanta q_cap *
  page245_i113
#CELL
  pure_quanta q_cap *
  page245_i114
#CELL
  pure_quanta q_cap *
  page245_i115
#ISCELL
  logical_power universal_power *
  page245_i116
#ISCELL
  logical_power gnd *
  page245_i117
#CELL
  pure_quanta q_cap *
  page245_i118
#ISCELL
  logical_power gnd *
  page245_i119
#ISCELL
  logical_power gnd *
  page245_i120
#CELL
  pure_quanta q_res *
  page245_i121
#CELL
  pure_quanta q_cap *
  page245_i122
#CELL
  pure_quanta q_res *
  page245_i123
#ISCELL
  logical_power gnd *
  page245_i124
#CELL
  pure_quanta q_res *
  page245_i125
#ISCELL
  logical_power universal_power *
  page245_i126
#CELL
  pure_quanta q_cap *
  page245_i127
#CELL
  pure_quanta q_res *
  page245_i128
#CELL
  pure_quanta q_inductor *
  page245_i129
#ISCELL
  standard offpage *
  page245_i130
#CELL
  pure_quanta q_capp *
  page245_i131
#CELL
  pure_quanta q_capp *
  page245_i132
#CELL
  pure_quanta q_cap *
  page245_i133
#CELL
  pure_quanta q_cap *
  page245_i134
#ISCELL
  logical_power gnd *
  page245_i135
#CELL
  pure_quanta q_cap *
  page245_i136
#CELL
  pure_quanta q_cap *
  page245_i137
#ISCELL
  logical_power universal_power *
  page245_i138
#CELL
  pure_quanta q_res *
  page245_i139
#ISCELL
  logical_power universal_power *
  page245_i140
#CELL
  pure_quanta q_diode *
  page245_i71
#CELL
  pure_quanta q_res *
  page245_i72
#CELL
  pure_quanta q_cap *
  page245_i73
#ISCELL
  logical_power gnd *
  page245_i74
#ISCELL
  logical_power gnd *
  page245_i75
#CELL
  pure_quanta q_res *
  page245_i76
#ISCELL
  logical_power gnd *
  page245_i77
#CELL
  pure_quanta q_res *
  page245_i78
#ISCELL
  standard offpage *
  page245_i79
#ISCELL
  logical_power p1v0_aux *
  page245_i80
#ISCELL
  logical_power gnd *
  page245_i83
#CELL
  pure_quanta q_res *
  page245_i84
#CELL
  pure_quanta q_cap *
  page245_i86
#ISCELL
  logical_power gnd *
  page245_i87
#ISCELL
  logical_power gnd *
  page245_i88
#CELL
  pure_quanta q_res *
  page245_i89
#ISCELL
  logical_power gnd *
  page245_i90
#CELL
  pure_quanta q_res *
  page245_i91
#ISCELL
  logical_power gnd *
  page245_i92
#CELL
  pure_quanta q_cap *
  page245_i93
#CELL
  pure_quanta q_res *
  page245_i94
#CELL
  pure_quanta ir3889mtrpbf *
  page245_i95
#ISCELL
  logical_power gnd *
  page245_i96
#CELL
  pure_quanta q_cap *
  page245_i97
#CELL
  pure_quanta q_inductor *
  page245_i98
#ISCELL
  logical_power universal_power *
  page245_i99
#ISCELL
  mstr_misc dns *
  *
#ISCELL
  pure_quanta quanta_title_block_c *
  *
#ISCELL
  logical_power universal_gnd *
  page246_i1
#CELL
  pure_quanta q_res *
  page246_i10
#ISCELL
  logical_power universal_gnd *
  page246_i100
#ISCELL
  logical_power universal_power *
  page246_i101
#CELL
  pure_quanta q_res *
  page246_i102
#ISCELL
  logical_power universal_gnd *
  page246_i103
#CELL
  pure_quanta q_res *
  page246_i104
#CELL
  pure_quanta apx80929sag7 *
  page246_i105
#ISCELL
  logical_power universal_gnd *
  page246_i106
#CELL
  pure_quanta q_cap *
  page246_i107
#ISCELL
  logical_power universal_power *
  page246_i108
#CELL
  pure_quanta q_res *
  page246_i109
#CELL
  pure_quanta q_cap *
  page246_i11
#ISCELL
  logical_power universal_gnd *
  page246_i110
#ISCELL
  logical_power universal_power *
  page246_i111
#CELL
  pure_quanta q_res *
  page246_i112
#ISCELL
  logical_power universal_gnd *
  page246_i113
#ISCELL
  logical_power universal_power *
  page246_i114
#ISCELL
  logical_power universal_gnd *
  page246_i12
#ISCELL
  logical_power universal_gnd *
  page246_i13
#CELL
  pure_quanta q_res *
  page246_i14
#ISCELL
  logical_power universal_gnd *
  page246_i15
#CELL
  pure_quanta q_res *
  page246_i17
#ISCELL
  logical_power universal_power *
  page246_i18
#CELL
  pure_quanta q_cap *
  page246_i2
#ISCELL
  logical_power universal_gnd *
  page246_i20
#CELL
  pure_quanta q_res *
  page246_i22
#ISCELL
  logical_power universal_power *
  page246_i23
#CELL
  pure_quanta q_cap *
  page246_i24
#CELL
  pure_quanta q_cap *
  page246_i25
#ISCELL
  logical_power p1v0_aux *
  page246_i26
#CELL
  pure_quanta q_res *
  page246_i27
#ISCELL
  logical_power universal_gnd *
  page246_i28
#ISCELL
  logical_power universal_power *
  page246_i3
#CELL
  pure_quanta mosfet_nch_1d3s *
  page246_i30
#ISCELL
  logical_power universal_power *
  page246_i31
#CELL
  pure_quanta bat547f *
  page246_i32
#ISCELL
  logical_power universal_power *
  page246_i34
#CELL
  pure_quanta rt9818c44gv *
  page246_i4
#ISCELL
  logical_power universal_power *
  page246_i42
#ISCELL
  logical_power universal_gnd *
  page246_i43
#CELL
  pure_quanta q_cap *
  page246_i44
#CELL
  pure_quanta q_cap *
  page246_i45
#ISCELL
  logical_power universal_gnd *
  page246_i47
#CELL
  pure_quanta q_cap *
  page246_i48
#CELL
  pure_quanta q_cap *
  page246_i49
#ISCELL
  logical_power universal_gnd *
  page246_i5
#CELL
  pure_quanta q_cap *
  page246_i50
#CELL
  pure_quanta mosfet_nch_1d3s *
  page246_i51
#ISCELL
  logical_power p1v0_aux *
  page246_i53
#CELL
  pure_quanta q_cap *
  page246_i58
#ISCELL
  logical_power universal_power *
  page246_i59
#CELL
  pure_quanta q_res *
  page246_i6
#ISCELL
  logical_power universal_gnd *
  page246_i60
#CELL
  pure_quanta q_cap *
  page246_i61
#ISCELL
  standard offpage *
  page246_i63
#ISCELL
  standard offpage *
  page246_i64
#ISCELL
  logical_power universal_gnd *
  page246_i65
#CELL
  pure_quanta mosfet_nch_gds_esd_protected *
  page246_i67
#CELL
  pure_quanta q_cap *
  page246_i68
#CELL
  pure_quanta mosfet_nch_dual *
  page246_i69
#ISCELL
  standard offpage *
  page246_i7
#CELL
  pure_quanta mosfet_nch_dual *
  page246_i76
#CELL
  pure_quanta q_res *
  page246_i77
#CELL
  pure_quanta q_res *
  page246_i78
#CELL
  pure_quanta q_res *
  page246_i79
#ISCELL
  standard offpage *
  page246_i8
#CELL
  pure_quanta q_res *
  page246_i80
#ISCELL
  logical_power universal_gnd *
  page246_i87
#CELL
  pure_quanta q_res *
  page246_i89
#CELL
  pure_quanta q_res *
  page246_i9
#CELL
  pure_quanta q_res *
  page246_i91
#ISCELL
  standard offpage *
  page246_i92
#ISCELL
  logical_power universal_power *
  page246_i93
#CELL
  pure_quanta q_cap *
  page246_i94
#ISCELL
  logical_power universal_gnd *
  page246_i95
#CELL
  pure_quanta q_res *
  page246_i96
#CELL
  pure_quanta mosfet_nch_dual *
  page246_i98
#CELL
  pure_quanta mosfet_nch_dual *
  page246_i99
#ISCELL
  pure_quanta quanta_title_block_c *
  *
#ISCELL
  mstr_misc dns *
  *
#ISCELL
  pure_quanta quanta_title_block_c *
  *
#ISCELL
  logical_power universal_gnd *
  page248_i1
#CELL
  pure_quanta q_res *
  page248_i10
#CELL
  pure_quanta rs53319lr *
  page248_i11
#ISCELL
  logical_power universal_gnd *
  page248_i12
#ISCELL
  logical_power universal_gnd *
  page248_i13
#CELL
  pure_quanta q_cap *
  page248_i14
#ISCELL
  logical_power universal_gnd *
  page248_i15
#CELL
  pure_quanta q_cap *
  page248_i16
#ISCELL
  logical_power gnd *
  page248_i17
#CELL
  pure_quanta q_cap *
  page248_i18
#CELL
  pure_quanta q_inductor *
  page248_i19
#CELL
  pure_quanta q_cap *
  page248_i2
#ISCELL
  logical_power vccaux15 *
  page248_i20
#ISCELL
  standard offpage *
  page248_i21
#ISCELL
  logical_power universal_gnd *
  page248_i22
#CELL
  pure_quanta q_capp *
  page248_i23
#ISCELL
  logical_power vccaux15 *
  page248_i24
#CELL
  pure_quanta q_cap *
  page248_i25
#CELL
  pure_quanta q_res *
  page248_i26
#CELL
  pure_quanta q_res *
  page248_i27
#CELL
  pure_quanta q_cap *
  page248_i28
#CELL
  pure_quanta q_cap *
  page248_i29
#CELL
  pure_quanta q_res *
  page248_i3
#CELL
  pure_quanta q_cap *
  page248_i30
#CELL
  pure_quanta q_cap *
  page248_i31
#CELL
  pure_quanta q_res *
  page248_i32
#ISCELL
  logical_power universal_power *
  page248_i33
#CELL
  pure_quanta q_res *
  page248_i34
#CELL
  pure_quanta q_cap *
  page248_i35
#CELL
  pure_quanta q_res *
  page248_i36
#CELL
  pure_quanta q_cap *
  page248_i37
#CELL
  pure_quanta q_cap *
  page248_i38
#ISCELL
  logical_power universal_gnd *
  page248_i39
#ISCELL
  logical_power universal_power *
  page248_i4
#CELL
  pure_quanta q_capp *
  page248_i40
#CELL
  pure_quanta q_capp *
  page248_i41
#CELL
  pure_quanta q_short *
  page248_i42
#CELL
  pure_quanta q_short *
  page248_i43
#CELL
  pure_quanta q_cap *
  page248_i44
#CELL
  pure_quanta q_cap *
  page248_i45
#ISCELL
  logical_power universal_gnd *
  page248_i46
#CELL
  pure_quanta q_capp *
  page248_i47
#CELL
  pure_quanta q_capp *
  page248_i48
#ISCELL
  logical_power vccaux15 *
  page248_i49
#ISCELL
  logical_power universal_gnd *
  page248_i5
#ISCELL
  logical_power universal_gnd *
  page248_i50
#CELL
  pure_quanta q_res *
  page248_i51
#CELL
  pure_quanta q_res *
  page248_i52
#CELL
  pure_quanta q_inductor *
  page248_i53
#ISCELL
  standard offpage *
  page248_i54
#ISCELL
  standard offpage *
  page248_i55
#ISCELL
  logical_power universal_power *
  page248_i56
#CELL
  pure_quanta q_res *
  page248_i6
#ISCELL
  logical_power universal_gnd *
  page248_i7
#CELL
  pure_quanta q_cap *
  page248_i8
#CELL
  pure_quanta q_res *
  page248_i9
#ISCELL
  logical_power cad_note *
  *
#ISCELL
  mstr_misc dns *
  *
#ISCELL
  pure_quanta quanta_title_block_c *
  *
#ISCELL
  logical_power universal_power *
  page249_i1
#ISCELL
  logical_power universal_gnd *
  page249_i10
#CELL
  pure_quanta q_res *
  page249_i11
#ISCELL
  standard offpage *
  page249_i12
#ISCELL
  logical_power gnd *
  page249_i13
#CELL
  pure_quanta q_cap *
  page249_i14
#ISCELL
  logical_power vccaux15 *
  page249_i15
#CELL
  pure_quanta q_inductor *
  page249_i16
#CELL
  pure_quanta q_res *
  page249_i17
#ISCELL
  logical_power universal_gnd *
  page249_i18
#CELL
  pure_quanta q_cap *
  page249_i19
#CELL
  pure_quanta q_res *
  page249_i2
#CELL
  pure_quanta q_cap *
  page249_i20
#CELL
  pure_quanta q_cap *
  page249_i21
#ISCELL
  logical_power universal_power *
  page249_i22
#ISCELL
  logical_power universal_power *
  page249_i23
#CELL
  pure_quanta q_res *
  page249_i24
#ISCELL
  logical_power universal_gnd *
  page249_i25
#CELL
  pure_quanta nb682gdz *
  page249_i26
#ISCELL
  logical_power universal_gnd *
  page249_i27
#CELL
  pure_quanta q_cap *
  page249_i28
#CELL
  pure_quanta q_cap *
  page249_i29
#ISCELL
  logical_power universal_gnd *
  page249_i3
#CELL
  pure_quanta q_cap *
  page249_i30
#CELL
  pure_quanta q_res *
  page249_i31
#ISCELL
  logical_power universal_power *
  page249_i32
#CELL
  pure_quanta q_res *
  page249_i34
#ISCELL
  logical_power universal_gnd *
  page249_i35
#CELL
  pure_quanta q_cap *
  page249_i36
#CELL
  pure_quanta q_cap *
  page249_i37
#CELL
  pure_quanta q_cap *
  page249_i38
#CELL
  pure_quanta q_cap *
  page249_i39
#CELL
  pure_quanta q_cap *
  page249_i4
#ISCELL
  logical_power universal_gnd *
  page249_i40
#CELL
  pure_quanta q_cap *
  page249_i41
#CELL
  pure_quanta q_res *
  page249_i42
#ISCELL
  standard offpage *
  page249_i43
#ISCELL
  logical_power universal_power *
  page249_i44
#CELL
  pure_quanta q_inductor *
  page249_i45
#CELL
  pure_quanta q_res *
  page249_i5
#ISCELL
  logical_power universal_power *
  page249_i6
#ISCELL
  logical_power universal_power *
  page249_i7
#CELL
  pure_quanta q_res *
  page249_i8
#ISCELL
  logical_power universal_gnd *
  page249_i9
#ISCELL
  pure_quanta quanta_title_block_c *
  *
#ISCELL
  pure_quanta quanta_title_block_c *
  *
#ISCELL
  mstr_misc dns *
  *
#ISCELL
  pure_quanta quanta_title_block_c *
  *
#ISCELL
  standard offpage *
  page252_i1
#CELL
  pure_quanta q_res *
  page252_i10
#ISCELL
  standard offpage *
  page252_i100
#ISCELL
  standard offpage *
  page252_i101
#ISCELL
  standard offpage *
  page252_i102
#ISCELL
  standard offpage *
  page252_i103
#ISCELL
  standard offpage *
  page252_i104
#ISCELL
  standard offpage *
  page252_i105
#ISCELL
  standard offpage *
  page252_i106
#ISCELL
  standard offpage *
  page252_i107
#ISCELL
  standard offpage *
  page252_i108
#ISCELL
  standard offpage *
  page252_i109
#CELL
  pure_quanta q_res *
  page252_i11
#ISCELL
  standard offpage *
  page252_i110
#ISCELL
  standard offpage *
  page252_i111
#ISCELL
  standard offpage *
  page252_i112
#ISCELL
  standard offpage *
  page252_i113
#ISCELL
  logical_power universal_gnd *
  page252_i114
#ISCELL
  standard offpage *
  page252_i115
#CELL
  pure_quanta q_cap *
  page252_i116
#ISCELL
  standard offpage *
  page252_i117
#ISCELL
  standard offpage *
  page252_i118
#ISCELL
  standard offpage *
  page252_i119
#ISCELL
  logical_power vcc15 *
  page252_i12
#ISCELL
  logical_power universal_gnd *
  page252_i120
#CELL
  pure_quanta q_res *
  page252_i121
#ISCELL
  standard offpage *
  page252_i122
#CELL
  pure_quanta q_res *
  page252_i123
#CELL
  pure_quanta q_res *
  page252_i124
#CELL
  pure_quanta q_res *
  page252_i125
#ISCELL
  logical_power universal_gnd *
  page252_i126
#CELL
  pure_quanta q_cap *
  page252_i127
#CELL
  pure_quanta q_cap *
  page252_i128
#ISCELL
  logical_power vcc15 *
  page252_i129
#ISCELL
  logical_power vcc15 *
  page252_i13
#ISCELL
  logical_power universal_gnd *
  page252_i130
#ISCELL
  standard offpage *
  page252_i131
#ISCELL
  logical_power universal_gnd *
  page252_i132
#CELL
  pure_quanta q_res *
  page252_i133
#ISCELL
  logical_power vcc15 *
  page252_i134
#CELL
  pure_quanta q_cap *
  page252_i136
#ISCELL
  standard offpage *
  page252_i14
#CELL
  pure_quanta q_res *
  page252_i15
#ISCELL
  logical_power vcc15 *
  page252_i16
#CELL
  pure_quanta q_res *
  page252_i17
#ISCELL
  standard offpage *
  page252_i18
#CELL
  pure_quanta q_res *
  page252_i19
#ISCELL
  standard offpage *
  page252_i2
#CELL
  pure_quanta q_res *
  page252_i20
#ISCELL
  logical_power universal_gnd *
  page252_i21
#ISCELL
  logical_power vcc15 *
  page252_i22
#CELL
  pure_quanta q_res *
  page252_i23
#CELL
  pure_quanta q_short *
  page252_i24
#CELL
  pure_quanta q_res *
  page252_i25
#CELL
  pure_quanta q_res *
  page252_i26
#ISCELL
  logical_power vcc15 *
  page252_i27
#ISCELL
  logical_power universal_gnd *
  page252_i28
#ISCELL
  standard offpage *
  page252_i29
#ISCELL
  standard offpage *
  page252_i3
#ISCELL
  standard offpage *
  page252_i30
#ISCELL
  standard offpage *
  page252_i31
#CELL
  pure_quanta conn3_210hp1030br1 *
  page252_i32
#ISCELL
  standard offpage *
  page252_i33
#ISCELL
  logical_power universal_gnd *
  page252_i34
#ISCELL
  standard offpage *
  page252_i35
#ISCELL
  standard offpage *
  page252_i36
#CELL
  pure_quanta q_short *
  page252_i37
#CELL
  pure_quanta q_res *
  page252_i38
#ISCELL
  logical_power vcc15 *
  page252_i39
#ISCELL
  standard offpage *
  page252_i4
#CELL
  pure_quanta q_res *
  page252_i40
#CELL
  pure_quanta q_res *
  page252_i41
#CELL
  pure_quanta q_res *
  page252_i42
#CELL
  pure_quanta q_res *
  page252_i43
#CELL
  pure_quanta q_res *
  page252_i44
#ISCELL
  standard offpage *
  page252_i45
#ISCELL
  standard offpage *
  page252_i46
#ISCELL
  logical_power vcc15 *
  page252_i47
#CELL
  pure_quanta q_res *
  page252_i48
#CELL
  pure_quanta q_res *
  page252_i49
#CELL
  pure_quanta q_res *
  page252_i5
#CELL
  pure_quanta q_res *
  page252_i50
#CELL
  pure_quanta q_res *
  page252_i51
#ISCELL
  logical_power universal_gnd *
  page252_i52
#CELL
  pure_quanta q_cap *
  page252_i53
#CELL
  pure_quanta q_res *
  page252_i54
#CELL
  pure_quanta q_res *
  page252_i55
#CELL
  pure_quanta q_res *
  page252_i56
#CELL
  pure_quanta q_cap *
  page252_i57
#CELL
  pure_quanta q_cap *
  page252_i58
#ISCELL
  logical_power universal_gnd *
  page252_i59
#ISCELL
  standard offpage *
  page252_i6
#CELL
  pure_quanta q_res *
  page252_i60
#CELL
  pure_quanta q_cap *
  page252_i61
#ISCELL
  logical_power universal_gnd *
  page252_i62
#CELL
  pure_quanta raa229126gnpha0 *
  page252_i63
#ISCELL
  logical_power universal_gnd *
  page252_i64
#ISCELL
  logical_power universal_gnd *
  page252_i65
#CELL
  pure_quanta q_res *
  page252_i66
#CELL
  pure_quanta q_cap *
  page252_i67
#CELL
  pure_quanta q_res *
  page252_i68
#ISCELL
  logical_power universal_gnd *
  page252_i69
#ISCELL
  standard offpage *
  page252_i7
#CELL
  pure_quanta q_cap *
  page252_i70
#ISCELL
  logical_power universal_gnd *
  page252_i71
#CELL
  pure_quanta q_res *
  page252_i72
#CELL
  pure_quanta q_res *
  page252_i73
#CELL
  pure_quanta q_res *
  page252_i74
#ISCELL
  logical_power universal_gnd *
  page252_i75
#ISCELL
  logical_power universal_gnd *
  page252_i76
#CELL
  pure_quanta q_res *
  page252_i77
#CELL
  pure_quanta q_res *
  page252_i78
#CELL
  pure_quanta q_cap *
  page252_i79
#CELL
  pure_quanta q_res *
  page252_i8
#CELL
  pure_quanta q_res *
  page252_i80
#ISCELL
  logical_power vcc15 *
  page252_i81
#CELL
  pure_quanta q_cap *
  page252_i82
#ISCELL
  logical_power universal_gnd *
  page252_i83
#CELL
  pure_quanta q_cap *
  page252_i84
#ISCELL
  logical_power universal_gnd *
  page252_i85
#CELL
  pure_quanta q_cap *
  page252_i86
#CELL
  pure_quanta q_cap *
  page252_i87
#CELL
  pure_quanta q_cap *
  page252_i88
#CELL
  pure_quanta q_cap *
  page252_i89
#ISCELL
  logical_power universal_gnd *
  page252_i9
#ISCELL
  standard offpage *
  page252_i90
#ISCELL
  standard offpage *
  page252_i91
#ISCELL
  standard offpage *
  page252_i92
#ISCELL
  standard offpage *
  page252_i93
#ISCELL
  standard offpage *
  page252_i94
#ISCELL
  standard offpage *
  page252_i95
#ISCELL
  standard offpage *
  page252_i96
#ISCELL
  standard offpage *
  page252_i97
#ISCELL
  standard offpage *
  page252_i98
#ISCELL
  standard offpage *
  page252_i99
#ISCELL
  mstr_misc dns *
  *
#ISCELL
  pure_quanta quanta_title_block_c *
  *
#ISCELL
  logical_power universal_gnd *
  page253_i1
#ISCELL
  logical_power universal_gnd *
  page253_i10
#CELL
  pure_quanta q_cap *
  page253_i11
#CELL
  pure_quanta q_res *
  page253_i12
#ISCELL
  logical_power vcc15 *
  page253_i13
#ISCELL
  logical_power universal_gnd *
  page253_i14
#CELL
  pure_quanta q_cap *
  page253_i15
#ISCELL
  logical_power universal_gnd *
  page253_i16
#ISCELL
  standard offpage *
  page253_i17
#CELL
  pure_quanta q_res *
  page253_i18
#CELL
  pure_quanta q_cap *
  page253_i19
#CELL
  pure_quanta q_res *
  page253_i2
#CELL
  pure_quanta q_cap *
  page253_i20
#CELL
  pure_quanta q_inductor4p_14 *
  page253_i21
#CELL
  pure_quanta q_cap *
  page253_i22
#CELL
  pure_quanta q_cap *
  page253_i23
#CELL
  pure_quanta q_cap *
  page253_i24
#ISCELL
  logical_power universal_gnd *
  page253_i25
#CELL
  pure_quanta q_res *
  page253_i26
#ISCELL
  logical_power vcc15 *
  page253_i27
#ISCELL
  logical_power universal_gnd *
  page253_i28
#CELL
  pure_quanta q_res *
  page253_i29
#ISCELL
  logical_power universal_gnd *
  page253_i3
#ISCELL
  standard offpage *
  page253_i30
#ISCELL
  standard offpage *
  page253_i31
#ISCELL
  standard offpage *
  page253_i32
#ISCELL
  standard offpage *
  page253_i33
#CELL
  pure_quanta q_cap *
  page253_i34
#ISCELL
  logical_power universal_gnd *
  page253_i35
#CELL
  pure_quanta q_cap *
  page253_i36
#CELL
  pure_quanta q_res *
  page253_i37
#ISCELL
  logical_power universal_gnd *
  page253_i38
#CELL
  pure_quanta q_cap *
  page253_i39
#ISCELL
  standard offpage *
  page253_i4
#CELL
  pure_quanta isl99390frztr5935 *
  page253_i40
#ISCELL
  logical_power vcc15 *
  page253_i41
#CELL
  pure_quanta q_res *
  page253_i42
#ISCELL
  logical_power universal_gnd *
  page253_i43
#CELL
  pure_quanta q_cap *
  page253_i44
#ISCELL
  standard offpage *
  page253_i45
#CELL
  pure_quanta q_inductor4p_14 *
  page253_i46
#CELL
  pure_quanta q_cap *
  page253_i47
#CELL
  pure_quanta q_cap *
  page253_i48
#CELL
  pure_quanta q_cap *
  page253_i49
#ISCELL
  standard offpage *
  page253_i5
#CELL
  pure_quanta q_cap *
  page253_i50
#CELL
  pure_quanta q_res *
  page253_i51
#ISCELL
  standard offpage *
  page253_i52
#ISCELL
  logical_power universal_gnd *
  page253_i53
#CELL
  pure_quanta q_cap *
  page253_i54
#ISCELL
  logical_power vcc15 *
  page253_i55
#CELL
  pure_quanta q_capp *
  page253_i56
#CELL
  pure_quanta q_cap *
  page253_i57
#CELL
  pure_quanta q_cap *
  page253_i58
#CELL
  pure_quanta q_res *
  page253_i59
#CELL
  pure_quanta isl99390frztr5935 *
  page253_i6
#CELL
  pure_quanta q_capp *
  page253_i60
#CELL
  pure_quanta q_capp *
  page253_i61
#CELL
  pure_quanta q_capp *
  page253_i62
#CELL
  pure_quanta q_capp *
  page253_i63
#CELL
  pure_quanta q_capp *
  page253_i64
#ISCELL
  logical_power universal_gnd *
  page253_i65
#CELL
  pure_quanta q_capp *
  page253_i66
#CELL
  pure_quanta q_capp *
  page253_i67
#ISCELL
  logical_power vcc15 *
  page253_i68
#ISCELL
  logical_power universal_gnd *
  page253_i69
#ISCELL
  standard offpage *
  page253_i7
#CELL
  pure_quanta q_capp *
  page253_i70
#ISCELL
  logical_power universal_gnd *
  page253_i71
#ISCELL
  logical_power vcc15 *
  page253_i72
#CELL
  pure_quanta q_res *
  page253_i73
#ISCELL
  logical_power universal_gnd *
  page253_i74
#CELL
  pure_quanta q_cap *
  page253_i75
#ISCELL
  standard offpage *
  page253_i76
#ISCELL
  logical_power gnd *
  page253_i77
#ISCELL
  logical_power vcc15 *
  page253_i78
#ISCELL
  logical_power vcc15 *
  page253_i79
#ISCELL
  standard offpage *
  page253_i8
#CELL
  pure_quanta q_cap *
  page253_i80
#CELL
  pure_quanta q_res *
  page253_i81
#CELL
  pure_quanta q_inductor *
  page253_i82
#CELL
  pure_quanta q_cap *
  page253_i83
#CELL
  pure_quanta q_cap *
  page253_i84
#CELL
  pure_quanta q_cap *
  page253_i85
#CELL
  pure_quanta q_cap *
  page253_i86
#ISCELL
  logical_power universal_gnd *
  page253_i87
#ISCELL
  logical_power vcc15 *
  page253_i88
#ISCELL
  logical_power vcc15 *
  page253_i89
#CELL
  pure_quanta q_cap *
  page253_i9
#ISCELL
  logical_power universal_gnd *
  page253_i90
#CELL
  pure_quanta q_capp *
  page253_i91
#CELL
  pure_quanta q_capp *
  page253_i92
#CELL
  pure_quanta q_capp *
  page253_i93
#CELL
  pure_quanta q_capp *
  page253_i94
#CELL
  pure_quanta q_capp *
  page253_i95
#ISCELL
  logical_power vcc15 *
  page253_i96
#CELL
  pure_quanta q_res *
  page253_i97
#ISCELL
  mstr_misc dns *
  *
#ISCELL
  pure_quanta quanta_title_block_c *
  *
#ISCELL
  logical_power universal_gnd *
  page254_i1
#ISCELL
  logical_power universal_gnd *
  page254_i10
#CELL
  pure_quanta q_cap *
  page254_i11
#CELL
  pure_quanta q_cap *
  page254_i12
#CELL
  pure_quanta isl99390frztr5935 *
  page254_i13
#CELL
  pure_quanta q_res *
  page254_i14
#ISCELL
  logical_power vcc15 *
  page254_i15
#ISCELL
  logical_power universal_gnd *
  page254_i16
#CELL
  pure_quanta q_cap *
  page254_i17
#ISCELL
  standard offpage *
  page254_i18
#ISCELL
  standard offpage *
  page254_i19
#CELL
  pure_quanta q_res *
  page254_i2
#CELL
  pure_quanta isl99390frztr5935 *
  page254_i20
#ISCELL
  logical_power universal_gnd *
  page254_i21
#ISCELL
  standard offpage *
  page254_i22
#ISCELL
  standard offpage *
  page254_i23
#ISCELL
  logical_power universal_gnd *
  page254_i24
#CELL
  pure_quanta q_cap *
  page254_i25
#CELL
  pure_quanta q_cap *
  page254_i26
#CELL
  pure_quanta q_res *
  page254_i27
#ISCELL
  logical_power vcc15 *
  page254_i28
#ISCELL
  logical_power universal_gnd *
  page254_i29
#ISCELL
  logical_power universal_gnd *
  page254_i3
#CELL
  pure_quanta q_cap *
  page254_i30
#ISCELL
  logical_power universal_gnd *
  page254_i31
#ISCELL
  standard offpage *
  page254_i32
#CELL
  pure_quanta q_inductor4p_14 *
  page254_i33
#CELL
  pure_quanta q_cap *
  page254_i34
#CELL
  pure_quanta q_cap *
  page254_i35
#CELL
  pure_quanta q_res *
  page254_i36
#ISCELL
  logical_power universal_gnd *
  page254_i37
#CELL
  pure_quanta q_cap *
  page254_i38
#CELL
  pure_quanta q_cap *
  page254_i39
#CELL
  pure_quanta q_res *
  page254_i4
#CELL
  pure_quanta q_cap *
  page254_i40
#CELL
  pure_quanta q_res *
  page254_i41
#ISCELL
  standard offpage *
  page254_i42
#CELL
  pure_quanta q_cap *
  page254_i43
#ISCELL
  logical_power universal_gnd *
  page254_i44
#ISCELL
  logical_power vcc15 *
  page254_i45
#CELL
  pure_quanta q_res *
  page254_i46
#ISCELL
  standard offpage *
  page254_i47
#CELL
  pure_quanta q_cap *
  page254_i48
#CELL
  pure_quanta q_res *
  page254_i49
#ISCELL
  logical_power universal_gnd *
  page254_i5
#CELL
  pure_quanta q_inductor4p_14 *
  page254_i50
#CELL
  pure_quanta q_cap *
  page254_i51
#CELL
  pure_quanta q_cap *
  page254_i52
#CELL
  pure_quanta q_cap *
  page254_i53
#CELL
  pure_quanta q_cap *
  page254_i54
#ISCELL
  logical_power universal_gnd *
  page254_i55
#CELL
  pure_quanta q_cap *
  page254_i56
#ISCELL
  logical_power vcc15 *
  page254_i57
#ISCELL
  standard offpage *
  page254_i58
#CELL
  pure_quanta q_cap *
  page254_i59
#ISCELL
  standard offpage *
  page254_i6
#CELL
  pure_quanta q_cap *
  page254_i60
#CELL
  pure_quanta q_cap *
  page254_i61
#ISCELL
  logical_power universal_gnd *
  page254_i62
#ISCELL
  logical_power vcc15 *
  page254_i63
#ISCELL
  logical_power universal_gnd *
  page254_i64
#CELL
  pure_quanta q_cap *
  page254_i65
#ISCELL
  logical_power vcc15 *
  page254_i66
#ISCELL
  standard offpage *
  page254_i7
#ISCELL
  standard offpage *
  page254_i8
#ISCELL
  standard offpage *
  page254_i9
#ISCELL
  mstr_misc dns *
  *
#ISCELL
  pure_quanta quanta_title_block_c *
  *
#ISCELL
  logical_power universal_gnd *
  page255_i1
#ISCELL
  logical_power universal_gnd *
  page255_i10
#CELL
  pure_quanta q_cap *
  page255_i11
#CELL
  pure_quanta isl99390frztr5935 *
  page255_i12
#CELL
  pure_quanta q_cap *
  page255_i13
#CELL
  pure_quanta q_res *
  page255_i14
#ISCELL
  logical_power vcc15 *
  page255_i15
#ISCELL
  logical_power universal_gnd *
  page255_i16
#CELL
  pure_quanta q_cap *
  page255_i17
#ISCELL
  standard offpage *
  page255_i18
#ISCELL
  standard offpage *
  page255_i19
#CELL
  pure_quanta q_res *
  page255_i2
#ISCELL
  logical_power universal_gnd *
  page255_i20
#ISCELL
  standard offpage *
  page255_i21
#ISCELL
  standard offpage *
  page255_i22
#ISCELL
  logical_power universal_gnd *
  page255_i23
#CELL
  pure_quanta q_cap *
  page255_i24
#CELL
  pure_quanta q_cap *
  page255_i25
#CELL
  pure_quanta q_res *
  page255_i26
#ISCELL
  logical_power vcc15 *
  page255_i27
#ISCELL
  logical_power universal_gnd *
  page255_i28
#CELL
  pure_quanta q_cap *
  page255_i29
#ISCELL
  logical_power universal_gnd *
  page255_i3
#ISCELL
  logical_power universal_gnd *
  page255_i30
#ISCELL
  standard offpage *
  page255_i31
#CELL
  pure_quanta q_inductor4p_14 *
  page255_i32
#CELL
  pure_quanta q_cap *
  page255_i33
#CELL
  pure_quanta q_cap *
  page255_i34
#CELL
  pure_quanta q_res *
  page255_i35
#ISCELL
  logical_power universal_gnd *
  page255_i36
#CELL
  pure_quanta q_cap *
  page255_i37
#CELL
  pure_quanta q_cap *
  page255_i38
#CELL
  pure_quanta q_cap *
  page255_i39
#CELL
  pure_quanta q_res *
  page255_i4
#CELL
  pure_quanta q_res *
  page255_i40
#ISCELL
  standard offpage *
  page255_i41
#CELL
  pure_quanta q_cap *
  page255_i42
#CELL
  pure_quanta q_cap *
  page255_i43
#ISCELL
  logical_power universal_gnd *
  page255_i44
#ISCELL
  logical_power vcc15 *
  page255_i45
#CELL
  pure_quanta q_res *
  page255_i46
#ISCELL
  standard offpage *
  page255_i47
#CELL
  pure_quanta q_cap *
  page255_i48
#CELL
  pure_quanta q_res *
  page255_i49
#ISCELL
  logical_power universal_gnd *
  page255_i5
#CELL
  pure_quanta q_inductor4p_14 *
  page255_i50
#CELL
  pure_quanta q_cap *
  page255_i51
#CELL
  pure_quanta q_cap *
  page255_i52
#CELL
  pure_quanta q_cap *
  page255_i53
#CELL
  pure_quanta q_cap *
  page255_i54
#ISCELL
  logical_power universal_gnd *
  page255_i55
#CELL
  pure_quanta q_cap *
  page255_i56
#ISCELL
  logical_power vcc15 *
  page255_i57
#ISCELL
  standard offpage *
  page255_i58
#CELL
  pure_quanta q_cap *
  page255_i59
#ISCELL
  standard offpage *
  page255_i6
#ISCELL
  logical_power universal_gnd *
  page255_i60
#ISCELL
  logical_power vcc15 *
  page255_i61
#ISCELL
  logical_power universal_gnd *
  page255_i62
#CELL
  pure_quanta q_cap *
  page255_i63
#CELL
  pure_quanta q_cap *
  page255_i64
#ISCELL
  logical_power vcc15 *
  page255_i65
#CELL
  pure_quanta isl99390frztr5935 *
  page255_i66
#ISCELL
  standard offpage *
  page255_i7
#ISCELL
  standard offpage *
  page255_i8
#ISCELL
  standard offpage *
  page255_i9
#ISCELL
  mstr_misc dns *
  *
#ISCELL
  pure_quanta quanta_title_block_c *
  *
#ISCELL
  logical_power universal_gnd *
  page256_i1
#ISCELL
  logical_power universal_gnd *
  page256_i10
#CELL
  pure_quanta q_cap *
  page256_i11
#CELL
  pure_quanta q_res *
  page256_i12
#ISCELL
  logical_power vcc15 *
  page256_i13
#ISCELL
  logical_power universal_gnd *
  page256_i14
#CELL
  pure_quanta q_cap *
  page256_i15
#ISCELL
  logical_power universal_gnd *
  page256_i16
#CELL
  pure_quanta q_cap *
  page256_i17
#ISCELL
  standard offpage *
  page256_i18
#CELL
  pure_quanta q_res *
  page256_i19
#CELL
  pure_quanta isl99390frztr5935 *
  page256_i2
#CELL
  pure_quanta q_cap *
  page256_i20
#CELL
  pure_quanta q_cap *
  page256_i21
#ISCELL
  logical_power universal_gnd *
  page256_i22
#CELL
  pure_quanta q_res *
  page256_i23
#ISCELL
  standard offpage *
  page256_i24
#ISCELL
  standard offpage *
  page256_i25
#ISCELL
  logical_power universal_gnd *
  page256_i26
#ISCELL
  standard offpage *
  page256_i27
#ISCELL
  standard offpage *
  page256_i28
#CELL
  pure_quanta q_cap *
  page256_i29
#ISCELL
  logical_power universal_gnd *
  page256_i3
#ISCELL
  logical_power universal_gnd *
  page256_i30
#CELL
  pure_quanta q_cap *
  page256_i31
#CELL
  pure_quanta isl99390frztr5935 *
  page256_i32
#CELL
  pure_quanta q_res *
  page256_i33
#ISCELL
  logical_power vcc15 *
  page256_i34
#ISCELL
  logical_power universal_gnd *
  page256_i35
#CELL
  pure_quanta q_cap *
  page256_i36
#ISCELL
  logical_power universal_gnd *
  page256_i37
#ISCELL
  logical_power universal_gnd *
  page256_i38
#CELL
  pure_quanta q_inductor *
  page256_i39
#CELL
  pure_quanta q_res *
  page256_i4
#CELL
  pure_quanta q_res *
  page256_i40
#CELL
  pure_quanta q_cap *
  page256_i41
#CELL
  pure_quanta q_cap *
  page256_i42
#CELL
  pure_quanta q_cap *
  page256_i43
#CELL
  pure_quanta q_inductor4p_14 *
  page256_i44
#CELL
  pure_quanta q_cap *
  page256_i45
#CELL
  pure_quanta q_res *
  page256_i46
#CELL
  pure_quanta q_cap *
  page256_i47
#CELL
  pure_quanta q_cap *
  page256_i48
#ISCELL
  logical_power universal_gnd *
  page256_i49
#ISCELL
  standard offpage *
  page256_i5
#ISCELL
  logical_power vcc15 *
  page256_i50
#ISCELL
  logical_power universal_gnd *
  page256_i51
#CELL
  pure_quanta q_cap *
  page256_i52
#CELL
  pure_quanta q_cap *
  page256_i53
#CELL
  pure_quanta q_cap *
  page256_i54
#ISCELL
  logical_power universal_gnd *
  page256_i55
#ISCELL
  logical_power vcc15 *
  page256_i56
#CELL
  pure_quanta q_res *
  page256_i57
#CELL
  pure_quanta q_inductor4p_14 *
  page256_i58
#CELL
  pure_quanta q_cap *
  page256_i59
#ISCELL
  standard offpage *
  page256_i6
#ISCELL
  logical_power universal_gnd *
  page256_i60
#ISCELL
  standard offpage *
  page256_i61
#CELL
  pure_quanta q_cap *
  page256_i62
#CELL
  pure_quanta q_cap *
  page256_i63
#CELL
  pure_quanta q_cap *
  page256_i64
#ISCELL
  logical_power vcc15 *
  page256_i65
#CELL
  pure_quanta q_cap *
  page256_i66
#CELL
  pure_quanta q_cap *
  page256_i67
#ISCELL
  logical_power universal_gnd *
  page256_i68
#ISCELL
  logical_power vcc15 *
  page256_i69
#CELL
  pure_quanta q_cap *
  page256_i7
#ISCELL
  standard offpage *
  page256_i8
#ISCELL
  standard offpage *
  page256_i9
#ISCELL
  mstr_misc dns *
  *
#ISCELL
  pure_quanta quanta_title_block_c *
  *
#ISCELL
  logical_power universal_gnd *
  page257_i1
#ISCELL
  logical_power vcc15 *
  page257_i10
#ISCELL
  standard offpage *
  page257_i11
#ISCELL
  standard offpage *
  page257_i12
#ISCELL
  standard offpage *
  page257_i13
#ISCELL
  standard offpage *
  page257_i14
#CELL
  pure_quanta q_cap *
  page257_i15
#CELL
  pure_quanta isl99390frztr5935 *
  page257_i16
#ISCELL
  logical_power universal_gnd *
  page257_i17
#CELL
  pure_quanta q_cap *
  page257_i18
#CELL
  pure_quanta q_res *
  page257_i19
#CELL
  pure_quanta q_res *
  page257_i2
#ISCELL
  logical_power universal_gnd *
  page257_i20
#CELL
  pure_quanta q_cap *
  page257_i21
#CELL
  pure_quanta q_res *
  page257_i22
#ISCELL
  logical_power vcc15 *
  page257_i23
#ISCELL
  standard offpage *
  page257_i24
#CELL
  pure_quanta isl99390frztr5935 *
  page257_i25
#ISCELL
  logical_power universal_gnd *
  page257_i26
#CELL
  pure_quanta q_cap *
  page257_i27
#CELL
  pure_quanta q_cap *
  page257_i28
#ISCELL
  logical_power universal_gnd *
  page257_i29
#ISCELL
  logical_power universal_gnd *
  page257_i3
#CELL
  pure_quanta q_res *
  page257_i30
#CELL
  pure_quanta q_cap *
  page257_i31
#CELL
  pure_quanta q_cap *
  page257_i32
#ISCELL
  standard offpage *
  page257_i33
#ISCELL
  standard offpage *
  page257_i34
#CELL
  pure_quanta q_cap *
  page257_i35
#ISCELL
  standard offpage *
  page257_i36
#CELL
  pure_quanta q_cap *
  page257_i37
#ISCELL
  logical_power universal_gnd *
  page257_i38
#CELL
  pure_quanta q_res *
  page257_i39
#CELL
  pure_quanta q_res *
  page257_i4
#CELL
  pure_quanta q_res *
  page257_i40
#ISCELL
  logical_power universal_gnd *
  page257_i41
#CELL
  pure_quanta q_cap *
  page257_i42
#ISCELL
  logical_power vcc15 *
  page257_i43
#CELL
  pure_quanta q_cap *
  page257_i44
#CELL
  pure_quanta q_cap *
  page257_i45
#CELL
  pure_quanta q_res *
  page257_i46
#CELL
  pure_quanta q_cap *
  page257_i47
#CELL
  pure_quanta q_cap *
  page257_i48
#CELL
  pure_quanta q_inductor *
  page257_i49
#ISCELL
  logical_power vcc15 *
  page257_i5
#CELL
  pure_quanta q_res *
  page257_i50
#CELL
  pure_quanta q_cap *
  page257_i51
#CELL
  pure_quanta q_cap *
  page257_i52
#CELL
  pure_quanta q_cap *
  page257_i53
#ISCELL
  logical_power universal_gnd *
  page257_i54
#CELL
  pure_quanta q_cap *
  page257_i55
#ISCELL
  logical_power vcc15 *
  page257_i56
#CELL
  pure_quanta q_capp *
  page257_i57
#CELL
  pure_quanta q_capp *
  page257_i58
#CELL
  pure_quanta q_cap *
  page257_i59
#ISCELL
  logical_power universal_gnd *
  page257_i6
#CELL
  pure_quanta q_res *
  page257_i60
#ISCELL
  logical_power universal_gnd *
  page257_i61
#CELL
  pure_quanta q_capp *
  page257_i62
#CELL
  pure_quanta q_capp *
  page257_i63
#ISCELL
  logical_power universal_gnd *
  page257_i64
#ISCELL
  logical_power vcc15 *
  page257_i65
#ISCELL
  logical_power universal_gnd *
  page257_i66
#CELL
  pure_quanta q_capp *
  page257_i67
#ISCELL
  logical_power vcc15 *
  page257_i68
#CELL
  pure_quanta q_res *
  page257_i69
#ISCELL
  logical_power universal_gnd *
  page257_i7
#CELL
  pure_quanta q_inductor *
  page257_i70
#CELL
  pure_quanta q_cap *
  page257_i71
#ISCELL
  logical_power universal_gnd *
  page257_i72
#CELL
  pure_quanta q_cap *
  page257_i73
#ISCELL
  logical_power vcc15 *
  page257_i74
#CELL
  pure_quanta q_cap *
  page257_i75
#ISCELL
  logical_power gnd *
  page257_i76
#CELL
  pure_quanta q_cap *
  page257_i77
#CELL
  pure_quanta q_cap *
  page257_i78
#ISCELL
  logical_power vcc15 *
  page257_i79
#CELL
  pure_quanta q_res *
  page257_i8
#CELL
  pure_quanta q_inductor *
  page257_i80
#CELL
  pure_quanta q_cap *
  page257_i81
#ISCELL
  logical_power vcc15 *
  page257_i82
#CELL
  pure_quanta q_cap *
  page257_i83
#CELL
  pure_quanta q_cap *
  page257_i84
#CELL
  pure_quanta q_cap *
  page257_i85
#CELL
  pure_quanta q_cap *
  page257_i86
#ISCELL
  logical_power universal_gnd *
  page257_i87
#CELL
  pure_quanta q_capp *
  page257_i88
#ISCELL
  logical_power vcc15 *
  page257_i89
#CELL
  pure_quanta q_res *
  page257_i9
#ISCELL
  mstr_misc dns *
  *
#ISCELL
  pure_quanta quanta_title_block_c *
  *
#ISCELL
  logical_power universal_gnd *
  page258_i1
#CELL
  pure_quanta isl99390frztr5935 *
  page258_i10
#CELL
  pure_quanta q_res *
  page258_i11
#ISCELL
  logical_power vcc15 *
  page258_i12
#CELL
  pure_quanta q_cap *
  page258_i13
#ISCELL
  logical_power universal_gnd *
  page258_i14
#CELL
  pure_quanta q_res *
  page258_i15
#ISCELL
  standard offpage *
  page258_i16
#ISCELL
  standard offpage *
  page258_i17
#CELL
  pure_quanta q_cap *
  page258_i18
#ISCELL
  logical_power universal_gnd *
  page258_i19
#ISCELL
  logical_power universal_gnd *
  page258_i2
#ISCELL
  logical_power universal_gnd *
  page258_i20
#ISCELL
  standard offpage *
  page258_i21
#ISCELL
  standard offpage *
  page258_i22
#CELL
  pure_quanta q_cap *
  page258_i23
#ISCELL
  logical_power universal_gnd *
  page258_i24
#CELL
  pure_quanta q_cap *
  page258_i25
#CELL
  pure_quanta q_res *
  page258_i26
#ISCELL
  logical_power vcc15 *
  page258_i27
#CELL
  pure_quanta q_cap *
  page258_i28
#ISCELL
  logical_power universal_gnd *
  page258_i29
#CELL
  pure_quanta q_res *
  page258_i3
#ISCELL
  logical_power universal_gnd *
  page258_i30
#CELL
  pure_quanta q_cap *
  page258_i31
#ISCELL
  logical_power universal_gnd *
  page258_i32
#CELL
  pure_quanta q_res *
  page258_i33
#CELL
  pure_quanta q_cap *
  page258_i34
#CELL
  pure_quanta q_cap *
  page258_i35
#CELL
  pure_quanta q_cap *
  page258_i36
#CELL
  pure_quanta q_cap *
  page258_i37
#CELL
  pure_quanta q_res *
  page258_i38
#CELL
  pure_quanta q_inductor *
  page258_i39
#ISCELL
  standard offpage *
  page258_i4
#CELL
  pure_quanta q_cap *
  page258_i40
#CELL
  pure_quanta q_cap *
  page258_i41
#ISCELL
  logical_power universal_gnd *
  page258_i42
#ISCELL
  logical_power vcc15 *
  page258_i43
#CELL
  pure_quanta q_cap *
  page258_i44
#CELL
  pure_quanta q_res *
  page258_i45
#CELL
  pure_quanta q_cap *
  page258_i46
#CELL
  pure_quanta q_cap *
  page258_i47
#CELL
  pure_quanta q_cap *
  page258_i48
#CELL
  pure_quanta q_cap *
  page258_i49
#ISCELL
  standard offpage *
  page258_i5
#CELL
  pure_quanta q_res *
  page258_i50
#CELL
  pure_quanta q_inductor *
  page258_i51
#ISCELL
  logical_power universal_gnd *
  page258_i52
#CELL
  pure_quanta q_cap *
  page258_i53
#ISCELL
  logical_power vcc15 *
  page258_i54
#CELL
  pure_quanta q_cap *
  page258_i55
#ISCELL
  logical_power gnd *
  page258_i56
#CELL
  pure_quanta q_cap *
  page258_i57
#ISCELL
  logical_power vcc15 *
  page258_i58
#CELL
  pure_quanta q_inductor *
  page258_i59
#ISCELL
  standard offpage *
  page258_i6
#CELL
  pure_quanta q_cap *
  page258_i60
#CELL
  pure_quanta q_cap *
  page258_i61
#ISCELL
  logical_power universal_gnd *
  page258_i62
#ISCELL
  logical_power vcc15 *
  page258_i63
#CELL
  pure_quanta q_capp *
  page258_i64
#CELL
  pure_quanta q_capp *
  page258_i65
#ISCELL
  logical_power universal_gnd *
  page258_i66
#ISCELL
  logical_power universal_gnd *
  page258_i67
#CELL
  pure_quanta q_capp *
  page258_i68
#CELL
  pure_quanta q_capp *
  page258_i69
#ISCELL
  standard offpage *
  page258_i7
#CELL
  pure_quanta q_capp *
  page258_i70
#ISCELL
  logical_power vcc15 *
  page258_i71
#CELL
  pure_quanta q_cap *
  page258_i72
#CELL
  pure_quanta q_cap *
  page258_i73
#ISCELL
  logical_power vcc15 *
  page258_i74
#CELL
  pure_quanta q_cap *
  page258_i75
#CELL
  pure_quanta q_cap *
  page258_i76
#CELL
  pure_quanta q_cap *
  page258_i77
#ISCELL
  logical_power universal_gnd *
  page258_i78
#CELL
  pure_quanta q_cap *
  page258_i79
#ISCELL
  logical_power universal_gnd *
  page258_i8
#CELL
  pure_quanta q_capp *
  page258_i80
#ISCELL
  logical_power vcc15 *
  page258_i81
#CELL
  pure_quanta isl99390frztr5935 *
  page258_i82
#CELL
  pure_quanta q_cap *
  page258_i9
#ISCELL
  pure_quanta quanta_title_block_c *
  *
#ISCELL
  mstr_misc dns *
  *
#ISCELL
  pure_quanta quanta_title_block_c *
  *
#ISCELL
  standard offpage *
  page260_i1
#CELL
  pure_quanta q_res *
  page260_i10
#CELL
  pure_quanta q_res *
  page260_i100
#ISCELL
  logical_power universal_gnd *
  page260_i101
#ISCELL
  standard offpage *
  page260_i102
#ISCELL
  logical_power universal_gnd *
  page260_i103
#ISCELL
  logical_power vcc15 *
  page260_i104
#ISCELL
  logical_power universal_gnd *
  page260_i105
#CELL
  pure_quanta q_res *
  page260_i106
#ISCELL
  standard offpage *
  page260_i107
#ISCELL
  standard offpage *
  page260_i108
#CELL
  pure_quanta q_res *
  page260_i109
#CELL
  pure_quanta q_res *
  page260_i11
#CELL
  pure_quanta q_cap *
  page260_i110
#ISCELL
  logical_power vcc15 *
  page260_i12
#CELL
  pure_quanta q_res *
  page260_i13
#CELL
  pure_quanta q_res *
  page260_i14
#ISCELL
  logical_power universal_gnd *
  page260_i15
#ISCELL
  logical_power vcc15 *
  page260_i16
#CELL
  pure_quanta q_res *
  page260_i17
#CELL
  pure_quanta q_res *
  page260_i18
#CELL
  pure_quanta q_res *
  page260_i19
#ISCELL
  standard offpage *
  page260_i2
#CELL
  pure_quanta q_cap *
  page260_i20
#CELL
  pure_quanta q_res *
  page260_i21
#CELL
  pure_quanta q_cap *
  page260_i22
#CELL
  pure_quanta q_cap *
  page260_i23
#ISCELL
  standard offpage *
  page260_i24
#ISCELL
  standard offpage *
  page260_i25
#ISCELL
  standard offpage *
  page260_i26
#ISCELL
  standard offpage *
  page260_i27
#ISCELL
  logical_power vcc15 *
  page260_i28
#ISCELL
  standard offpage *
  page260_i29
#ISCELL
  standard offpage *
  page260_i3
#ISCELL
  standard offpage *
  page260_i30
#ISCELL
  standard offpage *
  page260_i31
#ISCELL
  standard offpage *
  page260_i32
#ISCELL
  standard offpage *
  page260_i33
#ISCELL
  standard offpage *
  page260_i34
#ISCELL
  standard offpage *
  page260_i35
#CELL
  pure_quanta q_res *
  page260_i36
#CELL
  pure_quanta q_res *
  page260_i37
#CELL
  pure_quanta q_res *
  page260_i38
#CELL
  pure_quanta q_short *
  page260_i39
#ISCELL
  logical_power universal_gnd *
  page260_i4
#CELL
  pure_quanta q_res *
  page260_i40
#ISCELL
  logical_power vcc15 *
  page260_i41
#CELL
  pure_quanta q_res *
  page260_i42
#CELL
  pure_quanta q_short *
  page260_i43
#CELL
  pure_quanta q_res *
  page260_i44
#ISCELL
  logical_power universal_gnd *
  page260_i45
#ISCELL
  logical_power vcc15 *
  page260_i46
#CELL
  pure_quanta q_res *
  page260_i47
#CELL
  pure_quanta q_cap *
  page260_i48
#CELL
  pure_quanta q_res *
  page260_i49
#ISCELL
  logical_power universal_gnd *
  page260_i5
#CELL
  pure_quanta q_cap *
  page260_i50
#CELL
  pure_quanta q_res *
  page260_i51
#CELL
  pure_quanta q_res *
  page260_i52
#CELL
  pure_quanta q_res *
  page260_i53
#ISCELL
  logical_power vcc15 *
  page260_i54
#CELL
  pure_quanta q_res *
  page260_i55
#CELL
  pure_quanta q_res *
  page260_i56
#CELL
  pure_quanta q_res *
  page260_i57
#CELL
  pure_quanta q_res *
  page260_i58
#CELL
  pure_quanta q_res *
  page260_i59
#CELL
  pure_quanta q_cap *
  page260_i60
#CELL
  pure_quanta q_cap *
  page260_i61
#ISCELL
  logical_power universal_gnd *
  page260_i62
#CELL
  pure_quanta q_cap *
  page260_i63
#ISCELL
  logical_power universal_gnd *
  page260_i64
#CELL
  pure_quanta isl69260irazt *
  page260_i65
#ISCELL
  logical_power universal_gnd *
  page260_i66
#ISCELL
  logical_power universal_gnd *
  page260_i67
#ISCELL
  logical_power universal_gnd *
  page260_i68
#CELL
  pure_quanta q_cap *
  page260_i69
#CELL
  pure_quanta q_res *
  page260_i7
#ISCELL
  logical_power universal_gnd *
  page260_i70
#CELL
  pure_quanta q_res *
  page260_i71
#ISCELL
  logical_power universal_gnd *
  page260_i72
#CELL
  pure_quanta q_cap *
  page260_i73
#ISCELL
  standard offpage *
  page260_i74
#ISCELL
  standard offpage *
  page260_i75
#CELL
  pure_quanta q_res *
  page260_i76
#ISCELL
  standard offpage *
  page260_i77
#CELL
  pure_quanta q_res *
  page260_i78
#CELL
  pure_quanta q_res *
  page260_i79
#ISCELL
  logical_power vcc15 *
  page260_i8
#ISCELL
  logical_power universal_gnd *
  page260_i80
#ISCELL
  logical_power vcc15 *
  page260_i81
#ISCELL
  logical_power universal_gnd *
  page260_i82
#ISCELL
  logical_power universal_gnd *
  page260_i83
#CELL
  pure_quanta q_res *
  page260_i84
#CELL
  pure_quanta q_res *
  page260_i85
#CELL
  pure_quanta q_res *
  page260_i86
#CELL
  pure_quanta q_res *
  page260_i87
#ISCELL
  logical_power universal_gnd *
  page260_i88
#ISCELL
  logical_power universal_gnd *
  page260_i89
#CELL
  pure_quanta q_res *
  page260_i9
#ISCELL
  logical_power universal_gnd *
  page260_i90
#ISCELL
  logical_power universal_gnd *
  page260_i91
#CELL
  pure_quanta q_cap *
  page260_i92
#ISCELL
  standard offpage *
  page260_i93
#ISCELL
  standard offpage *
  page260_i94
#CELL
  pure_quanta q_cap *
  page260_i95
#ISCELL
  standard offpage *
  page260_i96
#ISCELL
  standard offpage *
  page260_i97
#CELL
  pure_quanta q_cap *
  page260_i98
#CELL
  pure_quanta q_cap *
  page260_i99
#ISCELL
  mstr_misc dns *
  *
#ISCELL
  pure_quanta quanta_title_block_c *
  *
#ISCELL
  logical_power universal_gnd *
  page261_i1
#ISCELL
  logical_power universal_gnd *
  page261_i10
#CELL
  pure_quanta q_cap *
  page261_i11
#CELL
  pure_quanta isl99390frztr5935 *
  page261_i12
#CELL
  pure_quanta q_cap *
  page261_i13
#CELL
  pure_quanta q_res *
  page261_i14
#ISCELL
  logical_power universal_gnd *
  page261_i15
#CELL
  pure_quanta q_cap *
  page261_i16
#ISCELL
  logical_power vcc15 *
  page261_i17
#ISCELL
  standard offpage *
  page261_i18
#ISCELL
  standard offpage *
  page261_i19
#CELL
  pure_quanta q_res *
  page261_i2
#ISCELL
  logical_power universal_gnd *
  page261_i20
#ISCELL
  standard offpage *
  page261_i21
#ISCELL
  standard offpage *
  page261_i22
#ISCELL
  logical_power universal_gnd *
  page261_i23
#CELL
  pure_quanta q_cap *
  page261_i24
#CELL
  pure_quanta q_cap *
  page261_i25
#CELL
  pure_quanta q_res *
  page261_i26
#ISCELL
  logical_power vcc15 *
  page261_i27
#ISCELL
  logical_power universal_gnd *
  page261_i28
#CELL
  pure_quanta q_cap *
  page261_i29
#ISCELL
  logical_power universal_gnd *
  page261_i3
#ISCELL
  logical_power universal_gnd *
  page261_i30
#CELL
  pure_quanta q_res *
  page261_i31
#CELL
  pure_quanta q_cap *
  page261_i32
#ISCELL
  logical_power universal_gnd *
  page261_i33
#CELL
  pure_quanta q_res *
  page261_i34
#CELL
  pure_quanta q_cap *
  page261_i35
#CELL
  pure_quanta q_cap *
  page261_i36
#CELL
  pure_quanta q_cap *
  page261_i37
#CELL
  pure_quanta q_cap *
  page261_i38
#CELL
  pure_quanta q_inductor *
  page261_i39
#ISCELL
  logical_power universal_gnd *
  page261_i4
#CELL
  pure_quanta q_cap *
  page261_i40
#CELL
  pure_quanta q_cap *
  page261_i41
#ISCELL
  logical_power universal_gnd *
  page261_i42
#ISCELL
  logical_power vcc15 *
  page261_i43
#ISCELL
  logical_power universal_gnd *
  page261_i44
#CELL
  pure_quanta q_cap *
  page261_i45
#CELL
  pure_quanta q_res *
  page261_i46
#CELL
  pure_quanta q_res *
  page261_i47
#CELL
  pure_quanta q_cap *
  page261_i48
#CELL
  pure_quanta q_cap *
  page261_i49
#CELL
  pure_quanta q_res *
  page261_i5
#CELL
  pure_quanta q_cap *
  page261_i50
#CELL
  pure_quanta q_cap *
  page261_i51
#CELL
  pure_quanta q_inductor *
  page261_i52
#ISCELL
  logical_power universal_gnd *
  page261_i53
#CELL
  pure_quanta q_cap *
  page261_i54
#ISCELL
  logical_power vcc15 *
  page261_i55
#CELL
  pure_quanta q_cap *
  page261_i56
#CELL
  pure_quanta q_cap *
  page261_i57
#ISCELL
  logical_power vcc15 *
  page261_i58
#ISCELL
  logical_power gnd *
  page261_i59
#ISCELL
  standard offpage *
  page261_i6
#CELL
  pure_quanta q_cap *
  page261_i60
#ISCELL
  logical_power vcc15 *
  page261_i61
#CELL
  pure_quanta q_inductor *
  page261_i62
#CELL
  pure_quanta q_res *
  page261_i63
#ISCELL
  logical_power universal_gnd *
  page261_i64
#ISCELL
  logical_power vcc15 *
  page261_i65
#CELL
  pure_quanta q_capp *
  page261_i66
#CELL
  pure_quanta q_capp *
  page261_i67
#CELL
  pure_quanta q_capp *
  page261_i68
#CELL
  pure_quanta q_capp *
  page261_i69
#ISCELL
  standard offpage *
  page261_i7
#CELL
  pure_quanta q_capp *
  page261_i70
#ISCELL
  logical_power universal_gnd *
  page261_i71
#ISCELL
  logical_power vcc15 *
  page261_i72
#ISCELL
  logical_power universal_gnd *
  page261_i73
#CELL
  pure_quanta q_capp *
  page261_i74
#CELL
  pure_quanta q_capp *
  page261_i75
#ISCELL
  logical_power universal_gnd *
  page261_i76
#ISCELL
  logical_power vcc15 *
  page261_i77
#ISCELL
  logical_power vcc15 *
  page261_i78
#CELL
  pure_quanta isl99390frztr5935 *
  page261_i79
#ISCELL
  standard offpage *
  page261_i8
#ISCELL
  standard offpage *
  page261_i9
#ISCELL
  mstr_misc dns *
  *
#ISCELL
  pure_quanta quanta_title_block_c *
  *
#ISCELL
  logical_power universal_gnd *
  page262_i1
#CELL
  pure_quanta q_cap *
  page262_i10
#ISCELL
  logical_power universal_gnd *
  page262_i11
#CELL
  pure_quanta q_cap *
  page262_i12
#CELL
  pure_quanta q_res *
  page262_i13
#CELL
  pure_quanta raa2213404gnphb0 *
  page262_i14
#CELL
  pure_quanta q_res *
  page262_i15
#CELL
  pure_quanta q_res *
  page262_i16
#CELL
  pure_quanta q_res *
  page262_i17
#ISCELL
  logical_power universal_gnd *
  page262_i18
#ISCELL
  logical_power vcc15 *
  page262_i19
#CELL
  pure_quanta q_res *
  page262_i2
#CELL
  pure_quanta q_cap *
  page262_i20
#CELL
  pure_quanta q_res *
  page262_i21
#CELL
  pure_quanta q_res *
  page262_i22
#ISCELL
  logical_power vcc15 *
  page262_i23
#CELL
  pure_quanta q_cap *
  page262_i24
#CELL
  pure_quanta q_cap *
  page262_i25
#CELL
  pure_quanta q_cap *
  page262_i26
#CELL
  pure_quanta q_cap *
  page262_i27
#CELL
  pure_quanta q_cap *
  page262_i28
#CELL
  pure_quanta q_inductor *
  page262_i29
#ISCELL
  standard offpage *
  page262_i3
#ISCELL
  logical_power universal_gnd *
  page262_i30
#CELL
  pure_quanta q_cap *
  page262_i31
#CELL
  pure_quanta q_cap *
  page262_i32
#CELL
  pure_quanta q_capp *
  page262_i33
#CELL
  pure_quanta q_capp *
  page262_i34
#ISCELL
  logical_power universal_gnd *
  page262_i35
#CELL
  pure_quanta q_res *
  page262_i36
#ISCELL
  logical_power vcc15 *
  page262_i37
#ISCELL
  logical_power vcc15 *
  page262_i38
#ISCELL
  standard offpage *
  page262_i4
#ISCELL
  logical_power universal_gnd *
  page262_i5
#ISCELL
  standard offpage *
  page262_i6
#ISCELL
  standard offpage *
  page262_i7
#CELL
  pure_quanta q_res *
  page262_i8
#ISCELL
  logical_power vcc15 *
  page262_i9
#ISCELL
  pure_quanta quanta_title_block_c *
  *
#ISCELL
  mstr_misc dns *
  *
#ISCELL
  pure_quanta quanta_title_block_c *
  *
#ISCELL
  standard offpage *
  page264_i1
#CELL
  pure_quanta q_res *
  page264_i10
#CELL
  pure_quanta q_res *
  page264_i11
#ISCELL
  standard offpage *
  page264_i12
#CELL
  pure_quanta q_res *
  page264_i13
#CELL
  pure_quanta q_res *
  page264_i14
#ISCELL
  standard offpage *
  page264_i15
#ISCELL
  standard offpage *
  page264_i16
#ISCELL
  logical_power universal_gnd *
  page264_i17
#CELL
  pure_quanta q_cap *
  page264_i18
#CELL
  pure_quanta q_cap *
  page264_i19
#ISCELL
  standard offpage *
  page264_i2
#ISCELL
  logical_power vcc15 *
  page264_i20
#ISCELL
  standard offpage *
  page264_i21
#ISCELL
  standard offpage *
  page264_i22
#ISCELL
  standard offpage *
  page264_i23
#CELL
  pure_quanta q_res *
  page264_i24
#CELL
  pure_quanta q_res *
  page264_i25
#ISCELL
  standard offpage *
  page264_i26
#ISCELL
  standard offpage *
  page264_i27
#ISCELL
  standard offpage *
  page264_i28
#ISCELL
  standard offpage *
  page264_i29
#ISCELL
  standard offpage *
  page264_i3
#CELL
  pure_quanta q_res *
  page264_i30
#CELL
  pure_quanta q_res *
  page264_i31
#CELL
  pure_quanta q_short *
  page264_i32
#ISCELL
  logical_power universal_gnd *
  page264_i33
#ISCELL
  logical_power vcc15 *
  page264_i34
#ISCELL
  logical_power vcc15 *
  page264_i35
#CELL
  pure_quanta q_res *
  page264_i36
#CELL
  pure_quanta q_cap *
  page264_i37
#CELL
  pure_quanta q_res *
  page264_i38
#CELL
  pure_quanta q_res *
  page264_i39
#ISCELL
  logical_power universal_gnd *
  page264_i4
#CELL
  pure_quanta q_res *
  page264_i40
#ISCELL
  logical_power vcc15 *
  page264_i41
#CELL
  pure_quanta q_res *
  page264_i42
#CELL
  pure_quanta q_res *
  page264_i43
#CELL
  pure_quanta q_res *
  page264_i44
#CELL
  pure_quanta q_res *
  page264_i45
#CELL
  pure_quanta q_res *
  page264_i46
#CELL
  pure_quanta q_cap *
  page264_i47
#CELL
  pure_quanta q_res *
  page264_i48
#ISCELL
  logical_power universal_gnd *
  page264_i49
#CELL
  pure_quanta q_res *
  page264_i5
#CELL
  pure_quanta q_cap *
  page264_i50
#CELL
  pure_quanta q_cap *
  page264_i51
#ISCELL
  logical_power universal_gnd *
  page264_i52
#CELL
  pure_quanta isl69260irazt *
  page264_i53
#ISCELL
  logical_power universal_gnd *
  page264_i54
#ISCELL
  logical_power universal_gnd *
  page264_i55
#CELL
  pure_quanta q_cap *
  page264_i56
#CELL
  pure_quanta q_res *
  page264_i57
#ISCELL
  logical_power universal_gnd *
  page264_i58
#CELL
  pure_quanta q_res *
  page264_i59
#CELL
  pure_quanta q_res *
  page264_i60
#CELL
  pure_quanta q_res *
  page264_i61
#CELL
  pure_quanta q_res *
  page264_i62
#CELL
  pure_quanta q_res *
  page264_i63
#ISCELL
  logical_power universal_gnd *
  page264_i64
#ISCELL
  logical_power universal_gnd *
  page264_i65
#CELL
  pure_quanta q_res *
  page264_i66
#CELL
  pure_quanta q_res *
  page264_i67
#CELL
  pure_quanta q_res *
  page264_i68
#CELL
  pure_quanta q_res *
  page264_i69
#CELL
  pure_quanta q_res *
  page264_i7
#CELL
  pure_quanta q_cap *
  page264_i70
#CELL
  pure_quanta q_cap *
  page264_i71
#CELL
  pure_quanta q_cap *
  page264_i72
#CELL
  pure_quanta q_cap *
  page264_i73
#CELL
  pure_quanta q_res *
  page264_i74
#ISCELL
  standard offpage *
  page264_i75
#ISCELL
  standard offpage *
  page264_i76
#ISCELL
  logical_power universal_gnd *
  page264_i77
#ISCELL
  logical_power universal_gnd *
  page264_i78
#ISCELL
  standard offpage *
  page264_i79
#ISCELL
  logical_power universal_gnd *
  page264_i8
#CELL
  pure_quanta q_res *
  page264_i80
#ISCELL
  logical_power vcc15 *
  page264_i81
#ISCELL
  standard offpage *
  page264_i82
#ISCELL
  logical_power universal_gnd *
  page264_i83
#ISCELL
  logical_power universal_gnd *
  page264_i84
#CELL
  pure_quanta q_res *
  page264_i85
#ISCELL
  logical_power vcc15 *
  page264_i86
#ISCELL
  logical_power universal_gnd *
  page264_i87
#ISCELL
  standard offpage *
  page264_i88
#ISCELL
  standard offpage *
  page264_i89
#CELL
  pure_quanta q_cap *
  page264_i9
#ISCELL
  logical_power universal_gnd *
  page264_i90
#ISCELL
  logical_power universal_gnd *
  page264_i91
#ISCELL
  logical_power universal_gnd *
  page264_i92
#ISCELL
  logical_power universal_gnd *
  page264_i93
#ISCELL
  logical_power universal_gnd *
  page264_i94
#CELL
  pure_quanta q_res *
  page264_i95
#CELL
  pure_quanta q_cap *
  page264_i96
#ISCELL
  mstr_misc dns *
  *
#ISCELL
  pure_quanta quanta_title_block_c *
  *
#ISCELL
  logical_power universal_gnd *
  page265_i1
#ISCELL
  logical_power universal_gnd *
  page265_i10
#CELL
  pure_quanta q_cap *
  page265_i11
#CELL
  pure_quanta q_res *
  page265_i12
#ISCELL
  logical_power universal_gnd *
  page265_i13
#CELL
  pure_quanta q_cap *
  page265_i14
#ISCELL
  logical_power vcc15 *
  page265_i15
#ISCELL
  logical_power universal_gnd *
  page265_i16
#CELL
  pure_quanta q_res *
  page265_i17
#CELL
  pure_quanta q_cap *
  page265_i18
#CELL
  pure_quanta q_res *
  page265_i19
#ISCELL
  logical_power universal_gnd *
  page265_i2
#CELL
  pure_quanta q_cap *
  page265_i20
#CELL
  pure_quanta q_cap *
  page265_i21
#CELL
  pure_quanta q_cap *
  page265_i22
#CELL
  pure_quanta q_cap *
  page265_i23
#CELL
  pure_quanta q_cap *
  page265_i24
#CELL
  pure_quanta q_cap *
  page265_i25
#CELL
  pure_quanta q_capp *
  page265_i26
#CELL
  pure_quanta q_capp *
  page265_i27
#CELL
  pure_quanta q_cap *
  page265_i28
#CELL
  pure_quanta q_cap *
  page265_i29
#CELL
  pure_quanta q_res *
  page265_i3
#CELL
  pure_quanta q_inductor *
  page265_i30
#ISCELL
  logical_power universal_gnd *
  page265_i31
#ISCELL
  logical_power vcc15 *
  page265_i32
#ISCELL
  logical_power universal_gnd *
  page265_i33
#CELL
  pure_quanta q_capp *
  page265_i34
#ISCELL
  logical_power vcc15 *
  page265_i35
#ISCELL
  logical_power universal_gnd *
  page265_i36
#CELL
  pure_quanta q_res *
  page265_i37
#ISCELL
  logical_power vcc15 *
  page265_i38
#ISCELL
  standard offpage *
  page265_i4
#ISCELL
  standard offpage *
  page265_i5
#ISCELL
  standard offpage *
  page265_i6
#CELL
  pure_quanta q_cap *
  page265_i7
#CELL
  pure_quanta isl99390frztr5935 *
  page265_i8
#ISCELL
  standard offpage *
  page265_i9
#ISCELL
  pure_quanta quanta_title_block_c *
  *
#ISCELL
  mstr_misc dns *
  *
#ISCELL
  pure_quanta quanta_title_block_c *
  *
#ISCELL
  logical_power universal_gnd *
  page267_i1
#CELL
  pure_quanta q_cap *
  page267_i10
#ISCELL
  logical_power universal_gnd *
  page267_i11
#CELL
  pure_quanta q_cap *
  page267_i12
#ISCELL
  logical_power universal_gnd *
  page267_i13
#CELL
  pure_quanta q_res *
  page267_i14
#CELL
  pure_quanta q_res *
  page267_i15
#CELL
  pure_quanta q_cap *
  page267_i16
#CELL
  pure_quanta q_cap *
  page267_i17
#CELL
  pure_quanta q_res *
  page267_i18
#CELL
  pure_quanta rs53318lr *
  page267_i19
#ISCELL
  standard offpage *
  page267_i2
#ISCELL
  logical_power universal_gnd *
  page267_i20
#ISCELL
  logical_power vccaux15 *
  page267_i21
#ISCELL
  logical_power universal_gnd *
  page267_i22
#CELL
  pure_quanta q_cap *
  page267_i23
#ISCELL
  logical_power universal_gnd *
  page267_i24
#CELL
  pure_quanta q_cap *
  page267_i25
#CELL
  pure_quanta q_res *
  page267_i26
#CELL
  pure_quanta q_cap *
  page267_i27
#CELL
  pure_quanta q_inductor *
  page267_i28
#CELL
  pure_quanta q_res *
  page267_i29
#ISCELL
  logical_power vccaux15 *
  page267_i3
#CELL
  pure_quanta q_cap *
  page267_i30
#CELL
  pure_quanta mosfet_n *
  page267_i31
#ISCELL
  standard offpage *
  page267_i32
#CELL
  pure_quanta q_short *
  page267_i33
#CELL
  pure_quanta q_res *
  page267_i34
#CELL
  pure_quanta q_cap *
  page267_i35
#CELL
  pure_quanta q_res *
  page267_i36
#ISCELL
  logical_power universal_gnd *
  page267_i37
#CELL
  pure_quanta q_cap *
  page267_i38
#ISCELL
  standard offpage *
  page267_i39
#CELL
  pure_quanta q_cap *
  page267_i4
#CELL
  pure_quanta q_cap *
  page267_i40
#CELL
  pure_quanta q_short *
  page267_i41
#CELL
  pure_quanta q_cap *
  page267_i42
#CELL
  pure_quanta q_cap *
  page267_i43
#CELL
  pure_quanta q_cap *
  page267_i44
#CELL
  pure_quanta q_res *
  page267_i45
#ISCELL
  logical_power universal_power *
  page267_i46
#ISCELL
  logical_power universal_gnd *
  page267_i47
#ISCELL
  logical_power universal_gnd *
  page267_i48
#CELL
  pure_quanta q_capp *
  page267_i49
#CELL
  pure_quanta q_res *
  page267_i5
#ISCELL
  logical_power universal_power *
  page267_i50
#ISCELL
  logical_power universal_power *
  page267_i6
#CELL
  pure_quanta q_cap *
  page267_i7
#ISCELL
  logical_power universal_gnd *
  page267_i8
#CELL
  pure_quanta q_res *
  page267_i9
#ISCELL
  mstr_misc dns *
  *
#ISCELL
  pure_quanta quanta_title_block_c *
  *
#ISCELL
  logical_power universal_gnd *
  page268_i1
#CELL
  pure_quanta q_res *
  page268_i10
#CELL
  pure_quanta q_res *
  page268_i11
#ISCELL
  logical_power universal_gnd *
  page268_i12
#CELL
  pure_quanta q_cap *
  page268_i13
#ISCELL
  logical_power vccaux15 *
  page268_i14
#CELL
  pure_quanta q_cap *
  page268_i15
#ISCELL
  logical_power vccaux15 *
  page268_i16
#ISCELL
  logical_power universal_gnd *
  page268_i17
#ISCELL
  logical_power universal_gnd *
  page268_i18
#CELL
  pure_quanta q_res *
  page268_i19
#ISCELL
  standard offpage *
  page268_i2
#ISCELL
  logical_power universal_gnd *
  page268_i20
#CELL
  pure_quanta q_res *
  page268_i21
#CELL
  pure_quanta rs53317lr *
  page268_i22
#CELL
  pure_quanta q_cap *
  page268_i23
#ISCELL
  logical_power universal_gnd *
  page268_i24
#CELL
  pure_quanta q_cap *
  page268_i25
#CELL
  pure_quanta q_cap *
  page268_i26
#CELL
  pure_quanta q_res *
  page268_i27
#CELL
  pure_quanta q_res *
  page268_i28
#CELL
  pure_quanta q_inductor *
  page268_i29
#ISCELL
  logical_power vccaux15 *
  page268_i3
#ISCELL
  logical_power universal_gnd *
  page268_i30
#CELL
  pure_quanta q_cap *
  page268_i31
#CELL
  pure_quanta q_res *
  page268_i32
#CELL
  pure_quanta q_res *
  page268_i33
#ISCELL
  logical_power vccaux15 *
  page268_i34
#CELL
  pure_quanta q_cap *
  page268_i35
#CELL
  pure_quanta q_res *
  page268_i36
#CELL
  pure_quanta q_cap *
  page268_i37
#CELL
  pure_quanta q_cap *
  page268_i38
#CELL
  pure_quanta q_cap *
  page268_i39
#CELL
  pure_quanta q_cap *
  page268_i4
#CELL
  pure_quanta q_res *
  page268_i40
#CELL
  pure_quanta q_res *
  page268_i41
#CELL
  pure_quanta q_cap *
  page268_i42
#CELL
  pure_quanta q_cap *
  page268_i43
#ISCELL
  standard offpage *
  page268_i44
#ISCELL
  logical_power universal_gnd *
  page268_i45
#ISCELL
  logical_power vccaux15 *
  page268_i46
#CELL
  pure_quanta q_cap *
  page268_i47
#ISCELL
  logical_power vccaux15 *
  page268_i48
#CELL
  pure_quanta q_res *
  page268_i5
#ISCELL
  logical_power universal_gnd *
  page268_i6
#CELL
  pure_quanta q_cap *
  page268_i7
#ISCELL
  logical_power universal_gnd *
  page268_i8
#CELL
  pure_quanta q_res *
  page268_i9
#ISCELL
  pure_quanta quanta_title_block_c *
  *
#ISCELL
  mstr_misc dns *
  *
#ISCELL
  pure_quanta quanta_title_block_c *
  *
#ISCELL
  standard offpage *
  page270_i1
#ISCELL
  standard offpage *
  page270_i10
#CELL
  pure_quanta q_res *
  page270_i100
#CELL
  pure_quanta q_res *
  page270_i101
#ISCELL
  logical_power universal_gnd *
  page270_i102
#CELL
  pure_quanta q_cap *
  page270_i103
#CELL
  pure_quanta q_cap *
  page270_i104
#ISCELL
  logical_power vcc15 *
  page270_i105
#ISCELL
  standard offpage *
  page270_i106
#ISCELL
  standard offpage *
  page270_i107
#ISCELL
  standard offpage *
  page270_i108
#ISCELL
  standard offpage *
  page270_i109
#ISCELL
  standard offpage *
  page270_i11
#ISCELL
  standard offpage *
  page270_i110
#ISCELL
  standard offpage *
  page270_i111
#ISCELL
  standard offpage *
  page270_i112
#ISCELL
  standard offpage *
  page270_i113
#ISCELL
  standard offpage *
  page270_i114
#ISCELL
  standard offpage *
  page270_i115
#ISCELL
  standard offpage *
  page270_i116
#ISCELL
  standard offpage *
  page270_i117
#ISCELL
  standard offpage *
  page270_i118
#CELL
  pure_quanta q_cap *
  page270_i119
#CELL
  pure_quanta q_res *
  page270_i12
#CELL
  pure_quanta q_cap *
  page270_i120
#CELL
  pure_quanta q_cap *
  page270_i121
#CELL
  pure_quanta q_cap *
  page270_i122
#ISCELL
  logical_power universal_gnd *
  page270_i123
#ISCELL
  standard offpage *
  page270_i124
#ISCELL
  logical_power universal_gnd *
  page270_i125
#CELL
  pure_quanta q_res *
  page270_i126
#ISCELL
  logical_power vcc15 *
  page270_i127
#CELL
  pure_quanta q_cap *
  page270_i128
#ISCELL
  logical_power vcc15 *
  page270_i13
#ISCELL
  logical_power vcc15 *
  page270_i14
#CELL
  pure_quanta q_res *
  page270_i15
#CELL
  pure_quanta q_res *
  page270_i16
#CELL
  pure_quanta q_res *
  page270_i17
#CELL
  pure_quanta q_res *
  page270_i18
#CELL
  pure_quanta q_res *
  page270_i19
#ISCELL
  standard offpage *
  page270_i2
#ISCELL
  standard offpage *
  page270_i20
#ISCELL
  logical_power universal_gnd *
  page270_i21
#CELL
  pure_quanta q_short *
  page270_i22
#CELL
  pure_quanta q_res *
  page270_i23
#ISCELL
  logical_power vcc15 *
  page270_i24
#CELL
  pure_quanta q_res *
  page270_i25
#ISCELL
  logical_power universal_gnd *
  page270_i26
#CELL
  pure_quanta q_res *
  page270_i27
#CELL
  pure_quanta q_cap *
  page270_i28
#CELL
  pure_quanta q_res *
  page270_i29
#ISCELL
  standard offpage *
  page270_i3
#ISCELL
  logical_power universal_gnd *
  page270_i30
#CELL
  pure_quanta q_cap *
  page270_i31
#ISCELL
  logical_power universal_gnd *
  page270_i32
#CELL
  pure_quanta raa229126gnpha0 *
  page270_i33
#CELL
  pure_quanta q_cap *
  page270_i34
#CELL
  pure_quanta q_cap *
  page270_i35
#CELL
  pure_quanta q_res *
  page270_i36
#CELL
  pure_quanta q_res *
  page270_i37
#CELL
  pure_quanta q_cap *
  page270_i38
#ISCELL
  logical_power universal_gnd *
  page270_i39
#CELL
  pure_quanta q_res *
  page270_i4
#ISCELL
  logical_power universal_gnd *
  page270_i40
#ISCELL
  standard offpage *
  page270_i41
#ISCELL
  standard offpage *
  page270_i42
#ISCELL
  standard offpage *
  page270_i43
#ISCELL
  standard offpage *
  page270_i44
#CELL
  pure_quanta q_res *
  page270_i45
#CELL
  pure_quanta q_short *
  page270_i46
#ISCELL
  logical_power universal_gnd *
  page270_i47
#ISCELL
  logical_power vcc15 *
  page270_i48
#CELL
  pure_quanta q_res *
  page270_i49
#ISCELL
  logical_power universal_gnd *
  page270_i5
#ISCELL
  logical_power vcc15 *
  page270_i50
#ISCELL
  standard offpage *
  page270_i51
#ISCELL
  standard offpage *
  page270_i52
#ISCELL
  standard offpage *
  page270_i53
#ISCELL
  standard offpage *
  page270_i54
#ISCELL
  standard offpage *
  page270_i55
#CELL
  pure_quanta q_res *
  page270_i56
#CELL
  pure_quanta q_res *
  page270_i57
#CELL
  pure_quanta q_res *
  page270_i58
#CELL
  pure_quanta q_res *
  page270_i59
#CELL
  pure_quanta q_res *
  page270_i6
#CELL
  pure_quanta q_res *
  page270_i60
#CELL
  pure_quanta q_res *
  page270_i61
#ISCELL
  logical_power vcc15 *
  page270_i62
#CELL
  pure_quanta q_res *
  page270_i63
#CELL
  pure_quanta q_cap *
  page270_i64
#CELL
  pure_quanta q_res *
  page270_i65
#CELL
  pure_quanta q_res *
  page270_i66
#CELL
  pure_quanta q_cap *
  page270_i67
#CELL
  pure_quanta q_cap *
  page270_i68
#ISCELL
  logical_power universal_gnd *
  page270_i69
#CELL
  pure_quanta q_res *
  page270_i7
#ISCELL
  logical_power universal_gnd *
  page270_i70
#ISCELL
  logical_power universal_gnd *
  page270_i71
#CELL
  pure_quanta q_cap *
  page270_i72
#ISCELL
  logical_power universal_gnd *
  page270_i73
#CELL
  pure_quanta q_res *
  page270_i74
#ISCELL
  standard offpage *
  page270_i75
#ISCELL
  standard offpage *
  page270_i76
#ISCELL
  logical_power universal_gnd *
  page270_i77
#ISCELL
  standard offpage *
  page270_i78
#ISCELL
  standard offpage *
  page270_i79
#ISCELL
  logical_power vcc15 *
  page270_i8
#CELL
  pure_quanta q_res *
  page270_i80
#CELL
  pure_quanta q_res *
  page270_i81
#ISCELL
  logical_power universal_gnd *
  page270_i82
#ISCELL
  standard offpage *
  page270_i83
#ISCELL
  standard offpage *
  page270_i84
#ISCELL
  standard offpage *
  page270_i85
#ISCELL
  standard offpage *
  page270_i86
#ISCELL
  standard offpage *
  page270_i87
#ISCELL
  standard offpage *
  page270_i88
#ISCELL
  standard offpage *
  page270_i89
#CELL
  pure_quanta q_res *
  page270_i9
#ISCELL
  standard offpage *
  page270_i90
#ISCELL
  logical_power universal_gnd *
  page270_i91
#CELL
  pure_quanta q_cap *
  page270_i92
#ISCELL
  logical_power universal_gnd *
  page270_i93
#CELL
  pure_quanta q_res *
  page270_i94
#ISCELL
  standard offpage *
  page270_i95
#ISCELL
  standard offpage *
  page270_i96
#ISCELL
  standard offpage *
  page270_i97
#ISCELL
  standard offpage *
  page270_i98
#CELL
  pure_quanta q_res *
  page270_i99
#ISCELL
  mstr_misc dns *
  *
#ISCELL
  pure_quanta quanta_title_block_c *
  *
#ISCELL
  logical_power universal_gnd *
  page271_i1
#ISCELL
  logical_power universal_gnd *
  page271_i10
#CELL
  pure_quanta q_cap *
  page271_i11
#ISCELL
  logical_power universal_gnd *
  page271_i12
#CELL
  pure_quanta q_res *
  page271_i13
#ISCELL
  logical_power vcc15 *
  page271_i14
#CELL
  pure_quanta q_cap *
  page271_i15
#ISCELL
  logical_power universal_gnd *
  page271_i16
#ISCELL
  standard offpage *
  page271_i17
#CELL
  pure_quanta q_inductor4p_14 *
  page271_i18
#CELL
  pure_quanta q_cap *
  page271_i19
#ISCELL
  logical_power universal_gnd *
  page271_i2
#CELL
  pure_quanta q_res *
  page271_i20
#CELL
  pure_quanta q_cap *
  page271_i21
#CELL
  pure_quanta q_cap *
  page271_i22
#CELL
  pure_quanta q_cap *
  page271_i23
#CELL
  pure_quanta q_cap *
  page271_i24
#ISCELL
  logical_power universal_gnd *
  page271_i25
#CELL
  pure_quanta q_res *
  page271_i26
#ISCELL
  logical_power vcc15 *
  page271_i27
#ISCELL
  logical_power universal_gnd *
  page271_i28
#CELL
  pure_quanta q_res *
  page271_i29
#CELL
  pure_quanta q_res *
  page271_i3
#ISCELL
  standard offpage *
  page271_i30
#ISCELL
  standard offpage *
  page271_i31
#ISCELL
  standard offpage *
  page271_i32
#ISCELL
  standard offpage *
  page271_i33
#CELL
  pure_quanta q_cap *
  page271_i34
#ISCELL
  logical_power universal_gnd *
  page271_i35
#CELL
  pure_quanta q_cap *
  page271_i36
#CELL
  pure_quanta q_res *
  page271_i37
#ISCELL
  logical_power universal_gnd *
  page271_i38
#CELL
  pure_quanta q_cap *
  page271_i39
#ISCELL
  standard offpage *
  page271_i4
#CELL
  pure_quanta isl99390frztr5935 *
  page271_i40
#CELL
  pure_quanta q_res *
  page271_i41
#ISCELL
  logical_power vcc15 *
  page271_i42
#ISCELL
  logical_power universal_gnd *
  page271_i43
#CELL
  pure_quanta q_cap *
  page271_i44
#ISCELL
  standard offpage *
  page271_i45
#CELL
  pure_quanta q_res *
  page271_i46
#CELL
  pure_quanta q_cap *
  page271_i47
#CELL
  pure_quanta q_cap *
  page271_i48
#CELL
  pure_quanta q_cap *
  page271_i49
#ISCELL
  standard offpage *
  page271_i5
#CELL
  pure_quanta q_cap *
  page271_i50
#CELL
  pure_quanta q_res *
  page271_i51
#ISCELL
  standard offpage *
  page271_i52
#CELL
  pure_quanta q_cap *
  page271_i53
#ISCELL
  logical_power universal_gnd *
  page271_i54
#ISCELL
  logical_power vcc15 *
  page271_i55
#CELL
  pure_quanta q_capp *
  page271_i56
#CELL
  pure_quanta q_cap *
  page271_i57
#CELL
  pure_quanta q_cap *
  page271_i58
#CELL
  pure_quanta q_res *
  page271_i59
#CELL
  pure_quanta q_cap *
  page271_i6
#ISCELL
  logical_power universal_gnd *
  page271_i60
#CELL
  pure_quanta q_capp *
  page271_i61
#CELL
  pure_quanta q_capp *
  page271_i62
#CELL
  pure_quanta q_capp *
  page271_i63
#CELL
  pure_quanta q_capp *
  page271_i64
#CELL
  pure_quanta q_capp *
  page271_i65
#ISCELL
  logical_power vcc15 *
  page271_i66
#ISCELL
  logical_power universal_gnd *
  page271_i67
#CELL
  pure_quanta q_capp *
  page271_i68
#CELL
  pure_quanta q_capp *
  page271_i69
#CELL
  pure_quanta isl99390frztr5935 *
  page271_i7
#ISCELL
  logical_power vcc15 *
  page271_i70
#ISCELL
  logical_power universal_gnd *
  page271_i71
#CELL
  pure_quanta q_capp *
  page271_i72
#CELL
  pure_quanta q_res *
  page271_i73
#CELL
  pure_quanta q_inductor4p_14 *
  page271_i74
#ISCELL
  logical_power universal_gnd *
  page271_i75
#CELL
  pure_quanta q_cap *
  page271_i76
#ISCELL
  standard offpage *
  page271_i77
#ISCELL
  logical_power gnd *
  page271_i78
#CELL
  pure_quanta q_cap *
  page271_i79
#ISCELL
  standard offpage *
  page271_i8
#ISCELL
  logical_power vcc15 *
  page271_i80
#ISCELL
  logical_power vcc15 *
  page271_i81
#CELL
  pure_quanta q_res *
  page271_i82
#CELL
  pure_quanta q_inductor *
  page271_i83
#CELL
  pure_quanta q_cap *
  page271_i84
#CELL
  pure_quanta q_cap *
  page271_i85
#CELL
  pure_quanta q_capp *
  page271_i86
#CELL
  pure_quanta q_capp *
  page271_i87
#CELL
  pure_quanta q_cap *
  page271_i88
#ISCELL
  logical_power vcc15 *
  page271_i89
#ISCELL
  standard offpage *
  page271_i9
#ISCELL
  logical_power universal_gnd *
  page271_i90
#CELL
  pure_quanta q_cap *
  page271_i91
#CELL
  pure_quanta q_capp *
  page271_i92
#ISCELL
  logical_power vcc15 *
  page271_i93
#CELL
  pure_quanta q_capp *
  page271_i94
#ISCELL
  logical_power universal_gnd *
  page271_i95
#CELL
  pure_quanta q_capp *
  page271_i96
#ISCELL
  logical_power vcc15 *
  page271_i97
#ISCELL
  mstr_misc dns *
  *
#ISCELL
  pure_quanta quanta_title_block_c *
  *
#ISCELL
  logical_power universal_gnd *
  page272_i1
#CELL
  pure_quanta isl99390frztr5935 *
  page272_i10
#CELL
  pure_quanta q_cap *
  page272_i11
#CELL
  pure_quanta q_res *
  page272_i12
#ISCELL
  logical_power vcc15 *
  page272_i13
#ISCELL
  logical_power universal_gnd *
  page272_i14
#CELL
  pure_quanta q_res *
  page272_i15
#ISCELL
  standard offpage *
  page272_i16
#ISCELL
  standard offpage *
  page272_i17
#ISCELL
  logical_power universal_gnd *
  page272_i18
#CELL
  pure_quanta q_cap *
  page272_i19
#ISCELL
  logical_power universal_gnd *
  page272_i2
#ISCELL
  logical_power universal_gnd *
  page272_i20
#ISCELL
  standard offpage *
  page272_i21
#ISCELL
  standard offpage *
  page272_i22
#ISCELL
  logical_power universal_gnd *
  page272_i23
#CELL
  pure_quanta q_cap *
  page272_i24
#CELL
  pure_quanta q_res *
  page272_i25
#ISCELL
  logical_power vcc15 *
  page272_i26
#CELL
  pure_quanta q_cap *
  page272_i27
#ISCELL
  logical_power universal_gnd *
  page272_i28
#CELL
  pure_quanta q_cap *
  page272_i29
#CELL
  pure_quanta q_res *
  page272_i3
#ISCELL
  logical_power universal_gnd *
  page272_i30
#ISCELL
  standard offpage *
  page272_i31
#ISCELL
  logical_power universal_gnd *
  page272_i32
#CELL
  pure_quanta q_cap *
  page272_i33
#CELL
  pure_quanta q_res *
  page272_i34
#CELL
  pure_quanta q_cap *
  page272_i35
#CELL
  pure_quanta q_cap *
  page272_i36
#CELL
  pure_quanta q_inductor4p_14 *
  page272_i37
#CELL
  pure_quanta q_res *
  page272_i38
#CELL
  pure_quanta q_cap *
  page272_i39
#ISCELL
  standard offpage *
  page272_i4
#ISCELL
  standard offpage *
  page272_i40
#CELL
  pure_quanta q_cap *
  page272_i41
#CELL
  pure_quanta q_cap *
  page272_i42
#ISCELL
  logical_power universal_gnd *
  page272_i43
#ISCELL
  logical_power vcc15 *
  page272_i44
#CELL
  pure_quanta q_res *
  page272_i45
#CELL
  pure_quanta q_res *
  page272_i46
#ISCELL
  standard offpage *
  page272_i47
#CELL
  pure_quanta q_cap *
  page272_i48
#CELL
  pure_quanta q_cap *
  page272_i49
#ISCELL
  standard offpage *
  page272_i5
#CELL
  pure_quanta q_cap *
  page272_i50
#CELL
  pure_quanta q_inductor4p_14 *
  page272_i51
#CELL
  pure_quanta q_cap *
  page272_i52
#ISCELL
  logical_power universal_gnd *
  page272_i53
#CELL
  pure_quanta q_cap *
  page272_i54
#CELL
  pure_quanta q_cap *
  page272_i55
#ISCELL
  logical_power vcc15 *
  page272_i56
#ISCELL
  standard offpage *
  page272_i57
#CELL
  pure_quanta q_cap *
  page272_i58
#CELL
  pure_quanta q_cap *
  page272_i59
#CELL
  pure_quanta q_cap *
  page272_i6
#ISCELL
  logical_power universal_gnd *
  page272_i60
#ISCELL
  logical_power vcc15 *
  page272_i61
#ISCELL
  logical_power universal_gnd *
  page272_i62
#CELL
  pure_quanta q_cap *
  page272_i63
#CELL
  pure_quanta q_cap *
  page272_i64
#ISCELL
  logical_power vcc15 *
  page272_i65
#CELL
  pure_quanta isl99390frztr5935 *
  page272_i66
#ISCELL
  standard offpage *
  page272_i7
#ISCELL
  standard offpage *
  page272_i8
#ISCELL
  logical_power universal_gnd *
  page272_i9
#ISCELL
  mstr_misc dns *
  *
#ISCELL
  pure_quanta quanta_title_block_c *
  *
#ISCELL
  logical_power universal_gnd *
  page273_i1
#ISCELL
  standard offpage *
  page273_i10
#ISCELL
  standard offpage *
  page273_i11
#ISCELL
  standard offpage *
  page273_i12
#ISCELL
  standard offpage *
  page273_i13
#ISCELL
  standard offpage *
  page273_i14
#CELL
  pure_quanta q_cap *
  page273_i15
#CELL
  pure_quanta isl99390frztr5935 *
  page273_i16
#CELL
  pure_quanta q_cap *
  page273_i17
#ISCELL
  logical_power universal_gnd *
  page273_i18
#CELL
  pure_quanta q_res *
  page273_i19
#CELL
  pure_quanta q_res *
  page273_i2
#ISCELL
  logical_power universal_gnd *
  page273_i20
#CELL
  pure_quanta q_cap *
  page273_i21
#ISCELL
  logical_power vcc15 *
  page273_i22
#CELL
  pure_quanta isl99390frztr5935 *
  page273_i23
#ISCELL
  logical_power universal_gnd *
  page273_i24
#ISCELL
  standard offpage *
  page273_i25
#CELL
  pure_quanta q_cap *
  page273_i26
#CELL
  pure_quanta q_res *
  page273_i27
#CELL
  pure_quanta q_inductor4p_14 *
  page273_i28
#CELL
  pure_quanta q_cap *
  page273_i29
#ISCELL
  standard offpage *
  page273_i3
#CELL
  pure_quanta q_res *
  page273_i30
#CELL
  pure_quanta q_cap *
  page273_i31
#ISCELL
  logical_power universal_gnd *
  page273_i32
#CELL
  pure_quanta q_cap *
  page273_i33
#CELL
  pure_quanta q_cap *
  page273_i34
#CELL
  pure_quanta q_cap *
  page273_i35
#CELL
  pure_quanta q_cap *
  page273_i36
#CELL
  pure_quanta q_cap *
  page273_i37
#ISCELL
  logical_power universal_gnd *
  page273_i38
#CELL
  pure_quanta q_res *
  page273_i39
#ISCELL
  logical_power universal_gnd *
  page273_i4
#ISCELL
  logical_power universal_gnd *
  page273_i40
#CELL
  pure_quanta q_cap *
  page273_i41
#ISCELL
  logical_power vcc15 *
  page273_i42
#ISCELL
  standard offpage *
  page273_i43
#CELL
  pure_quanta q_res *
  page273_i44
#CELL
  pure_quanta q_cap *
  page273_i45
#CELL
  pure_quanta q_cap *
  page273_i46
#CELL
  pure_quanta q_cap *
  page273_i47
#CELL
  pure_quanta q_inductor4p_14 *
  page273_i48
#CELL
  pure_quanta q_res *
  page273_i49
#ISCELL
  standard offpage *
  page273_i5
#CELL
  pure_quanta q_cap *
  page273_i50
#CELL
  pure_quanta q_cap *
  page273_i51
#CELL
  pure_quanta q_cap *
  page273_i52
#ISCELL
  standard offpage *
  page273_i53
#CELL
  pure_quanta q_cap *
  page273_i54
#ISCELL
  logical_power universal_gnd *
  page273_i55
#ISCELL
  logical_power vcc15 *
  page273_i56
#CELL
  pure_quanta q_cap *
  page273_i57
#ISCELL
  logical_power universal_gnd *
  page273_i58
#ISCELL
  logical_power vcc15 *
  page273_i59
#ISCELL
  logical_power universal_gnd *
  page273_i6
#ISCELL
  logical_power universal_gnd *
  page273_i60
#ISCELL
  logical_power universal_gnd *
  page273_i61
#ISCELL
  standard offpage *
  page273_i62
#ISCELL
  logical_power vcc15 *
  page273_i63
#CELL
  pure_quanta q_cap *
  page273_i64
#CELL
  pure_quanta q_cap *
  page273_i65
#ISCELL
  logical_power vcc15 *
  page273_i66
#CELL
  pure_quanta q_res *
  page273_i7
#ISCELL
  standard offpage *
  page273_i8
#ISCELL
  logical_power universal_gnd *
  page273_i9
#ISCELL
  mstr_misc dns *
  *
#ISCELL
  pure_quanta quanta_title_block_c *
  *
#ISCELL
  logical_power universal_gnd *
  page274_i1
#ISCELL
  logical_power universal_gnd *
  page274_i10
#CELL
  pure_quanta isl99390frztr5935 *
  page274_i11
#CELL
  pure_quanta q_res *
  page274_i12
#ISCELL
  logical_power vcc15 *
  page274_i13
#ISCELL
  logical_power universal_gnd *
  page274_i14
#CELL
  pure_quanta q_res *
  page274_i15
#ISCELL
  standard offpage *
  page274_i16
#ISCELL
  standard offpage *
  page274_i17
#CELL
  pure_quanta q_cap *
  page274_i18
#ISCELL
  logical_power universal_gnd *
  page274_i19
#ISCELL
  standard offpage *
  page274_i2
#CELL
  pure_quanta isl99390frztr5935 *
  page274_i20
#ISCELL
  logical_power universal_gnd *
  page274_i21
#ISCELL
  logical_power universal_gnd *
  page274_i22
#CELL
  pure_quanta q_inductor *
  page274_i23
#CELL
  pure_quanta q_cap *
  page274_i24
#ISCELL
  logical_power universal_gnd *
  page274_i25
#CELL
  pure_quanta q_res *
  page274_i26
#CELL
  pure_quanta q_cap *
  page274_i27
#CELL
  pure_quanta q_cap *
  page274_i28
#ISCELL
  logical_power universal_gnd *
  page274_i29
#CELL
  pure_quanta q_res *
  page274_i3
#ISCELL
  standard offpage *
  page274_i30
#ISCELL
  standard offpage *
  page274_i31
#CELL
  pure_quanta q_cap *
  page274_i32
#ISCELL
  logical_power universal_gnd *
  page274_i33
#CELL
  pure_quanta q_cap *
  page274_i34
#ISCELL
  logical_power vcc15 *
  page274_i35
#ISCELL
  logical_power universal_gnd *
  page274_i36
#CELL
  pure_quanta q_cap *
  page274_i37
#ISCELL
  standard offpage *
  page274_i38
#CELL
  pure_quanta q_res *
  page274_i39
#ISCELL
  logical_power universal_gnd *
  page274_i4
#CELL
  pure_quanta q_cap *
  page274_i40
#CELL
  pure_quanta q_cap *
  page274_i41
#CELL
  pure_quanta q_cap *
  page274_i42
#CELL
  pure_quanta q_inductor4p_14 *
  page274_i43
#CELL
  pure_quanta q_res *
  page274_i44
#ISCELL
  standard offpage *
  page274_i45
#CELL
  pure_quanta q_cap *
  page274_i46
#CELL
  pure_quanta q_cap *
  page274_i47
#ISCELL
  logical_power universal_gnd *
  page274_i48
#ISCELL
  logical_power vcc15 *
  page274_i49
#ISCELL
  standard offpage *
  page274_i5
#CELL
  pure_quanta q_res *
  page274_i50
#ISCELL
  logical_power universal_gnd *
  page274_i51
#CELL
  pure_quanta q_cap *
  page274_i52
#CELL
  pure_quanta q_cap *
  page274_i53
#CELL
  pure_quanta q_cap *
  page274_i54
#ISCELL
  logical_power universal_gnd *
  page274_i55
#ISCELL
  logical_power vcc15 *
  page274_i56
#ISCELL
  logical_power universal_gnd *
  page274_i57
#CELL
  pure_quanta q_inductor4p_14 *
  page274_i58
#CELL
  pure_quanta q_cap *
  page274_i59
#ISCELL
  standard offpage *
  page274_i6
#ISCELL
  logical_power universal_gnd *
  page274_i60
#CELL
  pure_quanta q_cap *
  page274_i61
#CELL
  pure_quanta q_cap *
  page274_i62
#ISCELL
  logical_power vcc15 *
  page274_i63
#CELL
  pure_quanta q_cap *
  page274_i64
#CELL
  pure_quanta q_cap *
  page274_i65
#CELL
  pure_quanta q_cap *
  page274_i66
#ISCELL
  logical_power vcc15 *
  page274_i67
#CELL
  pure_quanta q_res *
  page274_i68
#CELL
  pure_quanta q_cap *
  page274_i69
#CELL
  pure_quanta q_cap *
  page274_i7
#ISCELL
  standard offpage *
  page274_i8
#CELL
  pure_quanta q_cap *
  page274_i9
#ISCELL
  mstr_misc dns *
  *
#ISCELL
  pure_quanta quanta_title_block_c *
  *
#ISCELL
  logical_power universal_gnd *
  page275_i1
#ISCELL
  logical_power universal_gnd *
  page275_i10
#CELL
  pure_quanta q_cap *
  page275_i11
#CELL
  pure_quanta q_res *
  page275_i12
#CELL
  pure_quanta q_res *
  page275_i13
#ISCELL
  logical_power vcc15 *
  page275_i14
#ISCELL
  logical_power universal_gnd *
  page275_i15
#CELL
  pure_quanta q_cap *
  page275_i16
#CELL
  pure_quanta q_res *
  page275_i17
#ISCELL
  logical_power vcc15 *
  page275_i18
#ISCELL
  logical_power universal_gnd *
  page275_i19
#CELL
  pure_quanta q_res *
  page275_i2
#CELL
  pure_quanta q_res *
  page275_i20
#ISCELL
  logical_power universal_gnd *
  page275_i21
#ISCELL
  standard offpage *
  page275_i22
#ISCELL
  standard offpage *
  page275_i23
#ISCELL
  standard offpage *
  page275_i24
#ISCELL
  standard offpage *
  page275_i25
#ISCELL
  logical_power universal_gnd *
  page275_i26
#CELL
  pure_quanta q_cap *
  page275_i27
#CELL
  pure_quanta q_res *
  page275_i28
#CELL
  pure_quanta q_cap *
  page275_i29
#ISCELL
  logical_power universal_gnd *
  page275_i3
#ISCELL
  logical_power universal_gnd *
  page275_i30
#CELL
  pure_quanta q_cap *
  page275_i31
#CELL
  pure_quanta q_res *
  page275_i32
#ISCELL
  logical_power vcc15 *
  page275_i33
#CELL
  pure_quanta q_res *
  page275_i34
#ISCELL
  logical_power vcc15 *
  page275_i35
#ISCELL
  logical_power universal_gnd *
  page275_i36
#CELL
  pure_quanta q_cap *
  page275_i37
#CELL
  pure_quanta q_res *
  page275_i38
#CELL
  pure_quanta q_cap *
  page275_i39
#ISCELL
  standard offpage *
  page275_i4
#CELL
  pure_quanta q_cap *
  page275_i40
#CELL
  pure_quanta q_res *
  page275_i41
#CELL
  pure_quanta q_cap *
  page275_i42
#CELL
  pure_quanta q_cap *
  page275_i43
#CELL
  pure_quanta q_inductor *
  page275_i44
#ISCELL
  logical_power universal_gnd *
  page275_i45
#CELL
  pure_quanta q_cap *
  page275_i46
#ISCELL
  logical_power vcc15 *
  page275_i47
#ISCELL
  logical_power universal_gnd *
  page275_i48
#CELL
  pure_quanta q_cap *
  page275_i49
#ISCELL
  standard offpage *
  page275_i5
#CELL
  pure_quanta q_res *
  page275_i50
#CELL
  pure_quanta q_cap *
  page275_i51
#CELL
  pure_quanta q_cap *
  page275_i52
#CELL
  pure_quanta q_res *
  page275_i53
#CELL
  pure_quanta q_cap *
  page275_i54
#CELL
  pure_quanta q_inductor *
  page275_i55
#CELL
  pure_quanta q_cap *
  page275_i56
#ISCELL
  logical_power universal_gnd *
  page275_i57
#CELL
  pure_quanta q_cap *
  page275_i58
#ISCELL
  logical_power vcc15 *
  page275_i59
#ISCELL
  standard offpage *
  page275_i6
#CELL
  pure_quanta q_cap *
  page275_i60
#CELL
  pure_quanta q_cap *
  page275_i61
#CELL
  pure_quanta q_cap *
  page275_i62
#CELL
  pure_quanta q_cap *
  page275_i63
#CELL
  pure_quanta q_res *
  page275_i64
#ISCELL
  logical_power universal_gnd *
  page275_i65
#CELL
  pure_quanta q_capp *
  page275_i66
#CELL
  pure_quanta q_capp *
  page275_i67
#CELL
  pure_quanta q_capp *
  page275_i68
#ISCELL
  logical_power vcc15 *
  page275_i69
#ISCELL
  standard offpage *
  page275_i7
#CELL
  pure_quanta q_capp *
  page275_i70
#ISCELL
  logical_power universal_gnd *
  page275_i71
#CELL
  pure_quanta q_capp *
  page275_i72
#ISCELL
  logical_power vcc15 *
  page275_i73
#CELL
  pure_quanta q_cap *
  page275_i74
#CELL
  pure_quanta q_cap *
  page275_i75
#ISCELL
  logical_power gnd *
  page275_i76
#CELL
  pure_quanta q_cap *
  page275_i77
#ISCELL
  logical_power vcc15 *
  page275_i78
#CELL
  pure_quanta q_inductor *
  page275_i79
#CELL
  pure_quanta q_cap *
  page275_i8
#CELL
  pure_quanta q_cap *
  page275_i80
#ISCELL
  logical_power universal_gnd *
  page275_i81
#ISCELL
  logical_power vcc15 *
  page275_i82
#CELL
  pure_quanta q_cap *
  page275_i83
#CELL
  pure_quanta q_cap *
  page275_i84
#CELL
  pure_quanta q_cap *
  page275_i85
#ISCELL
  logical_power universal_gnd *
  page275_i86
#CELL
  pure_quanta q_capp *
  page275_i87
#ISCELL
  logical_power vcc15 *
  page275_i88
#CELL
  pure_quanta isl99390frztr5935 *
  page275_i89
#CELL
  pure_quanta isl99390frztr5935 *
  page275_i9
#ISCELL
  mstr_misc dns *
  *
#ISCELL
  pure_quanta quanta_title_block_c *
  *
#ISCELL
  logical_power universal_gnd *
  page276_i1
#ISCELL
  standard offpage *
  page276_i10
#ISCELL
  logical_power universal_gnd *
  page276_i11
#CELL
  pure_quanta q_cap *
  page276_i12
#CELL
  pure_quanta q_cap *
  page276_i13
#ISCELL
  logical_power universal_gnd *
  page276_i14
#CELL
  pure_quanta isl99390frztr5935 *
  page276_i15
#ISCELL
  logical_power universal_gnd *
  page276_i16
#CELL
  pure_quanta q_res *
  page276_i17
#CELL
  pure_quanta q_res *
  page276_i18
#ISCELL
  logical_power vcc15 *
  page276_i19
#CELL
  pure_quanta q_res *
  page276_i2
#CELL
  pure_quanta q_cap *
  page276_i20
#ISCELL
  standard offpage *
  page276_i21
#ISCELL
  standard offpage *
  page276_i22
#CELL
  pure_quanta q_cap *
  page276_i23
#CELL
  pure_quanta isl99390frztr5935 *
  page276_i24
#ISCELL
  standard offpage *
  page276_i25
#ISCELL
  standard offpage *
  page276_i26
#CELL
  pure_quanta q_cap *
  page276_i27
#ISCELL
  logical_power universal_gnd *
  page276_i28
#CELL
  pure_quanta q_res *
  page276_i29
#ISCELL
  logical_power universal_gnd *
  page276_i3
#ISCELL
  logical_power universal_gnd *
  page276_i30
#CELL
  pure_quanta q_cap *
  page276_i31
#ISCELL
  logical_power vcc15 *
  page276_i32
#CELL
  pure_quanta q_cap *
  page276_i33
#ISCELL
  logical_power universal_gnd *
  page276_i34
#CELL
  pure_quanta q_cap *
  page276_i35
#CELL
  pure_quanta q_cap *
  page276_i36
#CELL
  pure_quanta q_cap *
  page276_i37
#CELL
  pure_quanta q_cap *
  page276_i38
#CELL
  pure_quanta q_cap *
  page276_i39
#ISCELL
  logical_power universal_gnd *
  page276_i4
#CELL
  pure_quanta q_res *
  page276_i40
#CELL
  pure_quanta q_cap *
  page276_i41
#CELL
  pure_quanta q_cap *
  page276_i42
#CELL
  pure_quanta q_res *
  page276_i43
#CELL
  pure_quanta q_inductor *
  page276_i44
#CELL
  pure_quanta q_cap *
  page276_i45
#ISCELL
  logical_power universal_gnd *
  page276_i46
#CELL
  pure_quanta q_cap *
  page276_i47
#CELL
  pure_quanta q_cap *
  page276_i48
#ISCELL
  logical_power universal_gnd *
  page276_i49
#CELL
  pure_quanta q_res *
  page276_i5
#CELL
  pure_quanta q_cap *
  page276_i50
#ISCELL
  logical_power vcc15 *
  page276_i51
#CELL
  pure_quanta q_cap *
  page276_i52
#ISCELL
  logical_power vcc15 *
  page276_i53
#CELL
  pure_quanta q_res *
  page276_i54
#CELL
  pure_quanta q_capp *
  page276_i55
#CELL
  pure_quanta q_cap *
  page276_i56
#CELL
  pure_quanta q_inductor *
  page276_i57
#CELL
  pure_quanta q_cap *
  page276_i58
#ISCELL
  logical_power universal_gnd *
  page276_i59
#ISCELL
  logical_power universal_gnd *
  page276_i6
#CELL
  pure_quanta q_cap *
  page276_i60
#ISCELL
  logical_power vcc15 *
  page276_i61
#CELL
  pure_quanta q_cap *
  page276_i62
#ISCELL
  logical_power gnd *
  page276_i63
#CELL
  pure_quanta q_inductor *
  page276_i64
#ISCELL
  logical_power vcc15 *
  page276_i65
#CELL
  pure_quanta q_cap *
  page276_i66
#CELL
  pure_quanta q_capp *
  page276_i67
#CELL
  pure_quanta q_cap *
  page276_i68
#ISCELL
  logical_power universal_gnd *
  page276_i69
#ISCELL
  standard offpage *
  page276_i7
#CELL
  pure_quanta q_capp *
  page276_i70
#ISCELL
  logical_power universal_gnd *
  page276_i71
#CELL
  pure_quanta q_capp *
  page276_i72
#CELL
  pure_quanta q_capp *
  page276_i73
#ISCELL
  logical_power vcc15 *
  page276_i74
#CELL
  pure_quanta q_cap *
  page276_i75
#ISCELL
  logical_power vcc15 *
  page276_i76
#CELL
  pure_quanta q_cap *
  page276_i77
#CELL
  pure_quanta q_cap *
  page276_i78
#ISCELL
  logical_power universal_gnd *
  page276_i79
#ISCELL
  standard offpage *
  page276_i8
#CELL
  pure_quanta q_cap *
  page276_i80
#CELL
  pure_quanta q_capp *
  page276_i81
#ISCELL
  logical_power vcc15 *
  page276_i82
#ISCELL
  standard offpage *
  page276_i9
#ISCELL
  pure_quanta quanta_title_block_c *
  *
#ISCELL
  mstr_misc dns *
  *
#ISCELL
  pure_quanta quanta_title_block_c *
  *
#ISCELL
  standard offpage *
  page278_i1
#ISCELL
  standard offpage *
  page278_i10
#ISCELL
  logical_power universal_gnd *
  page278_i100
#ISCELL
  standard offpage *
  page278_i101
#ISCELL
  logical_power vcc15 *
  page278_i102
#CELL
  pure_quanta q_res *
  page278_i103
#CELL
  pure_quanta q_res *
  page278_i104
#CELL
  pure_quanta q_res *
  page278_i105
#CELL
  pure_quanta q_cap *
  page278_i106
#ISCELL
  logical_power universal_gnd *
  page278_i107
#CELL
  pure_quanta q_res *
  page278_i108
#ISCELL
  logical_power vcc15 *
  page278_i109
#ISCELL
  standard offpage *
  page278_i11
#CELL
  pure_quanta q_res *
  page278_i110
#CELL
  pure_quanta q_cap *
  page278_i111
#ISCELL
  standard offpage *
  page278_i12
#ISCELL
  standard offpage *
  page278_i13
#CELL
  pure_quanta q_res *
  page278_i14
#CELL
  pure_quanta q_res *
  page278_i15
#ISCELL
  logical_power vcc15 *
  page278_i16
#ISCELL
  standard offpage *
  page278_i17
#ISCELL
  standard offpage *
  page278_i18
#ISCELL
  logical_power universal_gnd *
  page278_i19
#ISCELL
  standard offpage *
  page278_i2
#CELL
  pure_quanta q_res *
  page278_i21
#CELL
  pure_quanta q_res *
  page278_i22
#CELL
  pure_quanta q_res *
  page278_i23
#ISCELL
  logical_power vcc15 *
  page278_i24
#ISCELL
  logical_power vcc15 *
  page278_i25
#CELL
  pure_quanta q_res *
  page278_i26
#ISCELL
  logical_power universal_gnd *
  page278_i27
#CELL
  pure_quanta q_cap *
  page278_i28
#CELL
  pure_quanta q_res *
  page278_i29
#ISCELL
  standard offpage *
  page278_i3
#CELL
  pure_quanta q_res *
  page278_i30
#CELL
  pure_quanta q_res *
  page278_i31
#CELL
  pure_quanta q_cap *
  page278_i32
#CELL
  pure_quanta q_cap *
  page278_i33
#ISCELL
  logical_power universal_gnd *
  page278_i34
#CELL
  pure_quanta q_res *
  page278_i35
#CELL
  pure_quanta q_cap *
  page278_i36
#ISCELL
  logical_power universal_gnd *
  page278_i37
#CELL
  pure_quanta isl69260irazt *
  page278_i38
#ISCELL
  logical_power universal_gnd *
  page278_i39
#ISCELL
  standard offpage *
  page278_i4
#ISCELL
  logical_power universal_gnd *
  page278_i40
#CELL
  pure_quanta q_res *
  page278_i41
#ISCELL
  logical_power vcc15 *
  page278_i42
#ISCELL
  logical_power universal_gnd *
  page278_i43
#CELL
  pure_quanta q_short *
  page278_i44
#CELL
  pure_quanta q_res *
  page278_i45
#CELL
  pure_quanta q_res *
  page278_i46
#ISCELL
  logical_power vcc15 *
  page278_i47
#ISCELL
  logical_power universal_gnd *
  page278_i48
#CELL
  pure_quanta q_res *
  page278_i49
#ISCELL
  standard offpage *
  page278_i5
#CELL
  pure_quanta q_res *
  page278_i50
#CELL
  pure_quanta q_cap *
  page278_i51
#CELL
  pure_quanta q_res *
  page278_i52
#CELL
  pure_quanta q_cap *
  page278_i53
#CELL
  pure_quanta q_short *
  page278_i54
#CELL
  pure_quanta q_res *
  page278_i55
#ISCELL
  logical_power vcc15 *
  page278_i56
#CELL
  pure_quanta q_res *
  page278_i57
#CELL
  pure_quanta q_res *
  page278_i58
#CELL
  pure_quanta q_res *
  page278_i59
#ISCELL
  standard offpage *
  page278_i6
#CELL
  pure_quanta q_res *
  page278_i60
#CELL
  pure_quanta q_res *
  page278_i61
#CELL
  pure_quanta q_res *
  page278_i62
#CELL
  pure_quanta q_cap *
  page278_i63
#ISCELL
  logical_power universal_gnd *
  page278_i64
#ISCELL
  logical_power universal_gnd *
  page278_i65
#CELL
  pure_quanta q_cap *
  page278_i66
#CELL
  pure_quanta q_res *
  page278_i67
#ISCELL
  logical_power universal_gnd *
  page278_i68
#CELL
  pure_quanta q_cap *
  page278_i69
#ISCELL
  standard offpage *
  page278_i7
#CELL
  pure_quanta q_res *
  page278_i70
#ISCELL
  logical_power universal_gnd *
  page278_i71
#ISCELL
  standard offpage *
  page278_i72
#CELL
  pure_quanta q_res *
  page278_i73
#ISCELL
  logical_power universal_gnd *
  page278_i74
#CELL
  pure_quanta q_res *
  page278_i75
#ISCELL
  standard offpage *
  page278_i76
#ISCELL
  standard offpage *
  page278_i77
#CELL
  pure_quanta q_res *
  page278_i78
#CELL
  pure_quanta q_res *
  page278_i79
#ISCELL
  standard offpage *
  page278_i8
#CELL
  pure_quanta q_res *
  page278_i80
#CELL
  pure_quanta q_res *
  page278_i81
#ISCELL
  standard offpage *
  page278_i82
#ISCELL
  standard offpage *
  page278_i83
#ISCELL
  logical_power universal_gnd *
  page278_i84
#ISCELL
  logical_power vcc15 *
  page278_i85
#ISCELL
  logical_power universal_gnd *
  page278_i86
#ISCELL
  logical_power universal_gnd *
  page278_i87
#ISCELL
  logical_power universal_gnd *
  page278_i88
#CELL
  pure_quanta q_res *
  page278_i89
#ISCELL
  standard offpage *
  page278_i9
#ISCELL
  standard offpage *
  page278_i90
#ISCELL
  standard offpage *
  page278_i91
#CELL
  pure_quanta q_cap *
  page278_i92
#CELL
  pure_quanta q_cap *
  page278_i93
#ISCELL
  standard offpage *
  page278_i94
#ISCELL
  standard offpage *
  page278_i95
#CELL
  pure_quanta q_cap *
  page278_i96
#CELL
  pure_quanta q_cap *
  page278_i97
#ISCELL
  logical_power universal_gnd *
  page278_i98
#ISCELL
  logical_power universal_gnd *
  page278_i99
#ISCELL
  mstr_misc dns *
  *
#ISCELL
  pure_quanta quanta_title_block_c *
  *
#ISCELL
  logical_power universal_gnd *
  page279_i1
#CELL
  pure_quanta q_cap *
  page279_i10
#CELL
  pure_quanta q_res *
  page279_i11
#ISCELL
  logical_power universal_gnd *
  page279_i12
#CELL
  pure_quanta q_cap *
  page279_i13
#ISCELL
  logical_power vcc15 *
  page279_i14
#ISCELL
  logical_power universal_gnd *
  page279_i15
#CELL
  pure_quanta q_res *
  page279_i16
#ISCELL
  logical_power universal_gnd *
  page279_i17
#ISCELL
  standard offpage *
  page279_i18
#ISCELL
  standard offpage *
  page279_i19
#ISCELL
  logical_power universal_gnd *
  page279_i2
#CELL
  pure_quanta q_cap *
  page279_i20
#ISCELL
  standard offpage *
  page279_i21
#ISCELL
  standard offpage *
  page279_i22
#ISCELL
  logical_power universal_gnd *
  page279_i23
#CELL
  pure_quanta q_cap *
  page279_i24
#CELL
  pure_quanta q_res *
  page279_i25
#CELL
  pure_quanta q_cap *
  page279_i26
#ISCELL
  logical_power universal_gnd *
  page279_i27
#ISCELL
  logical_power vcc15 *
  page279_i28
#CELL
  pure_quanta isl99390frztr5935 *
  page279_i29
#CELL
  pure_quanta q_res *
  page279_i3
#ISCELL
  logical_power universal_gnd *
  page279_i30
#CELL
  pure_quanta q_res *
  page279_i31
#CELL
  pure_quanta q_cap *
  page279_i32
#CELL
  pure_quanta q_cap *
  page279_i33
#CELL
  pure_quanta q_res *
  page279_i34
#ISCELL
  logical_power universal_gnd *
  page279_i35
#CELL
  pure_quanta q_cap *
  page279_i36
#CELL
  pure_quanta q_cap *
  page279_i37
#CELL
  pure_quanta isl99390frztr5935 *
  page279_i38
#ISCELL
  logical_power universal_gnd *
  page279_i39
#ISCELL
  standard offpage *
  page279_i4
#CELL
  pure_quanta q_cap *
  page279_i40
#CELL
  pure_quanta q_cap *
  page279_i41
#CELL
  pure_quanta q_res *
  page279_i42
#CELL
  pure_quanta q_cap *
  page279_i43
#CELL
  pure_quanta q_cap *
  page279_i44
#CELL
  pure_quanta q_cap *
  page279_i45
#CELL
  pure_quanta q_inductor *
  page279_i46
#ISCELL
  logical_power universal_gnd *
  page279_i47
#ISCELL
  logical_power vcc15 *
  page279_i48
#CELL
  pure_quanta q_res *
  page279_i49
#ISCELL
  standard offpage *
  page279_i5
#CELL
  pure_quanta q_res *
  page279_i50
#CELL
  pure_quanta q_cap *
  page279_i51
#CELL
  pure_quanta q_cap *
  page279_i52
#CELL
  pure_quanta q_cap *
  page279_i53
#CELL
  pure_quanta q_inductor *
  page279_i54
#CELL
  pure_quanta q_cap *
  page279_i55
#ISCELL
  logical_power universal_gnd *
  page279_i56
#ISCELL
  logical_power vcc15 *
  page279_i57
#ISCELL
  logical_power vcc15 *
  page279_i58
#CELL
  pure_quanta q_capp *
  page279_i59
#CELL
  pure_quanta q_cap *
  page279_i6
#CELL
  pure_quanta q_capp *
  page279_i60
#CELL
  pure_quanta q_capp *
  page279_i61
#CELL
  pure_quanta q_capp *
  page279_i62
#CELL
  pure_quanta q_cap *
  page279_i63
#ISCELL
  logical_power universal_gnd *
  page279_i64
#CELL
  pure_quanta q_cap *
  page279_i65
#ISCELL
  logical_power vcc15 *
  page279_i66
#ISCELL
  logical_power gnd *
  page279_i67
#CELL
  pure_quanta q_cap *
  page279_i68
#CELL
  pure_quanta q_capp *
  page279_i69
#ISCELL
  standard offpage *
  page279_i7
#CELL
  pure_quanta q_capp *
  page279_i70
#CELL
  pure_quanta q_capp *
  page279_i71
#ISCELL
  logical_power universal_gnd *
  page279_i72
#ISCELL
  logical_power vcc15 *
  page279_i73
#ISCELL
  logical_power universal_gnd *
  page279_i74
#ISCELL
  logical_power vcc15 *
  page279_i75
#ISCELL
  logical_power universal_gnd *
  page279_i76
#ISCELL
  logical_power vcc15 *
  page279_i77
#CELL
  pure_quanta q_inductor *
  page279_i78
#ISCELL
  logical_power vcc15 *
  page279_i79
#ISCELL
  standard offpage *
  page279_i8
#ISCELL
  logical_power universal_gnd *
  page279_i9
#ISCELL
  mstr_misc dns *
  *
#ISCELL
  pure_quanta quanta_title_block_c *
  *
#CELL
  pure_quanta q_res *
  page280_i1
#ISCELL
  standard offpage *
  page280_i10
#CELL
  pure_quanta q_cap *
  page280_i11
#ISCELL
  logical_power universal_gnd *
  page280_i12
#CELL
  pure_quanta q_res *
  page280_i13
#CELL
  pure_quanta raa2213404gnphb0 *
  page280_i14
#CELL
  pure_quanta q_res *
  page280_i15
#CELL
  pure_quanta q_res *
  page280_i16
#ISCELL
  logical_power vcc15 *
  page280_i17
#CELL
  pure_quanta q_res *
  page280_i18
#ISCELL
  logical_power universal_gnd *
  page280_i19
#ISCELL
  logical_power universal_gnd *
  page280_i2
#CELL
  pure_quanta q_res *
  page280_i20
#ISCELL
  logical_power vcc15 *
  page280_i21
#CELL
  pure_quanta q_cap *
  page280_i22
#CELL
  pure_quanta q_inductor *
  page280_i23
#CELL
  pure_quanta q_cap *
  page280_i24
#CELL
  pure_quanta q_res *
  page280_i25
#CELL
  pure_quanta q_cap *
  page280_i26
#CELL
  pure_quanta q_cap *
  page280_i27
#CELL
  pure_quanta q_cap *
  page280_i28
#CELL
  pure_quanta q_cap *
  page280_i29
#ISCELL
  logical_power universal_gnd *
  page280_i3
#CELL
  pure_quanta q_cap *
  page280_i30
#CELL
  pure_quanta q_cap *
  page280_i31
#CELL
  pure_quanta q_capp *
  page280_i32
#CELL
  pure_quanta q_capp *
  page280_i33
#ISCELL
  logical_power universal_gnd *
  page280_i34
#ISCELL
  logical_power vcc15 *
  page280_i35
#ISCELL
  logical_power universal_gnd *
  page280_i36
#CELL
  pure_quanta q_res *
  page280_i37
#ISCELL
  logical_power vcc15 *
  page280_i38
#CELL
  pure_quanta q_res *
  page280_i4
#ISCELL
  logical_power vcc15 *
  page280_i5
#ISCELL
  standard offpage *
  page280_i6
#ISCELL
  standard offpage *
  page280_i7
#ISCELL
  standard offpage *
  page280_i8
#CELL
  pure_quanta q_cap *
  page280_i9
#ISCELL
  pure_quanta quanta_title_block_c *
  *
#ISCELL
  mstr_misc dns *
  *
#ISCELL
  pure_quanta quanta_title_block_c *
  *
#ISCELL
  standard offpage *
  page282_i1
#CELL
  pure_quanta q_res *
  page282_i10
#CELL
  pure_quanta q_res *
  page282_i11
#ISCELL
  logical_power universal_gnd *
  page282_i12
#CELL
  pure_quanta q_cap *
  page282_i13
#ISCELL
  standard offpage *
  page282_i14
#CELL
  pure_quanta q_res *
  page282_i15
#CELL
  pure_quanta q_short *
  page282_i16
#ISCELL
  logical_power universal_gnd *
  page282_i17
#CELL
  pure_quanta q_res *
  page282_i18
#ISCELL
  logical_power vcc15 *
  page282_i19
#ISCELL
  standard offpage *
  page282_i2
#CELL
  pure_quanta q_res *
  page282_i20
#CELL
  pure_quanta q_res *
  page282_i21
#CELL
  pure_quanta q_cap *
  page282_i22
#ISCELL
  logical_power universal_gnd *
  page282_i23
#CELL
  pure_quanta q_cap *
  page282_i24
#ISCELL
  logical_power vcc15 *
  page282_i25
#ISCELL
  standard offpage *
  page282_i26
#ISCELL
  standard offpage *
  page282_i27
#CELL
  pure_quanta q_cap *
  page282_i28
#CELL
  pure_quanta q_res *
  page282_i29
#ISCELL
  standard offpage *
  page282_i3
#ISCELL
  standard offpage *
  page282_i30
#ISCELL
  standard offpage *
  page282_i31
#ISCELL
  standard offpage *
  page282_i32
#CELL
  pure_quanta q_res *
  page282_i33
#ISCELL
  standard offpage *
  page282_i34
#ISCELL
  standard offpage *
  page282_i35
#CELL
  pure_quanta q_res *
  page282_i36
#ISCELL
  logical_power vcc15 *
  page282_i37
#CELL
  pure_quanta q_res *
  page282_i38
#CELL
  pure_quanta q_res *
  page282_i39
#ISCELL
  logical_power universal_gnd *
  page282_i4
#CELL
  pure_quanta q_res *
  page282_i40
#CELL
  pure_quanta q_res *
  page282_i41
#CELL
  pure_quanta q_res *
  page282_i42
#CELL
  pure_quanta q_res *
  page282_i43
#CELL
  pure_quanta q_res *
  page282_i44
#CELL
  pure_quanta q_cap *
  page282_i45
#CELL
  pure_quanta q_res *
  page282_i46
#ISCELL
  logical_power vcc15 *
  page282_i47
#CELL
  pure_quanta q_res *
  page282_i48
#ISCELL
  logical_power universal_gnd *
  page282_i49
#ISCELL
  standard offpage *
  page282_i5
#CELL
  pure_quanta q_cap *
  page282_i50
#CELL
  pure_quanta q_cap *
  page282_i51
#ISCELL
  logical_power universal_gnd *
  page282_i52
#CELL
  pure_quanta isl69260irazt *
  page282_i53
#ISCELL
  logical_power universal_gnd *
  page282_i54
#ISCELL
  logical_power universal_gnd *
  page282_i55
#ISCELL
  logical_power universal_gnd *
  page282_i56
#CELL
  pure_quanta q_cap *
  page282_i57
#CELL
  pure_quanta q_res *
  page282_i58
#CELL
  pure_quanta q_res *
  page282_i59
#ISCELL
  standard offpage *
  page282_i6
#CELL
  pure_quanta q_res *
  page282_i60
#CELL
  pure_quanta q_res *
  page282_i61
#CELL
  pure_quanta q_res *
  page282_i62
#CELL
  pure_quanta q_res *
  page282_i63
#CELL
  pure_quanta q_res *
  page282_i64
#CELL
  pure_quanta q_res *
  page282_i65
#CELL
  pure_quanta q_res *
  page282_i66
#ISCELL
  logical_power universal_gnd *
  page282_i67
#CELL
  pure_quanta q_cap *
  page282_i68
#CELL
  pure_quanta q_cap *
  page282_i69
#CELL
  pure_quanta q_res *
  page282_i70
#ISCELL
  standard offpage *
  page282_i71
#ISCELL
  standard offpage *
  page282_i72
#ISCELL
  logical_power universal_gnd *
  page282_i73
#CELL
  pure_quanta q_cap *
  page282_i74
#ISCELL
  logical_power universal_gnd *
  page282_i75
#ISCELL
  standard offpage *
  page282_i76
#CELL
  pure_quanta q_cap *
  page282_i77
#CELL
  pure_quanta q_res *
  page282_i78
#ISCELL
  logical_power vcc15 *
  page282_i79
#CELL
  pure_quanta q_res *
  page282_i8
#ISCELL
  logical_power universal_gnd *
  page282_i80
#CELL
  pure_quanta q_res *
  page282_i81
#ISCELL
  logical_power universal_gnd *
  page282_i82
#ISCELL
  standard offpage *
  page282_i83
#ISCELL
  logical_power universal_gnd *
  page282_i84
#CELL
  pure_quanta q_res *
  page282_i85
#ISCELL
  logical_power vcc15 *
  page282_i86
#ISCELL
  standard offpage *
  page282_i87
#ISCELL
  standard offpage *
  page282_i88
#ISCELL
  logical_power universal_gnd *
  page282_i89
#CELL
  pure_quanta q_res *
  page282_i9
#ISCELL
  logical_power universal_gnd *
  page282_i90
#ISCELL
  logical_power universal_gnd *
  page282_i91
#ISCELL
  logical_power universal_gnd *
  page282_i92
#ISCELL
  logical_power universal_gnd *
  page282_i93
#ISCELL
  logical_power universal_gnd *
  page282_i94
#CELL
  pure_quanta q_res *
  page282_i95
#CELL
  pure_quanta q_cap *
  page282_i96
#ISCELL
  mstr_misc dns *
  *
#ISCELL
  pure_quanta quanta_title_block_c *
  *
#ISCELL
  logical_power universal_gnd *
  page283_i1
#CELL
  pure_quanta isl99390frztr5935 *
  page283_i10
#ISCELL
  logical_power universal_gnd *
  page283_i11
#CELL
  pure_quanta q_res *
  page283_i12
#CELL
  pure_quanta q_cap *
  page283_i13
#CELL
  pure_quanta q_inductor *
  page283_i14
#CELL
  pure_quanta q_cap *
  page283_i15
#CELL
  pure_quanta q_res *
  page283_i16
#ISCELL
  logical_power vcc15 *
  page283_i17
#CELL
  pure_quanta q_cap *
  page283_i18
#ISCELL
  logical_power universal_gnd *
  page283_i19
#ISCELL
  logical_power universal_gnd *
  page283_i2
#CELL
  pure_quanta q_cap *
  page283_i20
#CELL
  pure_quanta q_res *
  page283_i21
#CELL
  pure_quanta q_cap *
  page283_i22
#CELL
  pure_quanta q_cap *
  page283_i23
#CELL
  pure_quanta q_cap *
  page283_i24
#CELL
  pure_quanta q_capp *
  page283_i25
#CELL
  pure_quanta q_capp *
  page283_i26
#CELL
  pure_quanta q_cap *
  page283_i27
#CELL
  pure_quanta q_cap *
  page283_i28
#CELL
  pure_quanta q_cap *
  page283_i29
#CELL
  pure_quanta q_res *
  page283_i3
#CELL
  pure_quanta q_cap *
  page283_i30
#ISCELL
  logical_power universal_gnd *
  page283_i31
#CELL
  pure_quanta q_capp *
  page283_i32
#ISCELL
  logical_power vcc15 *
  page283_i33
#ISCELL
  logical_power universal_gnd *
  page283_i34
#CELL
  pure_quanta q_res *
  page283_i35
#ISCELL
  logical_power vcc15 *
  page283_i36
#ISCELL
  logical_power universal_gnd *
  page283_i37
#ISCELL
  logical_power vcc15 *
  page283_i38
#ISCELL
  standard offpage *
  page283_i4
#ISCELL
  standard offpage *
  page283_i5
#ISCELL
  standard offpage *
  page283_i6
#ISCELL
  standard offpage *
  page283_i7
#CELL
  pure_quanta q_cap *
  page283_i8
#ISCELL
  logical_power universal_gnd *
  page283_i9
#ISCELL
  pure_quanta quanta_title_block_c *
  *
#ISCELL
  mstr_misc dns *
  *
#ISCELL
  pure_quanta quanta_title_block_c *
  *
#CELL
  pure_quanta q_cap *
  page285_i1
#CELL
  pure_quanta q_res *
  page285_i10
#CELL
  pure_quanta q_cap *
  page285_i11
#ISCELL
  logical_power universal_gnd *
  page285_i12
#CELL
  pure_quanta q_res *
  page285_i13
#CELL
  pure_quanta q_res *
  page285_i14
#CELL
  pure_quanta q_cap *
  page285_i15
#CELL
  pure_quanta q_cap *
  page285_i16
#CELL
  pure_quanta q_cap *
  page285_i17
#CELL
  pure_quanta q_res *
  page285_i18
#ISCELL
  logical_power universal_gnd *
  page285_i19
#ISCELL
  logical_power universal_gnd *
  page285_i2
#ISCELL
  logical_power vccaux15 *
  page285_i20
#ISCELL
  logical_power universal_gnd *
  page285_i21
#ISCELL
  logical_power universal_gnd *
  page285_i22
#CELL
  pure_quanta q_cap *
  page285_i23
#CELL
  pure_quanta q_cap *
  page285_i24
#CELL
  pure_quanta rs53318lr *
  page285_i25
#CELL
  pure_quanta q_cap *
  page285_i26
#CELL
  pure_quanta q_res *
  page285_i27
#CELL
  pure_quanta q_res *
  page285_i28
#CELL
  pure_quanta mosfet_n *
  page285_i29
#CELL
  pure_quanta q_res *
  page285_i3
#CELL
  pure_quanta q_res *
  page285_i30
#ISCELL
  standard offpage *
  page285_i31
#CELL
  pure_quanta q_cap *
  page285_i32
#CELL
  pure_quanta q_inductor *
  page285_i33
#CELL
  pure_quanta q_res *
  page285_i34
#CELL
  pure_quanta q_cap *
  page285_i35
#CELL
  pure_quanta q_cap *
  page285_i36
#CELL
  pure_quanta q_res *
  page285_i37
#ISCELL
  logical_power universal_gnd *
  page285_i38
#CELL
  pure_quanta q_cap *
  page285_i39
#ISCELL
  standard offpage *
  page285_i4
#CELL
  pure_quanta q_cap *
  page285_i40
#CELL
  pure_quanta q_cap *
  page285_i41
#ISCELL
  standard offpage *
  page285_i42
#ISCELL
  logical_power universal_power *
  page285_i43
#CELL
  pure_quanta q_short *
  page285_i44
#ISCELL
  logical_power universal_gnd *
  page285_i45
#CELL
  pure_quanta q_short *
  page285_i46
#CELL
  pure_quanta q_cap *
  page285_i47
#ISCELL
  logical_power universal_gnd *
  page285_i48
#CELL
  pure_quanta q_capp *
  page285_i49
#ISCELL
  logical_power universal_power *
  page285_i5
#ISCELL
  logical_power universal_power *
  page285_i50
#ISCELL
  logical_power vccaux15 *
  page285_i6
#ISCELL
  logical_power universal_gnd *
  page285_i7
#CELL
  pure_quanta q_cap *
  page285_i8
#ISCELL
  logical_power universal_gnd *
  page285_i9
#ISCELL
  mstr_misc dns *
  *
#ISCELL
  pure_quanta quanta_title_block_c *
  *
#ISCELL
  standard offpage *
  page286_i1
#CELL
  pure_quanta q_cap *
  page286_i10
#ISCELL
  logical_power universal_gnd *
  page286_i11
#CELL
  pure_quanta q_res *
  page286_i12
#CELL
  pure_quanta q_res *
  page286_i13
#CELL
  pure_quanta q_cap *
  page286_i14
#ISCELL
  logical_power universal_power *
  page286_i15
#CELL
  pure_quanta q_cap *
  page286_i16
#ISCELL
  logical_power universal_gnd *
  page286_i17
#ISCELL
  logical_power universal_gnd *
  page286_i18
#CELL
  pure_quanta q_res *
  page286_i19
#ISCELL
  logical_power vccaux15 *
  page286_i2
#CELL
  pure_quanta rs53317lr *
  page286_i20
#ISCELL
  logical_power universal_gnd *
  page286_i21
#CELL
  pure_quanta q_res *
  page286_i22
#CELL
  pure_quanta q_cap *
  page286_i23
#CELL
  pure_quanta q_cap *
  page286_i24
#CELL
  pure_quanta q_res *
  page286_i25
#CELL
  pure_quanta q_res *
  page286_i26
#CELL
  pure_quanta q_inductor *
  page286_i27
#CELL
  pure_quanta q_cap *
  page286_i28
#CELL
  pure_quanta q_res *
  page286_i29
#ISCELL
  logical_power universal_gnd *
  page286_i3
#ISCELL
  logical_power vccaux15 *
  page286_i30
#CELL
  pure_quanta q_res *
  page286_i31
#ISCELL
  logical_power universal_power *
  page286_i32
#CELL
  pure_quanta q_cap *
  page286_i33
#CELL
  pure_quanta q_res *
  page286_i34
#ISCELL
  logical_power universal_gnd *
  page286_i35
#CELL
  pure_quanta q_cap *
  page286_i36
#CELL
  pure_quanta q_cap *
  page286_i37
#CELL
  pure_quanta q_cap *
  page286_i38
#ISCELL
  standard offpage *
  page286_i39
#ISCELL
  logical_power universal_gnd *
  page286_i4
#CELL
  pure_quanta q_cap *
  page286_i40
#ISCELL
  logical_power universal_gnd *
  page286_i41
#CELL
  pure_quanta q_res *
  page286_i42
#CELL
  pure_quanta q_res *
  page286_i43
#CELL
  pure_quanta q_cap *
  page286_i44
#CELL
  pure_quanta q_cap *
  page286_i45
#ISCELL
  logical_power universal_gnd *
  page286_i46
#ISCELL
  logical_power universal_power *
  page286_i47
#ISCELL
  logical_power universal_power *
  page286_i48
#CELL
  pure_quanta q_res *
  page286_i5
#CELL
  pure_quanta q_cap *
  page286_i6
#CELL
  pure_quanta q_res *
  page286_i7
#ISCELL
  logical_power universal_gnd *
  page286_i8
#CELL
  pure_quanta q_cap *
  page286_i9
#ISCELL
  mstr_misc dns *
  *
#ISCELL
  pure_quanta quanta_title_block_c *
  *
#ISCELL
  logical_power universal_gnd *
  page303_i1
#CELL
  pure_quanta q_res *
  page303_i10
#ISCELL
  logical_power gnd *
  page303_i11
#CELL
  pure_quanta conn3_210hp1030br1 *
  page303_i12
#ISCELL
  standard offpage *
  page303_i13
#CELL
  pure_quanta q_cap *
  page303_i14
#ISCELL
  standard offpage *
  page303_i15
#CELL
  pure_quanta q_res *
  page303_i17
#ISCELL
  standard offpage *
  page303_i18
#ISCELL
  standard offpage *
  page303_i19
#ISCELL
  standard offpage *
  page303_i2
#ISCELL
  standard offpage *
  page303_i21
#ISCELL
  logical_power universal_gnd *
  page303_i22
#CELL
  pure_quanta q_cap *
  page303_i23
#CELL
  pure_quanta q_res *
  page303_i24
#CELL
  pure_quanta q_res *
  page303_i26
#ISCELL
  standard offpage *
  page303_i27
#ISCELL
  logical_power universal_gnd *
  page303_i28
#CELL
  pure_quanta q_cap *
  page303_i29
#CELL
  pure_quanta q_cap *
  page303_i3
#ISCELL
  standard offpage *
  page303_i30
#ISCELL
  logical_power universal_gnd *
  page303_i31
#CELL
  pure_quanta q_res *
  page303_i32
#CELL
  pure_quanta q_res *
  page303_i33
#ISCELL
  logical_power universal_power *
  page303_i34
#CELL
  pure_quanta q_cap *
  page303_i35
#ISCELL
  logical_power universal_power *
  page303_i36
#CELL
  pure_quanta q_res *
  page303_i37
#CELL
  pure_quanta q_res *
  page303_i38
#ISCELL
  logical_power universal_gnd *
  page303_i39
#CELL
  pure_quanta q_res *
  page303_i4
#CELL
  pure_quanta q_res *
  page303_i40
#CELL
  pure_quanta q_res *
  page303_i41
#CELL
  pure_quanta q_res *
  page303_i42
#CELL
  pure_quanta q_res *
  page303_i43
#CELL
  pure_quanta q_res *
  page303_i44
#CELL
  pure_quanta q_cap *
  page303_i45
#ISCELL
  logical_power universal_power *
  page303_i47
#CELL
  pure_quanta mosfet_nch_gds_esd_protected *
  page303_i5
#ISCELL
  logical_power universal_power *
  page303_i50
#CELL
  pure_quanta q_cap *
  page303_i51
#CELL
  pure_quanta q_res *
  page303_i52
#ISCELL
  logical_power gnd *
  page303_i53
#CELL
  pure_quanta q_res *
  page303_i54
#ISCELL
  logical_power universal_gnd *
  page303_i55
#CELL
  pure_quanta mp5990gma1111z *
  page303_i56
#ISCELL
  logical_power universal_gnd *
  page303_i57
#CELL
  pure_quanta q_res *
  page303_i58
#CELL
  pure_quanta q_res *
  page303_i59
#ISCELL
  logical_power gnd *
  page303_i6
#ISCELL
  logical_power universal_gnd *
  page303_i60
#CELL
  pure_quanta q_res *
  page303_i61
#CELL
  pure_quanta q_res *
  page303_i62
#ISCELL
  standard offpage *
  page303_i63
#ISCELL
  logical_power universal_gnd *
  page303_i64
#ISCELL
  standard offpage *
  page303_i65
#ISCELL
  standard offpage *
  page303_i66
#ISCELL
  standard offpage *
  page303_i67
#ISCELL
  logical_power universal_power *
  page303_i68
#CELL
  pure_quanta q_cap *
  page303_i69
#CELL
  pure_quanta q_res *
  page303_i7
#ISCELL
  standard offpage *
  page303_i70
#ISCELL
  logical_power universal_gnd *
  page303_i71
#ISCELL
  standard offpage *
  page303_i72
#ISCELL
  standard offpage *
  page303_i73
#ISCELL
  logical_power universal_gnd *
  page303_i74
#CELL
  pure_quanta q_cap *
  page303_i75
#CELL
  pure_quanta q_cap *
  page303_i77
#ISCELL
  logical_power universal_gnd *
  page303_i78
#CELL
  pure_quanta q_res *
  page303_i79
#ISCELL
  logical_power gnd *
  page303_i8
#ISCELL
  standard offpage *
  page303_i80
#CELL
  pure_quanta q_res *
  page303_i81
#CELL
  pure_quanta q_res *
  page303_i82
#CELL
  pure_quanta q_res *
  page303_i84
#CELL
  pure_quanta q_res *
  page303_i85
#CELL
  pure_quanta q_res *
  page303_i86
#ISCELL
  logical_power universal_power *
  page303_i87
#ISCELL
  logical_power universal_power *
  page303_i88
#CELL
  pure_quanta q_cap *
  page303_i89
#ISCELL
  logical_power universal_gnd *
  page303_i9
#ISCELL
  logical_power universal_gnd *
  page303_i90
#CELL
  pure_quanta q_res *
  page303_i91
#ISCELL
  standard offpage *
  page303_i92
#CELL
  pure_quanta q_res *
  page303_i93
#ISCELL
  logical_power universal_gnd *
  page303_i94
#ISCELL
  standard offpage *
  page303_i95
#ISCELL
  standard offpage *
  page303_i96
#ISCELL
  logical_power gnd *
  page303_i97
#ISCELL
  mstr_misc dns *
  *
#ISCELL
  pure_quanta quanta_title_block_c *
  *
#ISCELL
  logical_power universal_gnd *
  page301_i1
#ISCELL
  standard offpage *
  page301_i10
#CELL
  pure_quanta q_cap *
  page301_i11
#CELL
  pure_quanta q_res *
  page301_i12
#CELL
  pure_quanta q_res *
  page301_i13
#CELL
  pure_quanta mp5991gluz *
  page301_i14
#CELL
  pure_quanta q_res *
  page301_i15
#ISCELL
  standard offpage *
  page301_i16
#CELL
  pure_quanta q_res *
  page301_i17
#ISCELL
  logical_power universal_power *
  page301_i18
#ISCELL
  logical_power universal_gnd *
  page301_i19
#CELL
  pure_quanta q_cap *
  page301_i2
#CELL
  pure_quanta q_cap *
  page301_i20
#CELL
  pure_quanta q_res *
  page301_i21
#ISCELL
  logical_power universal_gnd *
  page301_i22
#CELL
  pure_quanta q_cap *
  page301_i23
#ISCELL
  standard offpage *
  page301_i24
#ISCELL
  logical_power universal_gnd *
  page301_i25
#ISCELL
  standard offpage *
  page301_i26
#ISCELL
  standard offpage *
  page301_i27
#ISCELL
  logical_power universal_power *
  page301_i28
#CELL
  pure_quanta q_cap *
  page301_i29
#ISCELL
  logical_power universal_gnd *
  page301_i3
#CELL
  pure_quanta q_res *
  page301_i30
#ISCELL
  standard offpage *
  page301_i31
#CELL
  pure_quanta q_res *
  page301_i32
#CELL
  pure_quanta q_res *
  page301_i33
#CELL
  pure_quanta q_res *
  page301_i34
#CELL
  pure_quanta mp5991gluz *
  page301_i35
#ISCELL
  logical_power universal_power *
  page301_i36
#CELL
  pure_quanta q_cap *
  page301_i37
#ISCELL
  logical_power universal_gnd *
  page301_i38
#CELL
  pure_quanta q_res *
  page301_i39
#CELL
  pure_quanta q_cap *
  page301_i4
#CELL
  pure_quanta q_res *
  page301_i40
#ISCELL
  logical_power universal_power *
  page301_i41
#ISCELL
  standard offpage *
  page301_i42
#ISCELL
  standard offpage *
  page301_i43
#ISCELL
  standard offpage *
  page301_i44
#ISCELL
  standard offpage *
  page301_i45
#ISCELL
  standard offpage *
  page301_i46
#CELL
  pure_quanta q_cap *
  page301_i47
#ISCELL
  logical_power universal_gnd *
  page301_i48
#CELL
  pure_quanta q_res *
  page301_i49
#CELL
  pure_quanta q_res *
  page301_i5
#CELL
  pure_quanta q_res *
  page301_i50
#ISCELL
  logical_power universal_power *
  page301_i51
#ISCELL
  standard offpage *
  page301_i52
#ISCELL
  standard offpage *
  page301_i53
#ISCELL
  standard offpage *
  page301_i54
#ISCELL
  standard offpage *
  page301_i55
#ISCELL
  standard offpage *
  page301_i56
#ISCELL
  logical_power universal_power *
  page301_i6
#ISCELL
  standard offpage *
  page301_i7
#ISCELL
  logical_power universal_gnd *
  page301_i8
#ISCELL
  standard offpage *
  page301_i9
#ISCELL
  mstr_misc dns *
  *
#ISCELL
  pure_quanta quanta_title_block_c *
  *
#ISCELL
  logical_power universal_gnd *
  page325_i1
#ISCELL
  standard offpage *
  page325_i10
#CELL
  pure_quanta q_cap *
  page325_i11
#CELL
  pure_quanta q_res *
  page325_i12
#CELL
  pure_quanta q_res *
  page325_i13
#CELL
  pure_quanta q_res *
  page325_i14
#ISCELL
  standard offpage *
  page325_i15
#CELL
  pure_quanta q_res *
  page325_i16
#CELL
  pure_quanta mp5991gluz *
  page325_i17
#ISCELL
  logical_power universal_power *
  page325_i18
#CELL
  pure_quanta q_cap *
  page325_i19
#CELL
  pure_quanta q_cap *
  page325_i2
#ISCELL
  logical_power universal_gnd *
  page325_i20
#CELL
  pure_quanta q_res *
  page325_i21
#ISCELL
  logical_power universal_gnd *
  page325_i22
#CELL
  pure_quanta q_cap *
  page325_i23
#ISCELL
  standard offpage *
  page325_i24
#ISCELL
  logical_power universal_gnd *
  page325_i25
#ISCELL
  standard offpage *
  page325_i26
#ISCELL
  standard offpage *
  page325_i27
#ISCELL
  logical_power universal_power *
  page325_i28
#CELL
  pure_quanta q_cap *
  page325_i29
#ISCELL
  logical_power universal_gnd *
  page325_i3
#CELL
  pure_quanta q_res *
  page325_i30
#ISCELL
  standard offpage *
  page325_i31
#CELL
  pure_quanta q_res *
  page325_i32
#CELL
  pure_quanta q_res *
  page325_i33
#CELL
  pure_quanta q_res *
  page325_i34
#CELL
  pure_quanta mp5991gluz *
  page325_i35
#ISCELL
  logical_power universal_power *
  page325_i36
#ISCELL
  logical_power universal_gnd *
  page325_i37
#CELL
  pure_quanta q_cap *
  page325_i38
#CELL
  pure_quanta q_res *
  page325_i39
#CELL
  pure_quanta q_cap *
  page325_i4
#CELL
  pure_quanta q_res *
  page325_i40
#ISCELL
  logical_power universal_power *
  page325_i41
#ISCELL
  standard offpage *
  page325_i42
#ISCELL
  standard offpage *
  page325_i43
#ISCELL
  standard offpage *
  page325_i44
#ISCELL
  standard offpage *
  page325_i45
#ISCELL
  standard offpage *
  page325_i46
#ISCELL
  logical_power universal_gnd *
  page325_i47
#CELL
  pure_quanta q_cap *
  page325_i48
#CELL
  pure_quanta q_res *
  page325_i49
#CELL
  pure_quanta q_res *
  page325_i5
#CELL
  pure_quanta q_res *
  page325_i50
#ISCELL
  logical_power universal_power *
  page325_i51
#ISCELL
  standard offpage *
  page325_i52
#ISCELL
  standard offpage *
  page325_i53
#ISCELL
  standard offpage *
  page325_i54
#ISCELL
  standard offpage *
  page325_i55
#ISCELL
  standard offpage *
  page325_i56
#ISCELL
  logical_power universal_power *
  page325_i6
#ISCELL
  standard offpage *
  page325_i7
#ISCELL
  logical_power universal_gnd *
  page325_i8
#ISCELL
  standard offpage *
  page325_i9
#ISCELL
  mstr_misc dns *
  *
#ISCELL
  pure_quanta quanta_title_block_c *
  *
#ISCELL
  standard offpage *
  page328_i100
#ISCELL
  standard offpage *
  page328_i101
#ISCELL
  standard offpage *
  page328_i102
#ISCELL
  standard offpage *
  page328_i103
#ISCELL
  standard offpage *
  page328_i104
#ISCELL
  standard offpage *
  page328_i105
#ISCELL
  standard offpage *
  page328_i106
#ISCELL
  standard offpage *
  page328_i107
#ISCELL
  standard offpage *
  page328_i108
#ISCELL
  standard offpage *
  page328_i109
#ISCELL
  standard offpage *
  page328_i110
#ISCELL
  standard offpage *
  page328_i111
#ISCELL
  standard offpage *
  page328_i112
#ISCELL
  standard offpage *
  page328_i113
#ISCELL
  standard offpage *
  page328_i114
#ISCELL
  standard offpage *
  page328_i115
#ISCELL
  standard offpage *
  page328_i116
#CELL
  pure_quanta q_res *
  page328_i117
#CELL
  pure_quanta q_res *
  page328_i118
#CELL
  pure_quanta q_res *
  page328_i119
#CELL
  pure_quanta q_res *
  page328_i120
#ISCELL
  standard offpage *
  page328_i121
#ISCELL
  standard offpage *
  page328_i122
#ISCELL
  standard offpage *
  page328_i123
#ISCELL
  standard offpage *
  page328_i124
#ISCELL
  standard offpage *
  page328_i125
#CELL
  pure_quanta q_res_4p_12 *
  page328_i126
#ISCELL
  standard offpage *
  page328_i15
#CELL
  pure_quanta q_res *
  page328_i16
#CELL
  pure_quanta mosfet_nch_1d3s *
  page328_i35
#CELL
  pure_quanta q_res *
  page328_i38
#CELL
  pure_quanta q_res *
  page328_i39
#CELL
  pure_quanta mosfet_nch_1d3s *
  page328_i40
#CELL
  pure_quanta mosfet_nch_1d3s *
  page328_i41
#ISCELL
  standard offpage *
  page328_i42
#ISCELL
  standard offpage *
  page328_i43
#ISCELL
  standard offpage *
  page328_i50
#CELL
  pure_quanta zener_ac *
  page328_i51
#ISCELL
  logical_power gnd *
  page328_i52
#CELL
  pure_quanta zener_ac *
  page328_i53
#CELL
  pure_quanta q_fuse *
  page328_i54
#ISCELL
  logical_power universal_power *
  page328_i55
#ISCELL
  standard offpage *
  page328_i56
#ISCELL
  standard offpage *
  page328_i57
#ISCELL
  standard offpage *
  page328_i58
#CELL
  pure_quanta q_res *
  page328_i59
#CELL
  pure_quanta q_res *
  page328_i60
#CELL
  pure_quanta q_res *
  page328_i61
#CELL
  pure_quanta mosfet_nch_1d3s *
  page328_i62
#CELL
  pure_quanta q_sp_res4p *
  page328_i63
#CELL
  pure_quanta q_sp_res4p *
  page328_i64
#CELL
  pure_quanta mosfet_nch_1d3s *
  page328_i65
#ISCELL
  standard offpage *
  page328_i66
#ISCELL
  standard offpage *
  page328_i67
#CELL
  pure_quanta q_cap *
  page328_i68
#CELL
  pure_quanta q_cap *
  page328_i69
#CELL
  pure_quanta q_res *
  page328_i70
#ISCELL
  logical_power gnd *
  page328_i71
#CELL
  pure_quanta ss15p3sm386a *
  page328_i72
#CELL
  pure_quanta mosfet_nch_1d3s *
  page328_i73
#ISCELL
  standard offpage *
  page328_i74
#ISCELL
  logical_power universal_power *
  page328_i75
#CELL
  pure_quanta q_res *
  page328_i76
#CELL
  pure_quanta mosfet_nch_1d3s *
  page328_i77
#CELL
  pure_quanta q_sp_res4p *
  page328_i78
#CELL
  pure_quanta q_sp_res4p *
  page328_i79
#ISCELL
  standard offpage *
  page328_i81
#ISCELL
  standard offpage *
  page328_i82
#ISCELL
  standard offpage *
  page328_i83
#ISCELL
  logical_power universal_power *
  page328_i84
#ISCELL
  logical_power universal_power *
  page328_i85
#CELL
  pure_quanta q_res *
  page328_i86
#CELL
  pure_quanta q_res *
  page328_i87
#CELL
  pure_quanta q_res *
  page328_i88
#CELL
  pure_quanta q_res *
  page328_i89
#CELL
  pure_quanta q_res *
  page328_i90
#CELL
  pure_quanta q_res *
  page328_i91
#CELL
  pure_quanta q_res *
  page328_i92
#CELL
  pure_quanta q_res *
  page328_i93
#CELL
  pure_quanta q_res *
  page328_i94
#CELL
  pure_quanta q_res *
  page328_i95
#CELL
  pure_quanta q_res *
  page328_i96
#CELL
  pure_quanta q_res *
  page328_i97
#CELL
  pure_quanta q_res *
  page328_i98
#CELL
  pure_quanta q_res *
  page328_i99
#ISCELL
  mstr_misc dns *
  *
#ISCELL
  pure_quanta quanta_title_block_c *
  *
#CELL
  pure_quanta nct7718w *
  page327_i10
#CELL
  pure_quanta q_res *
  page327_i11
#ISCELL
  logical_power universal_gnd *
  page327_i13
#CELL
  pure_quanta q_res *
  page327_i14
#CELL
  pure_quanta q_res *
  page327_i15
#CELL
  pure_quanta q_res *
  page327_i16
#CELL
  pure_quanta q_res *
  page327_i17
#ISCELL
  logical_power universal_power *
  page327_i18
#ISCELL
  standard offpage *
  page327_i19
#ISCELL
  standard offpage *
  page327_i2
#ISCELL
  standard offpage *
  page327_i20
#ISCELL
  standard offpage *
  page327_i21
#ISCELL
  standard offpage *
  page327_i22
#CELL
  pure_quanta q_res *
  page327_i23
#ISCELL
  logical_power universal_power *
  page327_i24
#CELL
  pure_quanta q_res *
  page327_i25
#CELL
  pure_quanta q_res *
  page327_i26
#ISCELL
  standard offpage *
  page327_i27
#ISCELL
  standard offpage *
  page327_i28
#ISCELL
  standard offpage *
  page327_i29
#ISCELL
  standard offpage *
  page327_i3
#ISCELL
  standard offpage *
  page327_i30
#ISCELL
  standard offpage *
  page327_i31
#ISCELL
  standard offpage *
  page327_i32
#ISCELL
  logical_power universal_gnd *
  page327_i33
#CELL
  pure_quanta sconn21_9193031121lf *
  page327_i34
#ISCELL
  logical_power universal_power *
  page327_i35
#ISCELL
  logical_power universal_gnd *
  page327_i36
#ISCELL
  logical_power universal_gnd *
  page327_i37
#CELL
  pure_quanta q_cap *
  page327_i38
#ISCELL
  standard offpage *
  page327_i39
#CELL
  pure_quanta q_res *
  page327_i4
#ISCELL
  standard offpage *
  page327_i40
#ISCELL
  standard offpage *
  page327_i41
#ISCELL
  standard offpage *
  page327_i42
#ISCELL
  standard offpage *
  page327_i43
#ISCELL
  standard offpage *
  page327_i44
#ISCELL
  standard offpage *
  page327_i45
#ISCELL
  logical_power universal_power *
  page327_i46
#ISCELL
  standard offpage *
  page327_i47
#ISCELL
  logical_power universal_power *
  page327_i48
#CELL
  pure_quanta mmbt3904 *
  page327_i49
#CELL
  pure_quanta q_res *
  page327_i5
#ISCELL
  logical_power gnd *
  page327_i50
#CELL
  pure_quanta conn3_210hp1030br1 *
  page327_i51
#CELL
  pure_quanta q_cap *
  page327_i6
#ISCELL
  logical_power universal_gnd *
  page327_i7
#CELL
  pure_quanta q_cap *
  page327_i8
#ISCELL
  logical_power universal_power *
  page327_i9
#ISCELL
  mstr_misc dns *
  *
#ISCELL
  pure_quanta quanta_title_block_c *
  *
#ISCELL
  logical_power universal_gnd *
  page326_i1
#CELL
  pure_quanta q_res *
  page326_i100
#CELL
  pure_quanta q_res *
  page326_i101
#CELL
  pure_quanta lt6700cs61trpbf *
  page326_i102
#ISCELL
  logical_power universal_power *
  page326_i12
#CELL
  pure_quanta q_res *
  page326_i13
#CELL
  pure_quanta q_res *
  page326_i14
#ISCELL
  logical_power universal_gnd *
  page326_i15
#CELL
  pure_quanta q_res *
  page326_i17
#ISCELL
  logical_power universal_gnd *
  page326_i18
#CELL
  pure_quanta q_res *
  page326_i2
#CELL
  pure_quanta q_res *
  page326_i20
#ISCELL
  logical_power universal_power *
  page326_i21
#ISCELL
  logical_power universal_gnd *
  page326_i23
#CELL
  pure_quanta q_res *
  page326_i24
#CELL
  pure_quanta q_res *
  page326_i25
#ISCELL
  logical_power universal_gnd *
  page326_i26
#CELL
  pure_quanta q_res *
  page326_i29
#ISCELL
  logical_power universal_gnd *
  page326_i3
#CELL
  pure_quanta tps3700ddcr *
  page326_i30
#ISCELL
  standard offpage *
  page326_i31
#CELL
  pure_quanta q_res *
  page326_i33
#ISCELL
  standard offpage *
  page326_i34
#ISCELL
  logical_power universal_gnd *
  page326_i35
#ISCELL
  standard offpage *
  page326_i36
#ISCELL
  logical_power universal_gnd *
  page326_i37
#CELL
  pure_quanta mosfet_n *
  page326_i38
#CELL
  pure_quanta q_res *
  page326_i39
#ISCELL
  logical_power universal_power *
  page326_i40
#CELL
  pure_quanta q_res *
  page326_i41
#ISCELL
  logical_power universal_gnd *
  page326_i42
#ISCELL
  logical_power universal_gnd *
  page326_i43
#CELL
  pure_quanta q_res *
  page326_i44
#CELL
  pure_quanta q_res *
  page326_i45
#CELL
  pure_quanta mosfet_nch_gds_esd_protected *
  page326_i46
#ISCELL
  logical_power universal_gnd *
  page326_i47
#CELL
  pure_quanta q_res *
  page326_i48
#ISCELL
  standard offpage *
  page326_i49
#CELL
  pure_quanta tps3700ddcr *
  page326_i5
#ISCELL
  standard offpage *
  page326_i50
#CELL
  pure_quanta q_res *
  page326_i51
#ISCELL
  logical_power universal_power *
  page326_i52
#CELL
  pure_quanta q_res *
  page326_i53
#ISCELL
  logical_power universal_power *
  page326_i54
#ISCELL
  logical_power universal_gnd *
  page326_i55
#CELL
  pure_quanta lm4040aim3x25nopb *
  page326_i56
#CELL
  pure_quanta q_res *
  page326_i57
#ISCELL
  logical_power universal_power *
  page326_i58
#ISCELL
  logical_power universal_gnd *
  page326_i59
#ISCELL
  logical_power universal_gnd *
  page326_i6
#ISCELL
  logical_power universal_gnd *
  page326_i63
#CELL
  pure_quanta q_cap *
  page326_i64
#ISCELL
  logical_power universal_gnd *
  page326_i65
#CELL
  pure_quanta ap331awg7 *
  page326_i66
#ISCELL
  logical_power universal_gnd *
  page326_i67
#CELL
  pure_quanta q_res *
  page326_i68
#ISCELL
  logical_power universal_power *
  page326_i69
#CELL
  pure_quanta q_res *
  page326_i7
#ISCELL
  logical_power universal_gnd *
  page326_i70
#CELL
  pure_quanta q_cap *
  page326_i71
#CELL
  pure_quanta q_res *
  page326_i72
#ISCELL
  standard offpage *
  page326_i73
#CELL
  pure_quanta q_cap *
  page326_i76
#CELL
  pure_quanta q_res *
  page326_i77
#CELL
  pure_quanta q_res *
  page326_i78
#ISCELL
  standard offpage *
  page326_i79
#ISCELL
  logical_power universal_power *
  page326_i8
#CELL
  pure_quanta q_res *
  page326_i80
#ISCELL
  logical_power universal_power *
  page326_i81
#ISCELL
  standard offpage *
  page326_i82
#ISCELL
  logical_power universal_power *
  page326_i84
#ISCELL
  logical_power universal_power *
  page326_i86
#ISCELL
  logical_power universal_power *
  page326_i87
#CELL
  pure_quanta q_cap *
  page326_i89
#ISCELL
  logical_power universal_gnd *
  page326_i9
#CELL
  pure_quanta q_cap *
  page326_i90
#CELL
  pure_quanta q_cap *
  page326_i91
#CELL
  pure_quanta q_cap *
  page326_i92
#CELL
  pure_quanta q_cap *
  page326_i93
#ISCELL
  logical_power universal_gnd *
  page326_i94
#CELL
  pure_quanta q_cap *
  page326_i95
#ISCELL
  logical_power universal_gnd *
  page326_i96
#CELL
  pure_quanta q_res *
  page326_i97
#CELL
  pure_quanta q_res *
  page326_i98
#CELL
  pure_quanta q_res *
  page326_i99
#ISCELL
  mstr_misc dns *
  *
#ISCELL
  pure_quanta quanta_title_block_c *
  *
#CELL
  pure_quanta q_cap *
  page329_i1
#ISCELL
  logical_power universal_gnd *
  page329_i10
#CELL
  pure_quanta q_cap *
  page329_i11
#CELL
  pure_quanta ap331awg7 *
  page329_i12
#ISCELL
  logical_power universal_gnd *
  page329_i13
#CELL
  pure_quanta q_cap *
  page329_i14
#ISCELL
  logical_power universal_gnd *
  page329_i15
#ISCELL
  logical_power universal_power *
  page329_i16
#CELL
  pure_quanta q_res *
  page329_i17
#ISCELL
  logical_power universal_gnd *
  page329_i18
#ISCELL
  logical_power universal_gnd *
  page329_i19
#CELL
  pure_quanta q_res *
  page329_i2
#ISCELL
  logical_power universal_power *
  page329_i20
#CELL
  pure_quanta q_res *
  page329_i21
#ISCELL
  logical_power universal_gnd *
  page329_i22
#CELL
  pure_quanta ap331awg7 *
  page329_i23
#ISCELL
  logical_power universal_power *
  page329_i24
#CELL
  pure_quanta q_res *
  page329_i25
#ISCELL
  standard offpage *
  page329_i26
#CELL
  pure_quanta q_res *
  page329_i27
#ISCELL
  logical_power universal_gnd *
  page329_i28
#CELL
  pure_quanta q_cap *
  page329_i29
#CELL
  pure_quanta lm4040aim3x25nopb *
  page329_i3
#ISCELL
  logical_power universal_power *
  page329_i30
#CELL
  pure_quanta q_res *
  page329_i31
#ISCELL
  logical_power universal_gnd *
  page329_i32
#CELL
  pure_quanta q_cap *
  page329_i33
#ISCELL
  logical_power universal_gnd *
  page329_i34
#CELL
  pure_quanta q_cap *
  page329_i35
#ISCELL
  logical_power universal_gnd *
  page329_i36
#ISCELL
  logical_power universal_power *
  page329_i37
#CELL
  pure_quanta q_res *
  page329_i38
#CELL
  pure_quanta q_res *
  page329_i39
#ISCELL
  logical_power universal_power *
  page329_i4
#ISCELL
  logical_power universal_gnd *
  page329_i40
#ISCELL
  logical_power universal_power *
  page329_i41
#CELL
  pure_quanta q_res *
  page329_i42
#CELL
  pure_quanta lm4040aim3x25nopb *
  page329_i43
#ISCELL
  logical_power universal_gnd *
  page329_i44
#CELL
  pure_quanta ap331awg7 *
  page329_i45
#CELL
  pure_quanta q_res *
  page329_i46
#ISCELL
  logical_power universal_power *
  page329_i47
#ISCELL
  standard offpage *
  page329_i48
#CELL
  pure_quanta q_res *
  page329_i49
#ISCELL
  standard offpage *
  page329_i5
#CELL
  pure_quanta q_res *
  page329_i50
#CELL
  pure_quanta q_cap *
  page329_i51
#ISCELL
  logical_power universal_power *
  page329_i52
#ISCELL
  logical_power universal_gnd *
  page329_i53
#ISCELL
  logical_power universal_gnd *
  page329_i54
#CELL
  pure_quanta q_cap *
  page329_i55
#ISCELL
  logical_power universal_gnd *
  page329_i56
#CELL
  pure_quanta q_cap *
  page329_i57
#ISCELL
  logical_power universal_gnd *
  page329_i58
#ISCELL
  logical_power universal_power *
  page329_i59
#CELL
  pure_quanta q_res *
  page329_i6
#ISCELL
  logical_power universal_gnd *
  page329_i62
#CELL
  pure_quanta lm4040aim3x25nopb *
  page329_i63
#ISCELL
  logical_power universal_power *
  page329_i64
#CELL
  pure_quanta q_res *
  page329_i65
#ISCELL
  logical_power universal_gnd *
  page329_i66
#CELL
  pure_quanta q_res *
  page329_i67
#CELL
  pure_quanta q_res *
  page329_i68
#CELL
  pure_quanta q_res *
  page329_i7
#ISCELL
  logical_power universal_power *
  page329_i8
#CELL
  pure_quanta q_res *
  page329_i9
#ISCELL
  pure_quanta quanta_title_block_c *
  *
#ISCELL
  logical_power universal_gnd *
  page287_i1
#ISCELL
  logical_power universal_gnd *
  page287_i10
#CELL
  pure_quanta picoprobe_bxa *
  page287_i11
#CELL
  pure_quanta picoprobe_bxa *
  page287_i12
#ISCELL
  logical_power universal_gnd *
  page287_i13
#CELL
  pure_quanta picoprobe_bxa *
  page287_i14
#ISCELL
  logical_power universal_gnd *
  page287_i15
#ISCELL
  logical_power universal_gnd *
  page287_i16
#CELL
  pure_quanta picoprobe_bxa *
  page287_i17
#CELL
  pure_quanta picoprobe_bxa *
  page287_i18
#CELL
  pure_quanta picoprobe_bxa *
  page287_i19
#ISCELL
  logical_power universal_gnd *
  page287_i2
#CELL
  pure_quanta picoprobe_bxa *
  page287_i20
#CELL
  pure_quanta picoprobe_bxa *
  page287_i21
#CELL
  pure_quanta picoprobe_bxa *
  page287_i22
#CELL
  pure_quanta picoprobe_bxa *
  page287_i23
#CELL
  pure_quanta picoprobe_bxa *
  page287_i24
#ISCELL
  logical_power universal_gnd *
  page287_i25
#ISCELL
  logical_power universal_gnd *
  page287_i26
#ISCELL
  logical_power universal_gnd *
  page287_i27
#CELL
  pure_quanta picoprobe_bxa *
  page287_i28
#ISCELL
  logical_power universal_gnd *
  page287_i29
#CELL
  pure_quanta picoprobe_bxa *
  page287_i3
#CELL
  pure_quanta picoprobe_bxa *
  page287_i30
#CELL
  pure_quanta picoprobe_bxa *
  page287_i31
#CELL
  pure_quanta picoprobe_bxa *
  page287_i32
#ISCELL
  logical_power universal_gnd *
  page287_i33
#ISCELL
  logical_power universal_gnd *
  page287_i34
#ISCELL
  logical_power universal_gnd *
  page287_i35
#ISCELL
  logical_power universal_gnd *
  page287_i36
#ISCELL
  logical_power universal_gnd *
  page287_i37
#ISCELL
  logical_power universal_gnd *
  page287_i38
#CELL
  pure_quanta picoprobe_bxa *
  page287_i39
#CELL
  pure_quanta picoprobe_bxa *
  page287_i4
#ISCELL
  logical_power universal_gnd *
  page287_i40
#ISCELL
  logical_power universal_gnd *
  page287_i41
#CELL
  pure_quanta picoprobe_bxa *
  page287_i42
#CELL
  pure_quanta picoprobe_bxa *
  page287_i43
#ISCELL
  logical_power universal_gnd *
  page287_i44
#ISCELL
  logical_power universal_gnd *
  page287_i45
#ISCELL
  logical_power universal_gnd *
  page287_i46
#ISCELL
  logical_power universal_gnd *
  page287_i47
#CELL
  pure_quanta picoprobe_bxa *
  page287_i48
#ISCELL
  logical_power universal_gnd *
  page287_i49
#CELL
  pure_quanta picoprobe_bxa *
  page287_i5
#ISCELL
  logical_power universal_gnd *
  page287_i50
#CELL
  pure_quanta picoprobe_bxa *
  page287_i51
#CELL
  pure_quanta picoprobe_bxa *
  page287_i52
#CELL
  pure_quanta picoprobe_bxa *
  page287_i53
#CELL
  pure_quanta picoprobe_bxa *
  page287_i54
#CELL
  pure_quanta picoprobe_bxa *
  page287_i55
#CELL
  pure_quanta picoprobe_bxa *
  page287_i56
#CELL
  pure_quanta picoprobe_bxa *
  page287_i57
#CELL
  pure_quanta picoprobe_bxa *
  page287_i58
#ISCELL
  logical_power universal_gnd *
  page287_i59
#CELL
  pure_quanta picoprobe_bxa *
  page287_i6
#ISCELL
  logical_power universal_gnd *
  page287_i60
#ISCELL
  logical_power universal_gnd *
  page287_i61
#ISCELL
  logical_power universal_gnd *
  page287_i62
#ISCELL
  logical_power universal_gnd *
  page287_i63
#ISCELL
  logical_power universal_gnd *
  page287_i64
#ISCELL
  logical_power universal_gnd *
  page287_i7
#CELL
  pure_quanta picoprobe_bxa *
  page287_i8
#ISCELL
  logical_power universal_gnd *
  page287_i9
#ISCELL
  pure_quanta quanta_title_block_c *
  *
#CELL
  pure_quanta tp_tdr_4p_fts *
  page288_i10
#ISCELL
  logical_power universal_gnd *
  page288_i100
#CELL
  pure_quanta tdr_3p *
  page288_i101
#ISCELL
  logical_power universal_gnd *
  page288_i102
#ISCELL
  logical_power universal_gnd *
  page288_i103
#ISCELL
  logical_power universal_gnd *
  page288_i104
#ISCELL
  logical_power universal_gnd *
  page288_i105
#CELL
  pure_quanta tp_tdr_4p_fts *
  page288_i106
#CELL
  pure_quanta tp_tdr_4p_fts *
  page288_i107
#CELL
  pure_quanta tp_tdr_4p_fts *
  page288_i108
#ISCELL
  logical_power universal_gnd *
  page288_i109
#CELL
  pure_quanta tp_tdr_4p_fts *
  page288_i11
#CELL
  pure_quanta tp_tdr_4p_fts *
  page288_i110
#ISCELL
  logical_power universal_gnd *
  page288_i111
#CELL
  pure_quanta tp_tdr_4p_fts *
  page288_i112
#ISCELL
  logical_power universal_gnd *
  page288_i113
#ISCELL
  logical_power universal_gnd *
  page288_i114
#CELL
  pure_quanta tp_tdr_4p_fts *
  page288_i115
#CELL
  pure_quanta tp_tdr_4p_fts *
  page288_i116
#CELL
  pure_quanta tp_tdr_4p_fts *
  page288_i117
#ISCELL
  logical_power universal_gnd *
  page288_i118
#ISCELL
  logical_power universal_gnd *
  page288_i119
#CELL
  pure_quanta tp_tdr_4p_fts *
  page288_i12
#ISCELL
  logical_power universal_gnd *
  page288_i13
#CELL
  pure_quanta tp_tdr_4p_fts *
  page288_i17
#CELL
  pure_quanta tp_tdr_4p_fts *
  page288_i18
#CELL
  pure_quanta tp_tdr_4p_fts *
  page288_i19
#CELL
  pure_quanta tp_tdr_4p_fts *
  page288_i26
#CELL
  pure_quanta tp_tdr_4p_fts *
  page288_i27
#CELL
  pure_quanta tp_tdr_4p_fts *
  page288_i28
#CELL
  pure_quanta tp_tdr_4p_fts *
  page288_i3
#CELL
  pure_quanta tp_tdr_4p_fts *
  page288_i30
#CELL
  pure_quanta tp_tdr_4p_fts *
  page288_i32
#CELL
  pure_quanta tp_tdr_4p_fts *
  page288_i33
#CELL
  pure_quanta tp_tdr_4p_fts *
  page288_i34
#CELL
  pure_quanta tp_tdr_4p_fts *
  page288_i35
#CELL
  pure_quanta tp_tdr_4p_fts *
  page288_i37
#CELL
  pure_quanta tp_tdr_4p_fts *
  page288_i39
#CELL
  pure_quanta tp_tdr_4p_fts *
  page288_i4
#CELL
  pure_quanta tp_tdr_4p_fts *
  page288_i42
#CELL
  pure_quanta tp_tdr_4p_fts *
  page288_i43
#CELL
  pure_quanta tp_tdr_4p_fts *
  page288_i46
#CELL
  pure_quanta tp_tdr_4p_fts *
  page288_i47
#CELL
  pure_quanta tdr_3p *
  page288_i49
#ISCELL
  logical_power universal_gnd *
  page288_i50
#CELL
  pure_quanta tdr_3p *
  page288_i51
#ISCELL
  logical_power universal_gnd *
  page288_i52
#CELL
  pure_quanta tdr_3p *
  page288_i53
#ISCELL
  logical_power universal_gnd *
  page288_i54
#CELL
  pure_quanta tdr_3p *
  page288_i55
#ISCELL
  logical_power universal_gnd *
  page288_i56
#CELL
  pure_quanta tdr_3p *
  page288_i57
#ISCELL
  logical_power universal_gnd *
  page288_i58
#ISCELL
  logical_power universal_gnd *
  page288_i59
#CELL
  pure_quanta tdr_3p *
  page288_i60
#CELL
  pure_quanta tdr_3p *
  page288_i61
#CELL
  pure_quanta tdr_3p *
  page288_i62
#CELL
  pure_quanta tdr_3p *
  page288_i63
#ISCELL
  logical_power universal_gnd *
  page288_i64
#ISCELL
  logical_power universal_gnd *
  page288_i65
#ISCELL
  logical_power universal_gnd *
  page288_i66
#CELL
  pure_quanta tdr_3p *
  page288_i67
#CELL
  pure_quanta tdr_3p *
  page288_i68
#CELL
  pure_quanta tdr_3p *
  page288_i69
#ISCELL
  logical_power universal_gnd *
  page288_i70
#ISCELL
  logical_power universal_gnd *
  page288_i71
#ISCELL
  logical_power universal_gnd *
  page288_i72
#ISCELL
  logical_power universal_gnd *
  page288_i73
#ISCELL
  logical_power universal_gnd *
  page288_i74
#ISCELL
  logical_power universal_gnd *
  page288_i75
#ISCELL
  logical_power universal_gnd *
  page288_i76
#ISCELL
  logical_power universal_gnd *
  page288_i77
#ISCELL
  logical_power universal_gnd *
  page288_i78
#ISCELL
  logical_power universal_gnd *
  page288_i79
#CELL
  pure_quanta tp_tdr_4p_fts *
  page288_i8
#ISCELL
  logical_power universal_gnd *
  page288_i80
#ISCELL
  logical_power universal_gnd *
  page288_i81
#ISCELL
  logical_power universal_gnd *
  page288_i82
#ISCELL
  logical_power universal_gnd *
  page288_i83
#ISCELL
  logical_power universal_gnd *
  page288_i84
#ISCELL
  logical_power universal_gnd *
  page288_i85
#ISCELL
  logical_power universal_gnd *
  page288_i86
#ISCELL
  logical_power universal_gnd *
  page288_i87
#ISCELL
  logical_power universal_gnd *
  page288_i88
#ISCELL
  logical_power universal_gnd *
  page288_i89
#CELL
  pure_quanta tp_tdr_4p_fts *
  page288_i9
#ISCELL
  logical_power universal_gnd *
  page288_i90
#ISCELL
  logical_power universal_gnd *
  page288_i91
#ISCELL
  logical_power universal_gnd *
  page288_i92
#ISCELL
  logical_power universal_gnd *
  page288_i93
#ISCELL
  logical_power universal_gnd *
  page288_i94
#ISCELL
  logical_power universal_gnd *
  page288_i95
#CELL
  pure_quanta tdr_3p *
  page288_i96
#CELL
  pure_quanta tdr_3p *
  page288_i97
#ISCELL
  logical_power universal_gnd *
  page288_i98
#CELL
  pure_quanta tdr_3p *
  page288_i99
#ISCELL
  pure_quanta quanta_title_block_c *
  *
#ISCELL
  logical_power universal_gnd *
  page310_i1
#CELL
  pure_quanta tp_tdr_4p_fts *
  page310_i10
#ISCELL
  logical_power universal_gnd *
  page310_i11
#ISCELL
  logical_power universal_gnd *
  page310_i12
#ISCELL
  logical_power universal_gnd *
  page310_i13
#ISCELL
  logical_power universal_gnd *
  page310_i14
#CELL
  pure_quanta tp_tdr_4p_fts *
  page310_i15
#CELL
  pure_quanta tp_tdr_4p_fts *
  page310_i16
#ISCELL
  logical_power universal_gnd *
  page310_i17
#ISCELL
  logical_power universal_gnd *
  page310_i18
#CELL
  pure_quanta tp_tdr_4p_fts *
  page310_i19
#ISCELL
  logical_power universal_gnd *
  page310_i2
#CELL
  pure_quanta tp_tdr_4p_fts *
  page310_i20
#CELL
  pure_quanta tp_tdr_4p_fts *
  page310_i21
#CELL
  pure_quanta tp_tdr_4p_fts *
  page310_i22
#ISCELL
  logical_power universal_gnd *
  page310_i23
#ISCELL
  logical_power universal_gnd *
  page310_i24
#ISCELL
  logical_power universal_gnd *
  page310_i3
#ISCELL
  logical_power universal_gnd *
  page310_i4
#CELL
  pure_quanta tp_tdr_4p_fts *
  page310_i5
#CELL
  pure_quanta tp_tdr_4p_fts *
  page310_i6
#CELL
  pure_quanta tp_tdr_4p_fts *
  page310_i7
#CELL
  pure_quanta tp_tdr_4p_fts *
  page310_i8
#CELL
  pure_quanta tp_tdr_4p_fts *
  page310_i9
#ISCELL
  pure_quanta quanta_title_block_c *
  *
#CELL
  pure_quanta hole *
  page289_i10
#ISCELL
  logical_power universal_gnd *
  page289_i100
#ISCELL
  logical_power universal_gnd *
  page289_i101
#CELL
  pure_quanta hole *
  page289_i11
#CELL
  pure_quanta hole *
  page289_i12
#CELL
  pure_quanta hole *
  page289_i140
#ISCELL
  logical_power universal_gnd *
  page289_i141
#CELL
  pure_quanta hole *
  page289_i144
#ISCELL
  logical_power universal_gnd *
  page289_i145
#ISCELL
  logical_power universal_gnd *
  page289_i146
#CELL
  pure_quanta hole *
  page289_i147
#CELL
  pure_quanta hole *
  page289_i148
#CELL
  pure_quanta hole *
  page289_i149
#CELL
  pure_quanta hole *
  page289_i150
#ISCELL
  logical_power universal_gnd *
  page289_i151
#ISCELL
  logical_power universal_gnd *
  page289_i152
#ISCELL
  logical_power universal_gnd *
  page289_i153
#CELL
  pure_quanta hole *
  page289_i154
#CELL
  pure_quanta hole *
  page289_i155
#ISCELL
  logical_power universal_gnd *
  page289_i156
#ISCELL
  logical_power universal_gnd *
  page289_i157
#CELL
  pure_quanta hole *
  page289_i158
#CELL
  pure_quanta hole *
  page289_i159
#CELL
  pure_quanta hole *
  page289_i160
#CELL
  pure_quanta hole *
  page289_i161
#ISCELL
  logical_power universal_gnd *
  page289_i162
#ISCELL
  logical_power universal_gnd *
  page289_i163
#ISCELL
  logical_power universal_gnd *
  page289_i164
#CELL
  pure_quanta hole *
  page289_i165
#CELL
  pure_quanta hole *
  page289_i166
#CELL
  pure_quanta hole *
  page289_i167
#CELL
  pure_quanta hole *
  page289_i168
#ISCELL
  logical_power universal_gnd *
  page289_i169
#ISCELL
  logical_power universal_gnd *
  page289_i170
#ISCELL
  logical_power universal_gnd *
  page289_i171
#ISCELL
  logical_power universal_gnd *
  page289_i172
#ISCELL
  logical_power universal_gnd *
  page289_i173
#CELL
  pure_quanta hole *
  page289_i174
#CELL
  pure_quanta hole *
  page289_i175
#ISCELL
  logical_power universal_gnd *
  page289_i176
#ISCELL
  logical_power universal_gnd *
  page289_i177
#CELL
  pure_quanta hole *
  page289_i18
#CELL
  pure_quanta hole *
  page289_i19
#CELL
  pure_quanta hole *
  page289_i190
#ISCELL
  logical_power universal_gnd *
  page289_i191
#CELL
  pure_quanta hole *
  page289_i192
#ISCELL
  logical_power universal_gnd *
  page289_i193
#CELL
  pure_quanta hole *
  page289_i20
#CELL
  pure_quanta gnd_hole *
  page289_i202
#ISCELL
  logical_power universal_gnd *
  page289_i203
#CELL
  pure_quanta gnd_hole *
  page289_i204
#ISCELL
  logical_power universal_gnd *
  page289_i205
#ISCELL
  logical_power universal_gnd *
  page289_i206
#CELL
  pure_quanta gnd_hole *
  page289_i207
#CELL
  pure_quanta hole *
  page289_i21
#CELL
  pure_quanta hole *
  page289_i216
#CELL
  pure_quanta hole *
  page289_i217
#CELL
  pure_quanta hole *
  page289_i218
#CELL
  pure_quanta hole *
  page289_i219
#ISCELL
  logical_power universal_gnd *
  page289_i220
#ISCELL
  logical_power universal_gnd *
  page289_i221
#ISCELL
  logical_power universal_gnd *
  page289_i222
#ISCELL
  logical_power universal_gnd *
  page289_i223
#CELL
  pure_quanta hole *
  page289_i224
#CELL
  pure_quanta hole *
  page289_i225
#CELL
  pure_quanta hole *
  page289_i226
#CELL
  pure_quanta hole *
  page289_i227
#CELL
  pure_quanta hole *
  page289_i228
#CELL
  pure_quanta hole *
  page289_i229
#CELL
  pure_quanta hole *
  page289_i232
#ISCELL
  logical_power universal_gnd *
  page289_i233
#CELL
  pure_quanta conn1_10165288101lf *
  page289_i238
#CELL
  pure_quanta conn1_10165288101lf *
  page289_i239
#ISCELL
  logical_power universal_gnd *
  page289_i243
#ISCELL
  logical_power universal_gnd *
  page289_i244
#ISCELL
  logical_power universal_gnd *
  page289_i245
#CELL
  pure_quanta gnd_hole *
  page289_i247
#CELL
  pure_quanta gnd_hole *
  page289_i248
#CELL
  pure_quanta hole *
  page289_i249
#CELL
  pure_quanta hole *
  page289_i254
#CELL
  pure_quanta hole *
  page289_i54
#ISCELL
  logical_power universal_gnd *
  page289_i55
#CELL
  pure_quanta hole *
  page289_i56
#CELL
  pure_quanta hole *
  page289_i57
#CELL
  pure_quanta hole *
  page289_i58
#ISCELL
  logical_power universal_gnd *
  page289_i59
#CELL
  pure_quanta hole *
  page289_i60
#CELL
  pure_quanta hole *
  page289_i61
#CELL
  pure_quanta hole *
  page289_i63
#CELL
  pure_quanta hole *
  page289_i64
#CELL
  pure_quanta hole *
  page289_i7
#CELL
  pure_quanta hole *
  page289_i72
#CELL
  pure_quanta hole *
  page289_i73
#CELL
  pure_quanta hole *
  page289_i74
#CELL
  pure_quanta hole *
  page289_i75
#CELL
  pure_quanta hole *
  page289_i8
#CELL
  pure_quanta hole *
  page289_i83
#CELL
  pure_quanta hole *
  page289_i87
#CELL
  pure_quanta hole *
  page289_i9
#ISCELL
  pure_quanta quanta_title_block_c *
  *
#CELL
  pure_quanta me_dummy_symbol *
  page290_i10
#CELL
  pure_quanta me_dummy_symbol *
  page290_i11
#CELL
  pure_quanta me_dummy_symbol *
  page290_i12
#CELL
  pure_quanta me_dummy_symbol *
  page290_i13
#CELL
  pure_quanta me_dummy_symbol *
  page290_i14
#CELL
  pure_quanta me_dummy_symbol *
  page290_i15
#CELL
  pure_quanta me_dummy_symbol *
  page290_i16
#CELL
  pure_quanta dummy_symbol *
  page290_i17
#CELL
  pure_quanta me_dummy_symbol *
  page290_i18
#CELL
  pure_quanta me_dummy_symbol *
  page290_i19
#CELL
  pure_quanta dummy_symbol *
  page290_i23
#CELL
  pure_quanta tp *
  page290_i40
#CELL
  pure_quanta tp *
  page290_i41
#CELL
  pure_quanta tp *
  page290_i42
#CELL
  pure_quanta tp *
  page290_i43
#CELL
  pure_quanta tp *
  page290_i45
#CELL
  pure_quanta tp *
  page290_i47
#CELL
  pure_quanta me_dummy_symbol *
  page290_i62
#CELL
  pure_quanta me_dummy_symbol *
  page290_i63
#CELL
  pure_quanta me_dummy_symbol *
  page290_i64
#CELL
  pure_quanta me_dummy_symbol *
  page290_i65
#CELL
  pure_quanta tp *
  page290_i69
#CELL
  pure_quanta tp *
  page290_i70
#CELL
  pure_quanta tp *
  page290_i71
#CELL
  pure_quanta tp *
  page290_i72
#CELL
  pure_quanta me_dummy_symbol *
  page290_i73
#CELL
  pure_quanta me_dummy_symbol *
  page290_i74
#CELL
  pure_quanta me_dummy_symbol *
  page290_i75
#CELL
  pure_quanta me_dummy_symbol *
  page290_i76
#CELL
  pure_quanta me_dummy_symbol *
  page290_i9
